G04 ================== begin FILE IDENTIFICATION RECORD ==================*
G04 Layout Name:  F:/<user>/2022/FB/R4006-TIMING/brd/gerber-3/R4006-B0001-02_R01.brd*
G04 Film Name:    R4006-B0001-02_R01_TSS*
G04 File Format:  Gerber RS274X*
G04 File Origin:  Cadence Allegro 17.2-S079*
G04 Origin Date:  Fri Feb 25 18:14:43 2022*
G04 *
G04 Layer:  PACKAGE GEOMETRY/SILKSCREEN_TOP*
G04 Layer:  BOARD GEOMETRY/SILKSCREEN_TOP*
G04 Layer:  REF DES/SILKSCREEN_TOP*
G04 Layer:  MANUFACTURING/CELESTICA_LEGEND*
G04 *
G04 Offset:    (0.00 0.00)*
G04 Mirror:    No*
G04 Mode:      Positive*
G04 Rotation:  0*
G04 FullContactRelief:  No*
G04 UndefLineWidth:     6.00*
G04 ================== end FILE IDENTIFICATION RECORD ====================*
%FSLAX55Y55*MOIN*%
%IR0*IPPOS*OFA0.00000B0.00000*MIA0B0*SFA1.00000B1.00000*%
%ADD10C,.01*%
%ADD11C,.005*%
%ADD12C,.006*%
G75*
%LPD*%
G75*
G36*
G01X-698Y93960D02*
X204Y95160D01*
Y94260D01*
X1104D01*
Y93660D01*
X204D01*
Y92760D01*
X-698Y93960D01*
G37*
G36*
G01X-781Y100466D02*
X121Y101666D01*
Y100766D01*
X1021D01*
Y100166D01*
X121D01*
Y99266D01*
X-781Y100466D01*
G37*
G36*
G01Y157553D02*
X121Y158753D01*
Y157853D01*
X1021D01*
Y157253D01*
X121D01*
Y156353D01*
X-781Y157553D01*
G37*
G36*
G01X-698Y151047D02*
X204Y152247D01*
Y151347D01*
X1104D01*
Y150747D01*
X204D01*
Y149847D01*
X-698Y151047D01*
G37*
G36*
G01X-781Y214640D02*
X121Y215840D01*
Y214940D01*
X1021D01*
Y214340D01*
X121D01*
Y213440D01*
X-781Y214640D01*
G37*
G36*
G01X-698Y208134D02*
X204Y209334D01*
Y208434D01*
X1104D01*
Y207834D01*
X204D01*
Y206934D01*
X-698Y208134D01*
G37*
G36*
G01Y265220D02*
X204Y266420D01*
Y265520D01*
X1104D01*
Y264920D01*
X204D01*
Y264020D01*
X-698Y265220D01*
G37*
G36*
G01X-781Y271726D02*
X121Y272926D01*
Y272026D01*
X1021D01*
Y271426D01*
X121D01*
Y270526D01*
X-781Y271726D01*
G37*
G36*
G01Y328813D02*
X121Y330013D01*
Y329113D01*
X1021D01*
Y328513D01*
X121D01*
Y327613D01*
X-781Y328813D01*
G37*
G36*
G01X-698Y322307D02*
X204Y323507D01*
Y322607D01*
X1104D01*
Y322007D01*
X204D01*
Y321107D01*
X-698Y322307D01*
G37*
G36*
G01X21500Y89700D02*
G02I-1500J0D01*
G37*
G36*
G01Y203700D02*
G02I-1500J0D01*
G37*
G36*
G01X61000Y83000D02*
G02I-1500J0D01*
G37*
G36*
G01X60493Y141001D02*
G02I-1500J0D01*
G37*
G36*
G01Y198088D02*
G02I-1500J0D01*
G37*
G36*
G01Y255175D02*
G02I-1500J0D01*
G37*
G36*
G01X75500Y220500D02*
G03I-1500J0D01*
G37*
G36*
G01X69300Y333600D02*
G02I-1500J0D01*
G37*
G36*
G01X95130Y76700D02*
G02I-1500J0D01*
G37*
G36*
G01X88500Y99000D02*
G02I-1500J0D01*
G37*
G36*
G01X87500Y275000D02*
G02I-1999J0D01*
G37*
G36*
G01X130322Y365002D02*
G03I-2000J0D01*
G37*
G36*
G01X132584Y398000D02*
G03I-1500J0D01*
G37*
G36*
G01X157947Y305528D02*
G02I-1500J0D01*
G37*
G36*
G01X162690Y384458D02*
G03I-2000J0D01*
G37*
G36*
G01X172331Y313343D02*
Y320657D01*
X170331D01*
Y313343D01*
X172331D01*
G37*
G36*
G01Y323343D02*
Y330657D01*
X170331D01*
Y323343D01*
X172331D01*
G37*
G36*
G01X196531Y59041D02*
G02I-1500J0D01*
G37*
G36*
G01X218903Y332187D02*
G03I-1500J0D01*
G37*
G36*
G01X271452Y63470D02*
G03I-1500J0D01*
G37*
G36*
G01X336450Y322750D02*
G02I-1500J0D01*
G37*
G36*
G01X341210Y413342D02*
G03I-2000J0D01*
G37*
G36*
G01X353674Y182225D02*
G02I-1500J0D01*
G37*
G36*
G01X352000Y243500D02*
G02I-2000J0D01*
G37*
G36*
G01X378500Y266000D02*
G02I-1500J0D01*
G37*
G36*
G01X383500Y124000D02*
G03I-2500J0D01*
G37*
G36*
G01X388672Y282947D02*
G02I-1500J0D01*
G37*
G36*
G01X386000Y317500D02*
G02I-1500J0D01*
G37*
G36*
G01X403400Y352800D02*
G03I-1500J0D01*
G37*
G36*
G01X398250Y376250D02*
G02I-1500J0D01*
G37*
G36*
G01X414500Y328500D02*
G02I-1500J0D01*
G37*
G36*
G01X426000Y352000D02*
G03I-1500J0D01*
G37*
G36*
G01X440536Y347129D02*
G03I-1500J0D01*
G37*
G36*
G01X432743Y393294D02*
G02I-2000J0D01*
G37*
G36*
G01X450500Y280001D02*
G02I-1999J0D01*
G37*
G36*
G01X485000Y95500D02*
G02I-1500J0D01*
G37*
G36*
G01X523853Y266672D02*
G02I-1500J0D01*
G37*
G36*
G01X552447Y71928D02*
G02I-1500J0D01*
G37*
G36*
G01X547358Y219410D02*
G03I-2000J0D01*
G37*
G36*
G01X567501Y364000D02*
G02I-2001J0D01*
G37*
G36*
G01X605000Y113000D02*
G03I-1500J0D01*
G37*
G36*
G01X591000Y199500D02*
G02I-2000J0D01*
G37*
G36*
G01X587976Y405325D02*
X593520D01*
Y403325D01*
X587976D01*
Y405325D01*
G37*
G36*
G01X599787D02*
X605331D01*
Y403325D01*
X599787D01*
Y405325D01*
G37*
G36*
G01X611598D02*
X617142D01*
Y403325D01*
X611598D01*
Y405325D01*
G37*
G36*
G01X636100Y233974D02*
G02I-1500J0D01*
G37*
G36*
G01X525528Y410499D02*
Y412499D01*
X531072D01*
Y410499D01*
X525528D01*
G37*
G36*
G01X540732Y403325D02*
Y405325D01*
X546276D01*
Y403325D01*
X540732D01*
G37*
G36*
G01Y417104D02*
Y419104D01*
X546276D01*
Y417104D01*
X540732D01*
G37*
G36*
G01X564354Y403325D02*
Y405325D01*
X569898D01*
Y403325D01*
X564354D01*
G37*
G36*
G01X558087Y405325D02*
Y403325D01*
X552543D01*
Y405325D01*
X558087D01*
G37*
G36*
G01X552543Y417104D02*
Y419104D01*
X558087D01*
Y417104D01*
X552543D01*
G37*
G36*
G01X564354D02*
Y419104D01*
X569898D01*
Y417104D01*
X564354D01*
G37*
G36*
G01X576165Y403325D02*
Y405325D01*
X581709D01*
Y403325D01*
X576165D01*
G37*
G36*
G01Y417104D02*
Y419104D01*
X581709D01*
Y417104D01*
X576165D01*
G37*
G36*
G01X599787D02*
Y419104D01*
X605331D01*
Y417104D01*
X599787D01*
G37*
G36*
G01X611598D02*
Y419104D01*
X617142D01*
Y417104D01*
X611598D01*
G37*
G54D10*
G01X136000Y-65500D02*
Y-158000D01*
X506000D01*
Y-65500D01*
X136000D01*
G01X316000D02*
Y-158000D01*
G54D11*
G01X329433Y-125500D02*
Y-133000D01*
X333167D01*
G01X340480D02*
Y-128000D01*
G01Y-128875D02*
X340107Y-128375D01*
X339547Y-128125D01*
X338893Y-128000D01*
X338240Y-128250D01*
X337680Y-128750D01*
X337307Y-129500D01*
X337120Y-130500D01*
X337307Y-131500D01*
X337680Y-132250D01*
X338240Y-132750D01*
X338893Y-133000D01*
X339547Y-132875D01*
X340107Y-132500D01*
X340480Y-132000D01*
G01X344340Y-135250D02*
X344900Y-135500D01*
X345647Y-135250D01*
X346113Y-134750D01*
X346487Y-134125D01*
X347047Y-132125D01*
X348260Y-128000D01*
G01X345273D02*
X347047Y-132125D01*
G01X352400Y-129625D02*
X355387D01*
X355107Y-128750D01*
X354640Y-128250D01*
X353987Y-128000D01*
X353333Y-128125D01*
X352773Y-128500D01*
X352400Y-129375D01*
X352213Y-130125D01*
Y-130875D01*
X352400Y-131625D01*
X352867Y-132375D01*
X353427Y-132875D01*
X354080Y-133000D01*
X354733Y-132750D01*
X355387Y-132000D01*
G01X359993Y-133000D02*
Y-128000D01*
G01Y-129000D02*
X360460Y-128500D01*
X360927Y-128125D01*
X361580Y-128000D01*
X362047Y-128125D01*
X362607Y-128500D01*
G01X368800Y-133250D02*
X368613Y-133125D01*
Y-132875D01*
X368800Y-132750D01*
X368987Y-132875D01*
Y-133125D01*
X368800Y-133250D01*
G01Y-129875D02*
X368613Y-129750D01*
Y-129500D01*
X368800Y-129375D01*
X368987Y-129500D01*
Y-129750D01*
X368800Y-129875D01*
G01X336747Y-120500D02*
Y-113000D01*
X338613D01*
X339360Y-113375D01*
X339920Y-113875D01*
X340387Y-114625D01*
X340760Y-115500D01*
X340853Y-116750D01*
X340760Y-118000D01*
X340387Y-118875D01*
X339920Y-119625D01*
X339360Y-120125D01*
X338613Y-120500D01*
X336747D01*
G01X347980D02*
Y-115500D01*
G01Y-116375D02*
X347607Y-115875D01*
X347047Y-115625D01*
X346393Y-115500D01*
X345740Y-115750D01*
X345180Y-116250D01*
X344807Y-117000D01*
X344620Y-118000D01*
X344807Y-119000D01*
X345180Y-119750D01*
X345740Y-120250D01*
X346393Y-120500D01*
X347047Y-120375D01*
X347607Y-120000D01*
X347980Y-119500D01*
G01X353800Y-113000D02*
Y-120500D01*
G01X352493Y-115500D02*
X355107D01*
G01X359900Y-117125D02*
X362887D01*
X362607Y-116250D01*
X362140Y-115750D01*
X361487Y-115500D01*
X360833Y-115625D01*
X360273Y-116000D01*
X359900Y-116875D01*
X359713Y-117625D01*
Y-118375D01*
X359900Y-119125D01*
X360367Y-119875D01*
X360927Y-120375D01*
X361580Y-120500D01*
X362233Y-120250D01*
X362887Y-119500D01*
G01X368800Y-120750D02*
X368613Y-120625D01*
Y-120375D01*
X368800Y-120250D01*
X368987Y-120375D01*
Y-120625D01*
X368800Y-120750D01*
G01Y-117375D02*
X368613Y-117250D01*
Y-117000D01*
X368800Y-116875D01*
X368987Y-117000D01*
Y-117250D01*
X368800Y-117375D01*
G01X382027Y-114250D02*
X382587Y-113500D01*
X383240Y-113125D01*
X383987Y-113000D01*
X384920Y-113250D01*
X385573Y-113875D01*
X385760Y-114625D01*
X385667Y-115375D01*
X385293Y-116000D01*
X383427Y-117250D01*
X382587Y-118125D01*
X382027Y-119375D01*
X381840Y-120500D01*
X385760D01*
G01X391300Y-113000D02*
X390553Y-113250D01*
X389993Y-113875D01*
X389620Y-114625D01*
X389340Y-115625D01*
X389247Y-116750D01*
X389340Y-117875D01*
X389620Y-118875D01*
X389993Y-119625D01*
X390553Y-120250D01*
X391300Y-120500D01*
X392047Y-120250D01*
X392607Y-119625D01*
X392980Y-118875D01*
X393260Y-117875D01*
X393353Y-116750D01*
X393260Y-115625D01*
X392980Y-114625D01*
X392607Y-113875D01*
X392047Y-113250D01*
X391300Y-113000D01*
G01X397027Y-114250D02*
X397587Y-113500D01*
X398240Y-113125D01*
X398987Y-113000D01*
X399920Y-113250D01*
X400573Y-113875D01*
X400760Y-114625D01*
X400667Y-115375D01*
X400293Y-116000D01*
X398427Y-117250D01*
X397587Y-118125D01*
X397027Y-119375D01*
X396840Y-120500D01*
X400760D01*
G01X404527Y-114250D02*
X405087Y-113500D01*
X405740Y-113125D01*
X406487Y-113000D01*
X407420Y-113250D01*
X408073Y-113875D01*
X408260Y-114625D01*
X408167Y-115375D01*
X407793Y-116000D01*
X405927Y-117250D01*
X405087Y-118125D01*
X404527Y-119375D01*
X404340Y-120500D01*
X408260D01*
G01X412587Y-118000D02*
X415013D01*
G01X421300Y-113000D02*
X420553Y-113250D01*
X419993Y-113875D01*
X419620Y-114625D01*
X419340Y-115625D01*
X419247Y-116750D01*
X419340Y-117875D01*
X419620Y-118875D01*
X419993Y-119625D01*
X420553Y-120250D01*
X421300Y-120500D01*
X422047Y-120250D01*
X422607Y-119625D01*
X422980Y-118875D01*
X423260Y-117875D01*
X423353Y-116750D01*
X423260Y-115625D01*
X422980Y-114625D01*
X422607Y-113875D01*
X422047Y-113250D01*
X421300Y-113000D01*
G01X427027Y-114250D02*
X427587Y-113500D01*
X428240Y-113125D01*
X428987Y-113000D01*
X429920Y-113250D01*
X430573Y-113875D01*
X430760Y-114625D01*
X430667Y-115375D01*
X430293Y-116000D01*
X428427Y-117250D01*
X427587Y-118125D01*
X427027Y-119375D01*
X426840Y-120500D01*
X430760D01*
G01X435087Y-118000D02*
X437513D01*
G01X442027Y-114250D02*
X442587Y-113500D01*
X443240Y-113125D01*
X443987Y-113000D01*
X444920Y-113250D01*
X445573Y-113875D01*
X445760Y-114625D01*
X445667Y-115375D01*
X445293Y-116000D01*
X443427Y-117250D01*
X442587Y-118125D01*
X442027Y-119375D01*
X441840Y-120500D01*
X445760D01*
G01X449247Y-119375D02*
X449807Y-120000D01*
X450460Y-120375D01*
X451300Y-120500D01*
X452140Y-120250D01*
X452793Y-119750D01*
X453260Y-118875D01*
X453353Y-117875D01*
X453167Y-116875D01*
X452700Y-116250D01*
X452047Y-115750D01*
X451393Y-115625D01*
X450740Y-115750D01*
X449900Y-116250D01*
X450180Y-113000D01*
X452700D01*
G01X336933Y-108000D02*
Y-100500D01*
X339267D01*
X340013Y-100875D01*
X340480Y-101375D01*
X340667Y-102375D01*
X340480Y-103375D01*
X339920Y-104000D01*
X339267Y-104375D01*
X336933D01*
G01X339267D02*
X340667Y-108000D01*
G01X344900Y-104625D02*
X347887D01*
X347607Y-103750D01*
X347140Y-103250D01*
X346487Y-103000D01*
X345833Y-103125D01*
X345273Y-103500D01*
X344900Y-104375D01*
X344713Y-105125D01*
Y-105875D01*
X344900Y-106625D01*
X345367Y-107375D01*
X345927Y-107875D01*
X346580Y-108000D01*
X347233Y-107750D01*
X347887Y-107000D01*
G01X352120Y-103000D02*
X353800Y-108000D01*
X355480Y-103000D01*
G01X368800Y-108250D02*
X368613Y-108125D01*
Y-107875D01*
X368800Y-107750D01*
X368987Y-107875D01*
Y-108125D01*
X368800Y-108250D01*
G01Y-104875D02*
X368613Y-104750D01*
Y-104500D01*
X368800Y-104375D01*
X368987Y-104500D01*
Y-104750D01*
X368800Y-104875D01*
G01X383800Y-100500D02*
X383053Y-100750D01*
X382493Y-101375D01*
X382120Y-102125D01*
X381840Y-103125D01*
X381747Y-104250D01*
X381840Y-105375D01*
X382120Y-106375D01*
X382493Y-107125D01*
X383053Y-107750D01*
X383800Y-108000D01*
X384547Y-107750D01*
X385107Y-107125D01*
X385480Y-106375D01*
X385760Y-105375D01*
X385853Y-104250D01*
X385760Y-103125D01*
X385480Y-102125D01*
X385107Y-101375D01*
X384547Y-100750D01*
X383800Y-100500D01*
G01X391300Y-108000D02*
Y-100500D01*
X390180Y-102000D01*
G01Y-108000D02*
X392420D01*
G01X336933Y-95500D02*
Y-88000D01*
X339173D01*
X339920Y-88375D01*
X340480Y-89250D01*
X340667Y-90250D01*
X340480Y-91250D01*
X340013Y-92000D01*
X339173Y-92375D01*
X336933D01*
G01X344620Y-95750D02*
X347980Y-88000D01*
G01X351653Y-95500D02*
Y-88000D01*
X355947Y-95500D01*
Y-88000D01*
G01X368800Y-95750D02*
X368613Y-95625D01*
Y-95375D01*
X368800Y-95250D01*
X368987Y-95375D01*
Y-95625D01*
X368800Y-95750D01*
G01Y-92375D02*
X368613Y-92250D01*
Y-92000D01*
X368800Y-91875D01*
X368987Y-92000D01*
Y-92250D01*
X368800Y-92375D01*
G01X381933Y-95500D02*
Y-88000D01*
X384267D01*
X385013Y-88375D01*
X385480Y-88875D01*
X385667Y-89875D01*
X385480Y-90875D01*
X384920Y-91500D01*
X384267Y-91875D01*
X381933D01*
G01X384267D02*
X385667Y-95500D01*
G01X392420D02*
Y-88000D01*
X388967Y-93375D01*
X393633D01*
G01X398800Y-88000D02*
X398053Y-88250D01*
X397493Y-88875D01*
X397120Y-89625D01*
X396840Y-90625D01*
X396747Y-91750D01*
X396840Y-92875D01*
X397120Y-93875D01*
X397493Y-94625D01*
X398053Y-95250D01*
X398800Y-95500D01*
X399547Y-95250D01*
X400107Y-94625D01*
X400480Y-93875D01*
X400760Y-92875D01*
X400853Y-91750D01*
X400760Y-90625D01*
X400480Y-89625D01*
X400107Y-88875D01*
X399547Y-88250D01*
X398800Y-88000D01*
G01X406300D02*
X405553Y-88250D01*
X404993Y-88875D01*
X404620Y-89625D01*
X404340Y-90625D01*
X404247Y-91750D01*
X404340Y-92875D01*
X404620Y-93875D01*
X404993Y-94625D01*
X405553Y-95250D01*
X406300Y-95500D01*
X407047Y-95250D01*
X407607Y-94625D01*
X407980Y-93875D01*
X408260Y-92875D01*
X408353Y-91750D01*
X408260Y-90625D01*
X407980Y-89625D01*
X407607Y-88875D01*
X407047Y-88250D01*
X406300Y-88000D01*
G01X412027Y-92375D02*
X412680Y-91500D01*
X413240Y-91000D01*
X413987Y-90750D01*
X414640Y-91000D01*
X415107Y-91500D01*
X415480Y-92250D01*
X415573Y-93125D01*
X415480Y-93875D01*
X415107Y-94625D01*
X414547Y-95250D01*
X413893Y-95500D01*
X413147Y-95250D01*
X412493Y-94500D01*
X412120Y-93375D01*
X412027Y-92125D01*
X412213Y-90500D01*
X412493Y-89625D01*
X412960Y-88750D01*
X413613Y-88125D01*
X414267Y-88000D01*
X414920Y-88250D01*
X415387Y-88875D01*
G01X420087Y-93000D02*
X422513D01*
G01X429547Y-91500D02*
X429920Y-91125D01*
X430200Y-90500D01*
X430387Y-89625D01*
X430200Y-88875D01*
X429827Y-88375D01*
X429173Y-88000D01*
X426653D01*
Y-95500D01*
X429733D01*
X430387Y-95000D01*
X430760Y-94250D01*
X430947Y-93375D01*
X430760Y-92500D01*
X430200Y-91750D01*
X429547Y-91500D01*
X426653D01*
G01X436300Y-88000D02*
X435553Y-88250D01*
X434993Y-88875D01*
X434620Y-89625D01*
X434340Y-90625D01*
X434247Y-91750D01*
X434340Y-92875D01*
X434620Y-93875D01*
X434993Y-94625D01*
X435553Y-95250D01*
X436300Y-95500D01*
X437047Y-95250D01*
X437607Y-94625D01*
X437980Y-93875D01*
X438260Y-92875D01*
X438353Y-91750D01*
X438260Y-90625D01*
X437980Y-89625D01*
X437607Y-88875D01*
X437047Y-88250D01*
X436300Y-88000D01*
G01X443800D02*
X443053Y-88250D01*
X442493Y-88875D01*
X442120Y-89625D01*
X441840Y-90625D01*
X441747Y-91750D01*
X441840Y-92875D01*
X442120Y-93875D01*
X442493Y-94625D01*
X443053Y-95250D01*
X443800Y-95500D01*
X444547Y-95250D01*
X445107Y-94625D01*
X445480Y-93875D01*
X445760Y-92875D01*
X445853Y-91750D01*
X445760Y-90625D01*
X445480Y-89625D01*
X445107Y-88875D01*
X444547Y-88250D01*
X443800Y-88000D01*
G01X451300D02*
X450553Y-88250D01*
X449993Y-88875D01*
X449620Y-89625D01*
X449340Y-90625D01*
X449247Y-91750D01*
X449340Y-92875D01*
X449620Y-93875D01*
X449993Y-94625D01*
X450553Y-95250D01*
X451300Y-95500D01*
X452047Y-95250D01*
X452607Y-94625D01*
X452980Y-93875D01*
X453260Y-92875D01*
X453353Y-91750D01*
X453260Y-90625D01*
X452980Y-89625D01*
X452607Y-88875D01*
X452047Y-88250D01*
X451300Y-88000D01*
G01X458800Y-95500D02*
Y-88000D01*
X457680Y-89500D01*
G01Y-95500D02*
X459920D01*
G01X465087Y-93000D02*
X467513D01*
G01X473800Y-88000D02*
X473053Y-88250D01*
X472493Y-88875D01*
X472120Y-89625D01*
X471840Y-90625D01*
X471747Y-91750D01*
X471840Y-92875D01*
X472120Y-93875D01*
X472493Y-94625D01*
X473053Y-95250D01*
X473800Y-95500D01*
X474547Y-95250D01*
X475107Y-94625D01*
X475480Y-93875D01*
X475760Y-92875D01*
X475853Y-91750D01*
X475760Y-90625D01*
X475480Y-89625D01*
X475107Y-88875D01*
X474547Y-88250D01*
X473800Y-88000D01*
G01X479527Y-89250D02*
X480087Y-88500D01*
X480740Y-88125D01*
X481487Y-88000D01*
X482420Y-88250D01*
X483073Y-88875D01*
X483260Y-89625D01*
X483167Y-90375D01*
X482793Y-91000D01*
X480927Y-92250D01*
X480087Y-93125D01*
X479527Y-94375D01*
X479340Y-95500D01*
X483260D01*
G01X381840Y-132000D02*
X382587Y-132625D01*
X383427Y-133000D01*
X384173D01*
X384920Y-132625D01*
X385480Y-132000D01*
X385760Y-131125D01*
X385573Y-130250D01*
X385107Y-129500D01*
X384267Y-129000D01*
X383147Y-128750D01*
X382493Y-128250D01*
X382213Y-127375D01*
X382400Y-126500D01*
X382867Y-125875D01*
X383520Y-125500D01*
X384173D01*
X384827Y-125750D01*
X385387Y-126375D01*
G01X390180Y-125500D02*
X392420D01*
G01X391300D02*
Y-133000D01*
G01X390180D02*
X392420D01*
G01X396933Y-125500D02*
Y-133000D01*
X400667D01*
G01X404247D02*
Y-125500D01*
G01X407793D02*
X404247Y-130125D01*
G01X408353Y-133000D02*
X405833Y-128000D01*
G01X411840Y-132000D02*
X412587Y-132625D01*
X413427Y-133000D01*
X414173D01*
X414920Y-132625D01*
X415480Y-132000D01*
X415760Y-131125D01*
X415573Y-130250D01*
X415107Y-129500D01*
X414267Y-129000D01*
X413147Y-128750D01*
X412493Y-128250D01*
X412213Y-127375D01*
X412400Y-126500D01*
X412867Y-125875D01*
X413520Y-125500D01*
X414173D01*
X414827Y-125750D01*
X415387Y-126375D01*
G01X423353Y-126125D02*
X422793Y-125750D01*
X422140Y-125500D01*
X421393D01*
X420553Y-125875D01*
X419900Y-126500D01*
X419433Y-127250D01*
X419060Y-128500D01*
X418967Y-129625D01*
X419153Y-130750D01*
X419433Y-131500D01*
X419993Y-132250D01*
X420647Y-132750D01*
X421300Y-133000D01*
X421953D01*
X422607Y-132750D01*
X423167Y-132375D01*
X423633Y-131875D01*
G01X426933Y-133000D02*
Y-125500D01*
X429267D01*
X430013Y-125875D01*
X430480Y-126375D01*
X430667Y-127375D01*
X430480Y-128375D01*
X429920Y-129000D01*
X429267Y-129375D01*
X426933D01*
G01X429267D02*
X430667Y-133000D01*
G01X438167D02*
X434433D01*
Y-125500D01*
X438167D01*
G01X436673Y-129125D02*
X434433D01*
G01X445667Y-133000D02*
X441933D01*
Y-125500D01*
X445667D01*
G01X444173Y-129125D02*
X441933D01*
G01X449153Y-133000D02*
Y-125500D01*
X453447Y-133000D01*
Y-125500D01*
G01X466300D02*
Y-133000D01*
G01X464153Y-125500D02*
X468447D01*
G01X473800Y-133000D02*
X473053Y-132875D01*
X472400Y-132375D01*
X471840Y-131625D01*
X471467Y-130750D01*
X471280Y-129750D01*
Y-128750D01*
X471467Y-127750D01*
X471840Y-126875D01*
X472400Y-126125D01*
X473053Y-125625D01*
X473800Y-125500D01*
X474547Y-125625D01*
X475200Y-126125D01*
X475760Y-126875D01*
X476133Y-127750D01*
X476320Y-128750D01*
Y-129750D01*
X476133Y-130750D01*
X475760Y-131625D01*
X475200Y-132375D01*
X474547Y-132875D01*
X473800Y-133000D01*
G01X479433D02*
Y-125500D01*
X481673D01*
X482420Y-125875D01*
X482980Y-126750D01*
X483167Y-127750D01*
X482980Y-128750D01*
X482513Y-129500D01*
X481673Y-129875D01*
X479433D01*
G54D12*
G01X31539Y55760D02*
X-38898D01*
G01D02*
Y86760D01*
G01D02*
X31539D01*
G01Y112846D02*
X-38898D01*
G01D02*
Y143846D01*
G01D02*
X31539D01*
G01X-38898Y169933D02*
Y200933D01*
G01X31539Y169933D02*
X-38898D01*
G01Y200933D02*
X31539D01*
G01X-38898Y227020D02*
Y258020D01*
G01X31539Y227020D02*
X-38898D01*
G01Y258020D02*
X31539D01*
G01X-8476Y328905D02*
Y354326D01*
G01X51594Y328905D02*
X-8476D01*
G01Y354326D02*
X51594D01*
G01X2642Y91421D02*
X4124D01*
G01D02*
Y88983D01*
G01D02*
X10252D01*
G01X2642Y102279D02*
Y91421D01*
G01X10252Y104717D02*
X4124D01*
G01D02*
Y102279D01*
G01D02*
X2642D01*
G01Y159366D02*
Y148508D01*
G01X4124Y159366D02*
X2642D01*
G01X4124Y161804D02*
Y159366D01*
G01X10252Y161804D02*
X4124D01*
G01Y146070D02*
X10252D01*
G01X4124Y148508D02*
Y146070D01*
G01X2642Y148508D02*
X4124D01*
G01X2642Y216453D02*
Y205595D01*
G01X4124Y203157D02*
X10252D01*
G01X4124Y205595D02*
Y203157D01*
G01X2642Y205595D02*
X4124D01*
G01Y216453D02*
X2642D01*
G01X4124Y218891D02*
Y216453D01*
G01X10252Y218891D02*
X4124D01*
G01X2642Y273539D02*
Y262681D01*
G01X4124Y260243D02*
X10252D01*
G01X4124Y262681D02*
Y260243D01*
G01X2642Y262681D02*
X4124D01*
G01Y273539D02*
X2642D01*
G01X4124Y275977D02*
Y273539D01*
G01X10252Y275977D02*
X4124D01*
G01X2642Y330626D02*
Y319768D01*
G01X4124Y317330D02*
X10252D01*
G01X4124Y319768D02*
Y317330D01*
G01X2642Y319768D02*
X4124D01*
G01Y330626D02*
X2642D01*
G01X4124Y333064D02*
Y330626D01*
G01X10252Y333064D02*
X4124D01*
G01X16800Y91800D02*
Y108200D01*
G01X30200Y91800D02*
X16800D01*
G01X10252Y88983D02*
Y104717D01*
G01X16800Y108200D02*
X30200D01*
G01X25900Y150298D02*
X30300D01*
G01X25900Y159298D02*
Y150298D01*
G01X30300Y159298D02*
X25900D01*
G01X21400Y150298D02*
X25800D01*
G01X21400Y159298D02*
Y150298D01*
G01X25800Y159298D02*
X21400D01*
G01X25800Y150298D02*
Y159298D01*
G01X16900Y150298D02*
X21300D01*
G01X16900Y159298D02*
Y150298D01*
G01X21300Y159298D02*
X16900D01*
G01X21300Y150298D02*
Y159298D01*
G01X10252Y146070D02*
Y161804D01*
G01X16800Y205800D02*
Y222200D01*
G01X30200Y205800D02*
X16800D01*
G01X10252Y203157D02*
Y218891D01*
G01X16800Y222200D02*
X30200D01*
G01X22000Y264008D02*
X26400D01*
G01X22000Y273008D02*
Y264008D01*
G01X26400D02*
Y273008D01*
G01X17500Y264008D02*
X21900D01*
G01X17500Y273008D02*
Y264008D01*
G01X21900D02*
Y273008D01*
G01X26500Y264008D02*
X30900D01*
G01X26500Y273008D02*
Y264008D01*
G01X10252Y260243D02*
Y275977D01*
G01X26400Y273008D02*
X22000D01*
G01X21900D02*
X17500D01*
G01X30900D02*
X26500D01*
G01X15800Y316500D02*
X20200D01*
G01X15800Y325500D02*
Y316500D01*
G01X20200D02*
Y325500D01*
G01X20800Y316500D02*
X25200D01*
G01X20800Y325500D02*
Y316500D01*
G01X25200D02*
Y325500D01*
G01X25800Y316500D02*
X30200D01*
G01X25800Y325500D02*
Y316500D01*
G01X10252Y317330D02*
Y333064D01*
G01X20200Y325500D02*
X15800D01*
G01X25200D02*
X20800D01*
G01X30200D02*
X25800D01*
G01X31539Y86760D02*
Y55760D01*
G01X46500Y71300D02*
X42100D01*
G01Y62300D02*
X46500D01*
G01X42100Y71300D02*
Y62300D01*
G01X30200Y108200D02*
Y91800D01*
G01X43300Y105990D02*
X47700D01*
G01X43300Y114990D02*
Y105990D01*
G01X47700Y114990D02*
X43300D01*
G01X47700Y124400D02*
X43300D01*
G01Y115400D02*
X47700D01*
G01X43300Y124400D02*
Y115400D01*
G01X31539Y143846D02*
Y112846D01*
G01X30400Y150298D02*
X34800D01*
G01X30400Y159298D02*
Y150298D01*
G01X34800Y159298D02*
X30400D01*
G01X34800Y150298D02*
Y159298D01*
G01X34900Y150298D02*
X39300D01*
G01X34900Y159298D02*
Y150298D01*
G01X39300Y159298D02*
X34900D01*
G01X39300Y150298D02*
Y159298D01*
G01X39400Y150298D02*
X43800D01*
G01X39400Y159298D02*
Y150298D01*
G01X43800Y159298D02*
X39400D01*
G01X43800Y150298D02*
Y159298D01*
G01X30300Y150298D02*
Y159298D01*
G01X43300Y162000D02*
X47700D01*
G01X43300Y171000D02*
Y162000D01*
G01Y171500D02*
X47700D01*
G01X43300Y180500D02*
Y171500D01*
G01X47700Y180500D02*
X43300D01*
G01X47700Y171000D02*
X43300D01*
G01X31539Y200933D02*
Y169933D01*
G01X30200Y222200D02*
Y205800D01*
G01X48652Y229900D02*
X44252D01*
G01Y220900D02*
X48652D01*
G01X44252Y229900D02*
Y220900D01*
G01X43000Y230200D02*
X47400D01*
G01X43000Y239200D02*
Y230200D01*
G01X31539Y258020D02*
Y227020D01*
G01X47400Y239200D02*
X43000D01*
G01X35500Y264008D02*
X39900D01*
G01X35500Y273008D02*
Y264008D01*
G01X39900D02*
Y273008D01*
G01X40000Y264008D02*
X44400D01*
G01X40000Y273008D02*
Y264008D01*
G01X44400D02*
Y273008D01*
G01X31000Y264008D02*
X35400D01*
G01X31000Y273008D02*
Y264008D01*
G01X35400D02*
Y273008D01*
G01X30900Y264008D02*
Y273008D01*
G01X39900D02*
X35500D01*
G01X44400D02*
X40000D01*
G01X35400D02*
X31000D01*
G01X40800Y316500D02*
X45200D01*
G01X40800Y325500D02*
Y316500D01*
G01X35800D02*
X40200D01*
G01X35800Y325500D02*
Y316500D01*
G01X40200D02*
Y325500D01*
G01X30200Y316500D02*
Y325500D01*
G01X30800Y316500D02*
X35200D01*
G01X30800Y325500D02*
Y316500D01*
G01X35200D02*
Y325500D01*
G01X45200D02*
X40800D01*
G01X40200D02*
X35800D01*
G01X35200D02*
X30800D01*
G01X46500Y62300D02*
Y71300D01*
G01X49590Y61706D02*
Y80814D01*
G01X59858Y61706D02*
X49590D01*
G01X59858Y80814D02*
Y61706D01*
G01X60200Y86000D02*
Y95000D01*
G01X55800Y86000D02*
X60200D01*
G01X55800Y95000D02*
Y86000D01*
G01X46300D02*
X50700D01*
G01X46300Y95000D02*
Y86000D01*
G01X50700D02*
Y95000D01*
G01X55700Y86000D02*
Y95000D01*
G01X51300Y86000D02*
X55700D01*
G01X51300Y95000D02*
Y86000D01*
G01X49590Y80814D02*
X59858D01*
G01X60300Y106000D02*
X64700D01*
G01X60300Y115000D02*
Y106000D01*
G01X54043Y98250D02*
X48757D01*
G01Y101750D02*
X54043D01*
G01X48757Y98250D02*
Y101750D01*
G01X54043D02*
Y98250D01*
G01X60200Y95000D02*
X55800D01*
G01X48300Y105990D02*
X52700D01*
G01X48300Y114990D02*
Y105990D01*
G01X52700D02*
Y114990D01*
G01X50700Y95000D02*
X46300D01*
G01X55700D02*
X51300D01*
G01X47700Y105990D02*
Y114990D01*
G01X64700Y115000D02*
X60300D01*
G01X52700Y114990D02*
X48300D01*
G01X47700Y115400D02*
Y124400D01*
G01X49590Y118792D02*
Y137900D01*
G01X59858Y118792D02*
X49590D01*
G01X59858Y137900D02*
Y118792D01*
G01X60200Y142000D02*
Y151000D01*
G01X55800Y142000D02*
X60200D01*
G01X55800Y151000D02*
Y142000D01*
G01X45800D02*
X50200D01*
G01X45800Y151000D02*
Y142000D01*
G01X50200D02*
Y151000D01*
G01X55200Y142000D02*
Y151000D01*
G01X50800Y142000D02*
X55200D01*
G01X50800Y151000D02*
Y142000D01*
G01X49590Y137900D02*
X59858D01*
G01X58400Y162345D02*
X62800D01*
G01X58400Y171345D02*
Y162345D01*
G01X47357Y158750D02*
X52643D01*
G01X47357Y155250D02*
Y158750D01*
G01X52643Y155250D02*
X47357D01*
G01X52643Y158750D02*
Y155250D01*
G01X60200Y151000D02*
X55800D01*
G01X49000Y167200D02*
Y162800D01*
G01D02*
X58000D01*
G01D02*
Y167200D01*
G01X50200Y151000D02*
X45800D01*
G01X55200D02*
X50800D01*
G01X47700Y162000D02*
Y171000D01*
G01X62800Y171345D02*
X58400D01*
G01X58000Y167200D02*
X49000D01*
G01X47700Y171500D02*
Y180500D01*
G01X49590Y175879D02*
Y194987D01*
G01X59858Y175879D02*
X49590D01*
G01X59858Y194987D02*
Y175879D01*
G01X49590Y194987D02*
X59858D01*
G01X47957Y214850D02*
Y218350D01*
G01X53243Y214850D02*
X47957D01*
G01X53243Y218350D02*
Y214850D01*
G01X59700Y211500D02*
X55300D01*
G01X59700Y202500D02*
Y211500D01*
G01X55300Y202500D02*
X59700D01*
G01X55300Y211500D02*
Y202500D01*
G01X45800D02*
X50200D01*
G01X45800Y211500D02*
Y202500D01*
G01X50200Y211500D02*
X45800D01*
G01X50200Y202500D02*
Y211500D01*
G01X55200D02*
X50800D01*
G01X55200Y202500D02*
Y211500D01*
G01X50800Y202500D02*
X55200D01*
G01X50800Y211500D02*
Y202500D01*
G01X66200Y229500D02*
X61800D01*
G01Y220500D02*
X66200D01*
G01X61800Y229500D02*
Y220500D01*
G01X47957Y218350D02*
X53243D01*
G01X49252Y220900D02*
X53652D01*
G01X49252Y229900D02*
Y220900D01*
G01X53652Y229900D02*
X49252D01*
G01X53652Y220900D02*
Y229900D01*
G01X48652Y220900D02*
Y229900D01*
G01X47400Y230200D02*
Y239200D01*
G01X49590Y232966D02*
Y252074D01*
G01X59858Y232966D02*
X49590D01*
G01X59858Y252074D02*
Y232966D01*
G01X53343Y266250D02*
X48057D01*
G01D02*
Y269750D01*
G01X53343D02*
Y266250D01*
G01X60000Y263500D02*
X55600D01*
G01X60000Y254500D02*
Y263500D01*
G01X55600Y254500D02*
X60000D01*
G01X55600Y263500D02*
Y254500D01*
G01X61848Y268600D02*
Y264200D01*
G01D02*
X70848D01*
G01X45600Y254500D02*
X50000D01*
G01X45600Y263500D02*
Y254500D01*
G01X50000Y263500D02*
X45600D01*
G01X50000Y254500D02*
Y263500D01*
G01X55200Y265000D02*
X50800D01*
G01X55200Y256000D02*
Y265000D01*
G01X50800Y256000D02*
X55200D01*
G01X50800Y265000D02*
Y256000D01*
G01X61848Y259200D02*
X70848D01*
G01X61848Y263600D02*
Y259200D01*
G01X70848Y263600D02*
X61848D01*
G01X49590Y252074D02*
X59858D01*
G01X48057Y269750D02*
X53343D01*
G01X70848Y268600D02*
X61848D01*
G01Y268700D02*
X70848D01*
G01X61848Y273100D02*
Y268700D01*
G01X70848Y273100D02*
X61848D01*
G01X59500Y276800D02*
X68500D01*
G01X59500Y281200D02*
Y276800D01*
G01X68500Y281200D02*
X59500D01*
G01X45200Y316500D02*
Y325500D01*
G01X56500Y331200D02*
Y326800D01*
G01X65500Y331200D02*
X56500D01*
G01Y326800D02*
X65500D01*
G01X51594Y354326D02*
Y328905D01*
G01X57300Y353000D02*
X61700D01*
G01X57300Y362000D02*
Y353000D01*
G01X61700D02*
Y362000D01*
G01D02*
X57300D01*
G01X59900Y382000D02*
X54300D01*
G01X59900Y392400D02*
Y382000D01*
G01X54300D02*
Y392400D01*
G01D02*
X59900D01*
G01X70400Y66750D02*
Y98850D01*
G01X84600Y66750D02*
X70400D01*
G01X64700Y106000D02*
Y115000D01*
G01X75500Y107800D02*
X84500D01*
G01X75500Y112200D02*
Y107800D01*
G01Y102800D02*
X84500D01*
G01X75500Y107200D02*
Y102800D01*
G01X84500Y107200D02*
X75500D01*
G01X70400Y98850D02*
X84600D01*
G01X75500Y117800D02*
X84500D01*
G01X75500Y122200D02*
Y117800D01*
G01X84500Y122200D02*
X75500D01*
G01Y122800D02*
X84500D01*
G01X75500Y127200D02*
Y122800D01*
G01X84500Y127200D02*
X75500D01*
G01Y127800D02*
X84500D01*
G01X75500Y132200D02*
Y127800D01*
G01Y112800D02*
X84500D01*
G01X75500Y117200D02*
Y112800D01*
G01X84500Y117200D02*
X75500D01*
G01X84500Y112200D02*
X75500D01*
G01X84500Y132200D02*
X75500D01*
G01X65307Y134244D02*
Y170756D01*
G01X85693Y134244D02*
X65307D01*
G01X62800Y162345D02*
Y171345D01*
G01X72147Y177300D02*
X81147D01*
G01X72147Y181700D02*
Y177300D01*
G01Y172800D02*
X81147D01*
G01X72147Y177200D02*
Y172800D01*
G01X81147Y177200D02*
X72147D01*
G01X65307Y170756D02*
X85693D01*
G01X72147Y190800D02*
X81147D01*
G01X72147Y195200D02*
Y190800D01*
G01X81147Y195200D02*
X72147D01*
G01Y195300D02*
X81147D01*
G01X72147Y199700D02*
Y195300D01*
G01Y186300D02*
X81147D01*
G01X72147Y190700D02*
Y186300D01*
G01X81147Y190700D02*
X72147D01*
G01X81147Y181700D02*
X72147D01*
G01Y181800D02*
X81147D01*
G01X72147Y186200D02*
Y181800D01*
G01X81147Y186200D02*
X72147D01*
G01X71543Y202490D02*
Y218154D01*
G01X89257Y202490D02*
X71543D01*
G01X81147Y199700D02*
X72147D01*
G01X71543Y218154D02*
X89257D01*
G01X73600Y231800D02*
X69200D01*
G01X73600Y222800D02*
Y231800D01*
G01X69200Y222800D02*
X73600D01*
G01X69200Y231800D02*
Y222800D01*
G01X66200Y220500D02*
Y229500D01*
G01X76360Y220650D02*
X87840D01*
G01X76360Y226700D02*
Y220650D01*
G01X75100Y226700D02*
X76360D01*
G01X75100Y240700D02*
Y226700D01*
G01X69300Y237800D02*
X73700D01*
G01X69300Y246800D02*
Y237800D01*
G01X73700Y246800D02*
X69300D01*
G01X73700Y237800D02*
Y246800D01*
G01X79148Y250100D02*
Y259100D01*
G01X74748Y250100D02*
X79148D01*
G01X74748Y259100D02*
Y250100D01*
G01X76360Y246750D02*
Y240700D01*
G01X87840Y246750D02*
X76360D01*
G01Y240700D02*
X75100D01*
G01X70848Y264200D02*
Y268600D01*
G01X79148Y259100D02*
X74748D01*
G01X70848Y259200D02*
Y263600D01*
G01X73814Y260966D02*
Y271234D01*
G01X84082Y260966D02*
X73814D01*
G01X78000Y276800D02*
Y281200D01*
G01X69000Y276800D02*
X78000D01*
G01X69000Y281200D02*
Y276800D01*
G01X78000Y281200D02*
X69000D01*
G01X78448Y276500D02*
X82848D01*
G01X78448Y285500D02*
Y276500D01*
G01X70848Y268700D02*
Y273100D01*
G01X68500Y276800D02*
Y281200D01*
G01X73814Y271234D02*
X84082D01*
G01X82848Y285500D02*
X78448D01*
G01X68000Y322200D02*
Y317800D01*
G01D02*
X77000D01*
G01D02*
Y322200D01*
G01X66260Y336000D02*
X77740D01*
G01X66260Y340850D02*
Y336000D01*
G01X77740D02*
Y340850D01*
G01X65500Y326800D02*
Y331200D01*
G01X77000Y326700D02*
X68000D01*
G01D02*
Y322300D01*
G01D02*
X77000D01*
G01D02*
Y326700D01*
G01Y322200D02*
X68000D01*
G01X65291Y340850D02*
X66260D01*
G01X65291Y349150D02*
Y340850D01*
G01X66260Y349150D02*
X65291D01*
G01X66260Y354000D02*
Y349150D01*
G01X77740Y354000D02*
X66260D01*
G01X77740Y349150D02*
Y354000D01*
G01X78709Y349150D02*
X77740D01*
G01X78709Y340850D02*
Y349150D01*
G01X77740Y340850D02*
X78709D01*
G01X64050Y415000D02*
Y366700D01*
G01D02*
X92550D01*
G01Y415000D02*
X64050D01*
G01X92400Y74840D02*
X97250D01*
G01X92400Y63360D02*
Y74840D01*
G01X97250Y63360D02*
X92400D01*
G01X84600Y98850D02*
Y66750D01*
G01X84500Y107800D02*
Y112200D01*
G01Y102800D02*
Y107200D01*
G01Y117800D02*
Y122200D01*
G01Y122800D02*
Y127200D01*
G01Y127800D02*
Y132200D01*
G01Y112800D02*
Y117200D01*
G01X85693Y170756D02*
Y134244D01*
G01X81147Y177300D02*
Y181700D01*
G01Y172800D02*
Y177200D01*
G01Y190800D02*
Y195200D01*
G01Y195300D02*
Y199700D01*
G01Y186300D02*
Y190700D01*
G01Y181800D02*
Y186200D01*
G01X89257Y218154D02*
Y202490D01*
G01X89100Y226700D02*
Y240700D01*
G01X87840Y226700D02*
X89100D01*
G01X87840Y220650D02*
Y226700D01*
G01X81300Y250000D02*
X85700D01*
G01X81300Y259000D02*
Y250000D01*
G01X85700D02*
Y259000D01*
G01X87840Y240700D02*
Y246750D01*
G01X89100Y240700D02*
X87840D01*
G01X88300Y255848D02*
X97300D01*
G01X88300Y260248D02*
Y255848D01*
G01X97300Y260248D02*
X88300D01*
G01X88448Y270500D02*
Y266100D01*
G01D02*
X97448D01*
G01X85700Y259000D02*
X81300D01*
G01X84082Y271234D02*
Y260966D01*
G01X87348Y266000D02*
X97748D01*
G01X87348Y260400D02*
Y266000D01*
G01X97748Y260400D02*
X87348D01*
G01X88500Y275000D02*
Y270600D01*
G01X97500Y275000D02*
X88500D01*
G01Y270600D02*
X97500D01*
G01X97448Y270500D02*
X88448D01*
G01X82848Y276500D02*
Y285500D01*
G01X139400Y307800D02*
X85200D01*
G01D02*
Y362000D01*
G01X92550Y366700D02*
Y415000D01*
G01X85200Y362000D02*
X139400D01*
G01X97250Y74840D02*
Y75809D01*
G01Y62391D02*
Y63360D01*
G01X105550Y62391D02*
X97250D01*
G01Y75809D02*
X105550D01*
G01Y74840D02*
X110400D01*
G01X105550Y75809D02*
Y74840D01*
G01Y63360D02*
Y62391D01*
G01X110400Y63360D02*
X105550D01*
G01X110400Y67360D02*
Y63360D01*
G01X105550Y67360D02*
X110400D01*
G01X105550Y70840D02*
Y67360D01*
G01X110400Y70840D02*
X105550D01*
G01X110400Y74840D02*
Y70840D01*
G01X97300Y255848D02*
Y260248D01*
G01X97448Y266100D02*
Y270500D01*
G01X97748Y266000D02*
Y260400D01*
G01X97500Y270600D02*
Y275000D01*
G01X109700Y300500D02*
X105300D01*
G01X109700Y291500D02*
Y300500D01*
G01X105300Y291500D02*
X109700D01*
G01X105300Y300500D02*
Y291500D01*
G01X114700Y300500D02*
X110300D01*
G01Y291500D02*
X114700D01*
G01X110300Y300500D02*
Y291500D01*
G01X100300D02*
X104700D01*
G01X100300Y300500D02*
Y291500D01*
G01X104700Y300500D02*
X100300D01*
G01X104700Y291500D02*
Y300500D01*
G01X112700Y366500D02*
Y375500D01*
G01X108300Y366500D02*
X112700D01*
G01X108300Y375500D02*
Y366500D01*
G01X113300D02*
X117700D01*
G01X113300Y375500D02*
Y366500D01*
G01X107700D02*
Y375500D01*
G01X103300Y366500D02*
X107700D01*
G01X103300Y375500D02*
Y366500D01*
G01X112700Y375500D02*
X108300D01*
G01X117700D02*
X113300D01*
G01X107700D02*
X103300D01*
G01X114970Y63560D02*
Y59160D01*
G01X123970Y63560D02*
X114970D01*
G01Y59160D02*
X123970D01*
G01D02*
Y63560D01*
G01X114970Y63660D02*
X123970D01*
G01X114970Y68060D02*
Y63660D01*
G01X123970Y68060D02*
X114970D01*
G01X123970Y63660D02*
Y68060D01*
G01X114970Y73160D02*
X123970D01*
G01X114970Y77560D02*
Y73160D01*
G01X123970D02*
Y77560D01*
G01X114970Y68660D02*
X123970D01*
G01X114970Y73060D02*
Y68660D01*
G01X123970Y73060D02*
X114970D01*
G01X123970Y68660D02*
Y73060D01*
G01X137450Y68000D02*
X128450D01*
G01D02*
Y63600D01*
G01D02*
X137450D01*
G01X128450Y59100D02*
X137450D01*
G01X128450Y63500D02*
Y59100D01*
G01X137450Y63500D02*
X128450D01*
G01X128470Y68600D02*
X137470D01*
G01X128470Y73000D02*
Y68600D01*
G01X137470Y73000D02*
X128470D01*
G01Y73100D02*
X137470D01*
G01X128470Y77500D02*
Y73100D01*
G01X123970Y77560D02*
X114970D01*
G01X137470Y77500D02*
X128470D01*
G01X132067Y104043D02*
G02I-6000J0D01*
G01Y184043D02*
G02I-6000J0D01*
G01Y264043D02*
G02I-6000J0D01*
G01X114700Y291500D02*
Y300500D01*
G01X119700D02*
X115300D01*
G01X119700Y291500D02*
Y300500D01*
G01X115300Y291500D02*
X119700D01*
G01X115300Y300500D02*
Y291500D01*
G01X117700Y366500D02*
Y375500D01*
G01X133581Y381804D02*
X117419D01*
G01D02*
Y395196D01*
G01X125143Y377250D02*
X119857D01*
G01Y380750D02*
X125143D01*
G01X119857Y377250D02*
Y380750D01*
G01X125143D02*
Y377250D01*
G01X125357Y380750D02*
X130643D01*
G01X125357Y377250D02*
Y380750D01*
G01X130643Y377250D02*
X125357D01*
G01X130643Y380750D02*
Y377250D01*
G01X129500Y372800D02*
Y377200D01*
G01X120500Y372800D02*
X129500D01*
G01X120500Y377200D02*
Y372800D01*
G01X129500Y377200D02*
X120500D01*
G01X117419Y395196D02*
X133581D01*
G01X145964Y-110118D02*
G03I-634J0D01*
G01X149695D02*
G03I-1038J0D01*
G01X137450Y63600D02*
Y68000D01*
G01Y59100D02*
Y63500D01*
G01X137470Y68600D02*
Y73000D01*
G01Y73100D02*
Y77500D01*
G01X142300Y297800D02*
X149700D01*
G01X142300Y310200D02*
Y297800D01*
G01X146000Y292800D02*
X155000D01*
G01X146000Y297200D02*
Y292800D01*
G01X155000Y297200D02*
X146000D01*
G01X148800Y314000D02*
X153200D01*
G01X148800Y323000D02*
Y314000D01*
G01X149700Y310200D02*
X142300D01*
G01X142700Y311300D02*
Y321700D01*
G01X148300Y311300D02*
X142700D01*
G01X148300Y321700D02*
Y311300D01*
G01X139400Y362000D02*
Y307800D01*
G01X153200Y323000D02*
X148800D01*
G01X142700Y321700D02*
X148300D01*
G01X146700Y368000D02*
Y377000D01*
G01X142300Y368000D02*
X146700D01*
G01X142300Y377000D02*
Y368000D01*
G01X133581Y395196D02*
Y381804D01*
G01X146700Y377000D02*
X142300D01*
G01X148743Y388350D02*
X143457D01*
G01X148743Y391850D02*
Y388350D01*
G01X143457D02*
Y391850D01*
G01X149100Y382900D02*
Y387300D01*
G01X140100Y382900D02*
X149100D01*
G01X140100Y387300D02*
Y382900D01*
G01X149100Y387300D02*
X140100D01*
G01X141100Y396900D02*
X150100D01*
G01X141100Y401300D02*
Y396900D01*
G01X150100Y401300D02*
X141100D01*
G01Y392400D02*
X150100D01*
G01X141100Y396800D02*
Y392400D01*
G01X150100Y396800D02*
X141100D01*
G01X143457Y391850D02*
X148743D01*
G01X143457Y404850D02*
X148743D01*
G01X143457Y401350D02*
Y404850D01*
G01X148743Y401350D02*
X143457D01*
G01X148743Y404850D02*
Y401350D01*
G01X148243Y406850D02*
X142957D01*
G01X148243Y410350D02*
Y406850D01*
G01X142957D02*
Y410350D01*
G01X136300Y406000D02*
X140700D01*
G01X136300Y415000D02*
Y406000D01*
G01X140700D02*
Y415000D01*
G01X142957Y410350D02*
X148243D01*
G01X140700Y415000D02*
X136300D01*
G01X141100Y416400D02*
Y412000D01*
G01X150100Y416400D02*
X141100D01*
G01Y412000D02*
X150100D01*
G01X168013Y-137456D02*
G03I-634J0D01*
G01X155900Y-133655D02*
G03I-632J0D01*
G01X161735Y-128639D02*
G03I-1458J0D01*
G01X158530Y-131428D02*
G03I-1041J0D01*
G01X158461Y-119126D02*
G03I-1283J0D01*
G01X162690Y-117490D02*
G03I-1584J0D01*
G01X169809Y-121292D02*
G03I-2180J0D01*
G01X165531Y-125255D02*
G03I-1869J0D01*
G01X167813Y-115513D02*
G03I-1971J0D01*
G01X154775Y-120500D02*
G03I-892J0D01*
G01X162681Y-102774D02*
G03I-1584J0D01*
G01X158451Y-101149D02*
G03I-1283J0D01*
G01X159258Y-110118D02*
G03I-1868J0D01*
G01X169812Y-98951D02*
G03I-2180J0D01*
G01X167802Y-104739D02*
G03I-1971J0D01*
G01X165183Y-110118D02*
G03I-2180J0D01*
G01X171881D02*
G03I-2642J0D01*
G01X152135Y-98681D02*
G03I-632J0D01*
G01X154064Y-110118D02*
G03I-1460J0D01*
G01X154764Y-99775D02*
G03I-892J0D01*
G01X158530Y-88809D02*
G03I-1041J0D01*
G01X161742Y-91601D02*
G03I-1458J0D01*
G01X165531Y-94981D02*
G03I-1869J0D01*
G01X168570Y57000D02*
X161970D01*
G01D02*
Y76000D01*
G01X152600Y59720D02*
X157000D01*
G01X152600Y68720D02*
Y59720D01*
G01X157000Y68720D02*
X152600D01*
G01X157000Y59720D02*
Y68720D01*
G01X161970Y76000D02*
X168570D01*
G01X149700Y297800D02*
Y310200D01*
G01X155000Y292800D02*
Y297200D01*
G01X150800Y298000D02*
X155200D01*
G01X150800Y307000D02*
Y298000D01*
G01X155200D02*
Y307000D01*
G01X158983Y294496D02*
Y308504D01*
G01X177017Y294496D02*
X158983D01*
G01X153200Y314000D02*
Y323000D01*
G01X155200Y307000D02*
X150800D01*
G01X158983Y308504D02*
X177017D01*
G01X157669Y313343D02*
Y320657D01*
G01X170331Y313343D02*
X157669D01*
G01Y330657D02*
X170331D01*
G01X157669Y323343D02*
Y330657D01*
G01X170331Y323343D02*
X157669D01*
G01Y320657D02*
X170331D01*
G01X164600Y386300D02*
Y381900D01*
G01X173600Y386300D02*
X164600D01*
G01Y381900D02*
X173600D01*
G01X164900Y381300D02*
Y373900D01*
G01X177300Y381300D02*
X164900D01*
G01Y373900D02*
X177300D01*
G01X155904Y387904D02*
Y405296D01*
G01X173262Y387904D02*
X155904D01*
G01X150900Y374800D02*
Y380400D01*
G01X161300Y374800D02*
X150900D01*
G01Y380400D02*
X161300D01*
G01D02*
Y374800D01*
G01X150100Y396900D02*
Y401300D01*
G01Y392400D02*
Y396800D01*
G01X162600Y411300D02*
Y406900D01*
G01D02*
X171600D01*
G01X155904Y405296D02*
X173262D01*
G01X171600Y411300D02*
X162600D01*
G01X161900Y418800D02*
Y411400D01*
G01X174300Y418800D02*
X161900D01*
G01Y411400D02*
X174300D01*
G01X153400Y409600D02*
X157800D01*
G01X153400Y418600D02*
Y409600D01*
G01X157800Y418600D02*
X153400D01*
G01X157800Y409600D02*
Y418600D01*
G01X150100Y412000D02*
Y416400D01*
G01X171080Y-131739D02*
G03I-1282J0D01*
G01X169322Y-135033D02*
G03I-892J0D01*
G01X180669Y-131528D02*
G03I-1870J0D01*
G01X180255Y-136311D02*
G03I-1456J0D01*
G01X179841Y-140261D02*
G03I-1042J0D01*
G01X179433Y-143587D02*
G03I-634J0D01*
G01X181439Y-119680D02*
G03I-2640J0D01*
G01X175373Y-123081D02*
G03I-1968J0D01*
G01X173018Y-127816D02*
G03I-1584J0D01*
G01X174681Y-116876D02*
G03I-2640J0D01*
G01X180979Y-125917D02*
G03I-2180J0D01*
G01X186177Y-123075D02*
G03I-1971J0D01*
G01X188199Y-116876D02*
G03I-2640J0D01*
G01X175452Y-97124D02*
G03I-1968J0D01*
G01X186225Y-97178D02*
G03I-1971J0D01*
G01X181439Y-100556D02*
G03I-2640J0D01*
G01X174681Y-103361D02*
G03I-2640J0D01*
G01X188199D02*
G03I-2640J0D01*
G01X179841Y-79975D02*
G03I-1042J0D01*
G01X171217Y-88444D02*
G03I-1282J0D01*
G01X173123Y-92378D02*
G03I-1584J0D01*
G01X180255Y-83924D02*
G03I-1456J0D01*
G01X180669Y-88708D02*
G03I-1870J0D01*
G01X180979Y-94320D02*
G03I-2180J0D01*
G01X179433Y-76648D02*
G03I-634J0D01*
G01X168570Y55850D02*
Y57000D01*
G01X185970Y55850D02*
X168570D01*
G01Y76000D02*
Y77150D01*
G01D02*
X185970D01*
G01X180000Y306200D02*
Y301800D01*
G01D02*
X189000D01*
G01X169857Y291750D02*
X175143D01*
G01X169857Y288250D02*
Y291750D01*
G01X175143Y288250D02*
X169857D01*
G01X175143Y291750D02*
Y288250D01*
G01X185700Y300500D02*
X181300D01*
G01Y291500D02*
X185700D01*
G01X181300Y300500D02*
Y291500D01*
G01X177017Y308504D02*
Y294496D01*
G01X189000Y306200D02*
X180000D01*
G01X179500Y321200D02*
Y316800D01*
G01D02*
X188500D01*
G01X179300Y314200D02*
Y306800D01*
G01X191700Y314200D02*
X179300D01*
G01Y306800D02*
X191700D01*
G01X173200Y310800D02*
Y321200D01*
G01X178800Y310800D02*
X173200D01*
G01X178800Y321200D02*
Y310800D01*
G01X170331Y320657D02*
Y313343D01*
G01X188500Y321200D02*
X179500D01*
G01X175300Y329700D02*
Y322300D01*
G01X187700Y329700D02*
X175300D01*
G01Y322300D02*
X187700D01*
G01X173200Y321200D02*
X178800D01*
G01X170331Y330657D02*
Y323343D01*
G01X173600Y381900D02*
Y386300D01*
G01X177300Y373900D02*
Y381300D01*
G01X213613Y382624D02*
X178587D01*
G01D02*
Y412576D01*
G01X173262Y405296D02*
Y387904D01*
G01X171600Y406900D02*
Y411300D01*
G01X174300Y411400D02*
Y418800D01*
G01X178587Y412576D02*
X213613D01*
G01X191096Y-134658D02*
G03I-892J0D01*
G01X192135Y-136781D02*
G03I-631J0D01*
G01X198775Y-128635D02*
G03I-1458J0D01*
G01X195808Y-125255D02*
G03I-1869J0D01*
G01X200547Y-113952D02*
G03X203345Y-117196I7247J3422D01*
G01X192148Y-121285D02*
G03I-2180J0D01*
G01X187928Y-127802D02*
G03I-1584J0D01*
G01X189667Y-131511D02*
G03I-1283J0D01*
G01X200699Y-105836D02*
G03X200547Y-113953I8974J-4228D01*
G01X208284Y-101612D02*
G03X200698Y-105835I-219J-8531D01*
G01X192148Y-98951D02*
G03I-2180J0D01*
G01X191108Y-82727D02*
G03I-634J0D01*
G01X190184Y-85250D02*
G03I-893J0D01*
G01X195808Y-94981D02*
G03I-1869J0D01*
G01X187839Y-92457D02*
G03I-1584J0D01*
G01X189190Y-88538D02*
G03I-1283J0D01*
G01X197570Y56600D02*
X201970D01*
G01X197570Y65600D02*
Y56600D01*
G01X192570Y57000D02*
X185970D01*
G01D02*
Y55850D01*
G01X192570Y76000D02*
Y57000D01*
G01X201970Y65600D02*
X197570D01*
G01X185970Y77150D02*
Y76000D01*
G01D02*
X192570D01*
G01X189000Y301800D02*
Y306200D01*
G01X186300Y291500D02*
X190700D01*
G01X186300Y300500D02*
Y291500D01*
G01X190700Y300500D02*
X186300D01*
G01X190700Y291500D02*
Y300500D01*
G01X185700Y291500D02*
Y300500D01*
G01X188500Y316800D02*
Y321200D01*
G01X191700Y306800D02*
Y314200D01*
G01X187700Y322300D02*
Y329700D01*
G01X198100Y331300D02*
X193700D01*
G01X198100Y322300D02*
Y331300D01*
G01X193700Y322300D02*
X198100D01*
G01X193700Y331300D02*
Y322300D01*
G01X214259Y-115661D02*
G03X213314Y-114453I-714J415D01*
G01X202049Y-108260D02*
G03X205722Y-116181I7039J-1548D01*
G01X218075Y-112869D02*
G03X219083Y-115752I4343J-99D01*
G01X208854Y-116658D02*
G03X213313Y-114452I-2485J10632D01*
G01X208470Y-118462D02*
G03X214261Y-115663I-1122J9711D01*
G01X203346Y-117195D02*
G03X208470Y-118461I4545J7394D01*
G01X205721Y-116179D02*
G03X208853Y-116659I2561J6250D01*
G01X215903Y-114020D02*
G03X219079Y-118061I6190J1597D01*
G01X215904Y-114020D02*
Y-111835D01*
G01X227413Y-112869D02*
X218074D01*
G01X214175Y-103951D02*
G03X208283Y-101613I-6403J-7542D01*
G01X213150Y-105147D02*
G03X214175Y-103951I410J686D01*
G01X213152Y-105146D02*
G03X208030Y-103430I-5122J-6786D01*
G01X208029Y-103429D02*
G03X202049Y-108259I-48J-6058D01*
G01X225189Y-111399D02*
G03X218071I-3559J159D01*
G01X218070Y-111418D02*
Y-111399D01*
G01X225188Y-111418D02*
X218070D01*
G01X227412Y-111835D02*
G03X215906I-5753J223D01*
G01X212700Y57000D02*
Y66000D01*
G01X208300D02*
Y57000D01*
G01D02*
X212700D01*
G01X217200D02*
Y66000D01*
G01X212800D02*
Y57000D01*
G01D02*
X217200D01*
G01X201970Y56600D02*
Y65600D01*
G01X202570D02*
Y56600D01*
G01D02*
X206970D01*
G01D02*
Y65600D01*
G01X212700Y66000D02*
X208300D01*
G01X217200D02*
X212800D01*
G01X206970Y65600D02*
X202570D01*
G01X215100Y290700D02*
X219500D01*
G01X215100Y299700D02*
Y290700D01*
G01X219500Y299700D02*
X215100D01*
G01X210600Y290700D02*
X215000D01*
G01X210600Y299700D02*
Y290700D01*
G01X215000Y299700D02*
X210600D01*
G01X215000Y290700D02*
Y299700D01*
G01X206100Y290700D02*
X210500D01*
G01X206100Y299700D02*
Y290700D01*
G01X210500Y299700D02*
X206100D01*
G01X210500Y290700D02*
Y299700D01*
G01X206500Y310500D02*
X207760D01*
G01X206500Y324500D02*
Y310500D01*
G01X207760Y304450D02*
X219240D01*
G01X207760Y310500D02*
Y304450D01*
G01Y324500D02*
X206500D01*
G01X207760Y330550D02*
Y324500D01*
G01X219240Y330550D02*
X207760D01*
G01X215400Y382100D02*
X219800D01*
G01X215400Y391100D02*
Y382100D01*
G01X213613Y412576D02*
Y382624D01*
G01X219800Y391100D02*
X215400D01*
G01X214900Y400900D02*
X222300D01*
G01X214900Y413300D02*
Y400900D01*
G01X222300Y413300D02*
X214900D01*
G01X230059Y-117625D02*
Y-102034D01*
G01X230060Y-117626D02*
G03X232080I1010J239D01*
G01X226590Y-116472D02*
G03X225311Y-115210I-817J451D01*
G01X234673Y-114020D02*
G03X237849Y-118061I6190J1597D01*
G01X232081Y-102041D02*
Y-117625D01*
G01X219083Y-115753D02*
G03X225311Y-115211I2844J3371D01*
G01X219079Y-118060D02*
G03X226591Y-116473I2662J5972D01*
G01X227413Y-111835D02*
Y-112869D01*
G01X232080Y-102041D02*
G03X230060Y-102034I-1011J-236D01*
G01X225188Y-111399D02*
Y-111418D01*
G01X234675Y-114020D02*
Y-111835D01*
G01X246181D02*
G03X234675I-5753J223D01*
G01X219600Y290700D02*
X224000D01*
G01X219600Y299700D02*
Y290700D01*
G01X224000Y299700D02*
X219600D01*
G01X224000Y290700D02*
Y299700D01*
G01X219500Y290700D02*
Y299700D01*
G01X219240Y304450D02*
Y310500D01*
G01X220500D02*
Y324500D01*
G01X219240Y310500D02*
X220500D01*
G01X224080Y322100D02*
X228480D01*
G01X224080Y331100D02*
Y322100D01*
G01X228480Y331100D02*
X224080D01*
G01X228480Y322100D02*
Y331100D01*
G01X219240Y324500D02*
Y330550D01*
G01X220500Y324500D02*
X219240D01*
G01X219800Y382100D02*
Y391100D01*
G01X219900Y379900D02*
X227300D01*
G01X219900Y392300D02*
Y379900D01*
G01X227300D02*
Y392300D01*
G01D02*
X219900D01*
G01X222400Y400900D02*
X229800D01*
G01X222400Y413300D02*
Y400900D01*
G01X229800D02*
Y413300D01*
G01X222300Y400900D02*
Y413300D01*
G01X229800D02*
X222400D01*
G01X252849Y-116771D02*
G03X254892Y-115895I-74J2994D01*
G01X236844Y-112869D02*
G03X237852Y-115752I4343J-99D01*
G01X237848Y-118060D02*
G03X245360Y-116473I2662J5972D01*
G01X245358Y-116472D02*
G03X244079Y-115210I-817J451D01*
G01X237852Y-115753D02*
G03X244080Y-115211I2844J3371D01*
G01X249566Y-115529D02*
G03X252307Y-116760I2985J2980D01*
G01Y-116761D02*
G03X252849Y-116772I366J4691D01*
G01X250282Y-118087D02*
G03X254318Y-118340I2605J9244D01*
G01X247897Y-116444D02*
G03X250283Y-118086I3752J2898D01*
G01X249568Y-115529D02*
G03X247898Y-116443I-748J-616D01*
G01X255608Y-108618D02*
G03X253612Y-107689I-3116J-4086D01*
G01X246181Y-111835D02*
Y-112869D01*
G01D02*
X236844D01*
G01X255002Y-114328D02*
G03X252723Y-112986I-3540J-3405D01*
G01X249955Y-112030D02*
G03X252723Y-112985I8208J19302D01*
G01X243957Y-111399D02*
Y-111418D01*
G01X243958Y-111399D02*
G03X236840I-3559J159D01*
G01X236841Y-111418D02*
Y-111399D01*
G01X243957Y-111418D02*
X236841D01*
G01X248537Y-109748D02*
G03X249956Y-112031I2652J66D01*
G01X248537Y-108250D02*
Y-109748D01*
G01X250179Y-106359D02*
G03X248537Y-108249I2747J-4045D01*
G01X256884Y-107368D02*
G03X250178Y-106359I-4153J-4811D01*
G01X253611Y-107689D02*
G03X251080Y-107949I-869J-3992D01*
G01X251081Y-107948D02*
G03X250837Y-110104I805J-1183D01*
G01Y-110106D02*
G03X254306Y-111513I5270J8013D01*
G01X248922Y65000D02*
Y56000D01*
G01D02*
X253322D01*
G01D02*
Y65000D01*
G01D02*
X248922D01*
G01X259967Y93443D02*
G02I-6000J0D01*
G01X269106Y309646D02*
G02I-13200J0D01*
G01Y412008D02*
G02I-13200J0D01*
G01X260954Y-116041D02*
Y-107954D01*
G01X254892Y-115895D02*
G03X255001Y-114328I-764J840D01*
G01X269619Y-117484D02*
Y-106797D01*
G01X269620Y-117484D02*
G03X271926I1153J198D01*
G01X266864Y-117375D02*
G03X266002Y-116329I-764J249D01*
G01X262978Y-115462D02*
G03X266002Y-116329I2046J1428D01*
G01X260955Y-116043D02*
G03X264164Y-118351I2956J725D01*
G01X265463Y-118350D02*
X264165D01*
G01X265464Y-118352D02*
G03X266864Y-117374I-24J1525D01*
G01X256906Y-116470D02*
G03X257054Y-113728I-3143J1545D01*
G01X254317Y-118340D02*
G03X256906Y-116470I-1259J4470D01*
G01X262978Y-107954D02*
Y-115463D01*
G01X257054Y-113729D02*
G03X254307Y-111513I-3470J-1490D01*
G01X271969Y-102342D02*
G03I-1194J0D01*
G01X271926Y-106797D02*
G03X269620I-1153J-409D01*
G01X266003Y-107954D02*
X262978D01*
G01X266004Y-107955D02*
G03X266008Y-105932I-177J1012D01*
G01X262978D02*
X266008D01*
G01X262971Y-103419D02*
X262978Y-105932D01*
G01X262972Y-103418D02*
G03X260954Y-103491I-1005J-141D01*
G01Y-105932D02*
Y-103492D01*
G01X259930Y-105932D02*
X260954D01*
G01X259930D02*
G03X259981Y-107955I298J-1005D01*
G01X260954Y-107954D02*
X259982D01*
G01X255606Y-108620D02*
G03X256885Y-107367I599J667D01*
G01X266100Y58300D02*
Y62700D01*
G01X257100Y58300D02*
X266100D01*
G01X257100Y62700D02*
Y58300D01*
G01X266100Y62700D02*
X257100D01*
G01X266100Y63300D02*
Y67700D01*
G01D02*
X257100D01*
G01D02*
Y63300D01*
G01D02*
X266100D01*
G01X271967Y93443D02*
G02I-6000J0D01*
G01X290671Y-110842D02*
G03X290703Y-118351I860J-3751D01*
G01X276837Y-114305D02*
G03X278891Y-116297I4069J2141D01*
G01X274529Y-113568D02*
G03X275888Y-116443I5718J944D01*
G01X275887D02*
G03X279572Y-118352I4392J3967D01*
G01X281425Y-118350D02*
X279571D01*
G01X281425D02*
G03X284525Y-117161I0J4636D01*
G01X285201Y-116508D02*
X284524Y-117161D01*
G01X285201Y-116508D02*
G03X283966Y-115211I-695J574D01*
G01X281510Y-116675D02*
G03X283966Y-115212I-989J4453D01*
G01X278889Y-116297D02*
G03X281508Y-116677I1946J4197D01*
G01X271926Y-106797D02*
Y-117484D01*
G01X274529Y-113566D02*
Y-111839D01*
G01X276446Y-112943D02*
G03X276837Y-114305I4162J458D01*
G01X276445Y-112066D02*
Y-112943D01*
G01X283833Y-109274D02*
G03X285403Y-108106I585J852D01*
G01X285402D02*
G03X280919Y-105777I-4776J-3714D01*
G01X279541D02*
X280919D01*
G01X279540D02*
G03X274999Y-109274I1260J-6333D01*
G01X274998D02*
G03X274529Y-111839I9988J-3152D01*
G01X276849Y-109932D02*
G03X276446Y-112066I5467J-2137D01*
G01X280036Y-107542D02*
G03X276849Y-109933I664J-4205D01*
G01X282662Y-108199D02*
G03X280037Y-107539I-2313J-3650D01*
G01X283833Y-109275D02*
G03X282662Y-108202I-9277J-8949D01*
G01X287700Y56291D02*
Y64709D01*
G01X283851Y55270D02*
Y56291D01*
G01D02*
X287700D01*
G01X272500Y64709D02*
Y56291D01*
G01D02*
X276349D01*
G01D02*
Y55270D01*
G01D02*
X283851D01*
G01X287700Y64709D02*
X283851D01*
G01D02*
Y65730D01*
G01D02*
X276349D01*
G01D02*
Y64709D01*
G01D02*
X272500D01*
G01X283867Y93443D02*
G02I-6000J0D01*
G01X292067Y104043D02*
G02I-6000J0D01*
G01X272436Y199862D02*
Y165325D01*
G01D02*
X297284D01*
G01Y202759D02*
X275333D01*
G01D02*
X272436Y199862D01*
G01X292067Y264043D02*
G02I-6000J0D01*
G01X287100Y318400D02*
X296100D01*
G01X287100Y322800D02*
Y318400D01*
G01X296100Y322800D02*
X287100D01*
G01Y328100D02*
Y323700D01*
G01X296100Y328100D02*
X287100D01*
G01Y323700D02*
X296100D01*
G01X287200Y335400D02*
Y331000D01*
G01X296200Y335400D02*
X287200D01*
G01Y331000D02*
X296200D01*
G01X294457Y-116619D02*
G03Y-112289I-51J2165D01*
G01X291853Y-116620D02*
X294456D01*
G01X291853Y-112289D02*
G03Y-116619I195J-2165D01*
G01X294165Y-118350D02*
X290701D01*
G01X294165D02*
G03X296471Y-117226I-1088J5161D01*
G01X296473Y-117625D02*
Y-117226D01*
G01X296474Y-117627D02*
G03X298494I1010J185D01*
G01X298495Y-109394D02*
Y-117625D01*
G01X301067Y-108534D02*
Y-106508D01*
G01X301615Y-108534D02*
X301067D01*
G01X301615Y-106508D02*
Y-108534D01*
G01X302461Y-106508D02*
X301615D01*
G01X302461Y-106001D02*
Y-106508D01*
G01X300223Y-106001D02*
X302461D01*
G01X300223Y-106508D02*
Y-106001D01*
G01X301067Y-106508D02*
X300223D01*
G01X305164Y-106001D02*
X304731D01*
G01X305713Y-108544D02*
X305164Y-106001D01*
G01X305171Y-108544D02*
X305713D01*
G01X304889Y-106871D02*
X305171Y-108544D01*
G01X304309D02*
X304889Y-106871D01*
G01X304086Y-108544D02*
X304309D01*
G01X303501Y-106887D02*
X304086Y-108544D01*
G01X303226D02*
X303501Y-106887D01*
G01X302698Y-108544D02*
X303226D01*
G01X303243Y-106001D02*
X302698Y-108544D01*
G01X303648Y-106001D02*
X303243D01*
G01X304192Y-107632D02*
X303648Y-106001D01*
G01X304731D02*
X304192Y-107632D01*
G01X294456Y-112288D02*
X291853D01*
G01X296473Y-110841D02*
Y-109686D01*
G01X296472Y-110841D02*
G03X292878Y-110536I-3256J-17043D01*
G01X292879Y-110535D02*
G03X290670Y-110842I280J-10112D01*
G01X298496Y-109394D02*
G03X295031Y-105933I-3962J-501D01*
G01X291563Y-105932D02*
X295031D01*
G01X291562D02*
G03X289112Y-107085I584J-4421D01*
G01Y-107086D02*
G03X289820Y-108520I585J-603D01*
G01X290987Y-107954D02*
G03X289821Y-108520I1446J-4464D01*
G01X294740Y-107954D02*
X290987D01*
G01X296473Y-109686D02*
G03X294742Y-107955I-1598J133D01*
G01X302000Y55241D02*
Y59641D01*
G01X293000Y55241D02*
X302000D01*
G01X293000Y59641D02*
Y55241D01*
G01X302120Y64580D02*
Y68980D01*
G01X293120Y64580D02*
X302120D01*
G01Y68980D02*
X293120D01*
G01D02*
Y64580D01*
G01X302000Y59641D02*
X293000D01*
G01X302100Y59900D02*
Y64300D01*
G01X293100Y59900D02*
X302100D01*
G01Y64300D02*
X293100D01*
G01D02*
Y59900D01*
G01X297284Y165325D02*
Y202759D01*
G01X296100Y318400D02*
Y322800D01*
G01X300150Y320650D02*
Y342350D01*
G01X332250Y320650D02*
X300150D01*
G01X296100Y323700D02*
Y328100D01*
G01X296200Y331000D02*
Y335400D01*
G01X300150Y342350D02*
X332250D01*
G01X290024Y368987D02*
Y404013D01*
G01X319976Y368987D02*
X290024D01*
G01Y404013D02*
X319976D01*
G01X319000Y162300D02*
Y166700D01*
G01X310000D02*
Y162300D01*
G01D02*
X319000D01*
G01X318900Y177800D02*
Y182200D01*
G01X309900D02*
Y177800D01*
G01D02*
X318900D01*
G01X319000Y166700D02*
X310000D01*
G01X319000Y167300D02*
Y171700D01*
G01X310000Y167300D02*
X319000D01*
G01Y171700D02*
X310000D01*
G01D02*
Y167300D01*
G01X318900Y172800D02*
Y177200D01*
G01D02*
X309900D01*
G01D02*
Y172800D01*
G01D02*
X318900D01*
G01X323400Y194300D02*
Y198700D01*
G01X314400Y194300D02*
X323400D01*
G01X314400Y198700D02*
Y194300D01*
G01X318900Y182200D02*
X309900D01*
G01X318500Y187300D02*
Y191700D01*
G01X309500Y187300D02*
X318500D01*
G01Y191700D02*
X309500D01*
G01D02*
Y187300D01*
G01X318500Y182800D02*
Y187200D01*
G01X309500Y182800D02*
X318500D01*
G01Y187200D02*
X309500D01*
G01D02*
Y182800D01*
G01X323000Y218700D02*
Y214300D01*
G01D02*
X332000D01*
G01X323400Y198700D02*
X314400D01*
G01X323400Y199300D02*
Y203700D01*
G01X314400Y199300D02*
X323400D01*
G01X314400Y203700D02*
Y199300D01*
G01X323400Y203700D02*
X314400D01*
G01X323400Y203800D02*
Y208200D01*
G01X314400Y203800D02*
X323400D01*
G01X314400Y208200D02*
Y203800D01*
G01X323400Y208200D02*
X314400D01*
G01X323400Y208800D02*
Y213200D01*
G01X314400Y208800D02*
X323400D01*
G01X314400Y213200D02*
Y208800D01*
G01X323400Y213200D02*
X314400D01*
G01X322500Y214200D02*
Y218600D01*
G01X313500Y214200D02*
X322500D01*
G01X313500Y218600D02*
Y214200D01*
G01X332000Y218700D02*
X323000D01*
G01X322500Y218600D02*
X313500D01*
G01X322500Y218700D02*
Y223100D01*
G01X313500Y218700D02*
X322500D01*
G01X313500Y223100D02*
Y218700D01*
G01X322500Y223100D02*
X313500D01*
G01X322500Y232200D02*
Y236600D01*
G01X313500Y232200D02*
X322500D01*
G01X313500Y236600D02*
Y232200D01*
G01X322500Y227700D02*
Y232100D01*
G01X313500Y227700D02*
X322500D01*
G01X313500Y232100D02*
Y227700D01*
G01X322500Y232100D02*
X313500D01*
G01Y227600D02*
Y223200D01*
G01X322500Y227600D02*
X313500D01*
G01X322500Y223200D02*
Y227600D01*
G01X313500Y223200D02*
X322500D01*
G01Y250200D02*
Y254600D01*
G01X313500Y250200D02*
X322500D01*
G01X313500Y254600D02*
Y250200D01*
G01X322500Y245700D02*
Y250100D01*
G01X313500Y245700D02*
X322500D01*
G01X313500Y250100D02*
Y245700D01*
G01X322500Y250100D02*
X313500D01*
G01X322500Y236600D02*
X313500D01*
G01Y241100D02*
Y236700D01*
G01X322500Y241100D02*
X313500D01*
G01X322500Y236700D02*
Y241100D01*
G01X313500Y236700D02*
X322500D01*
G01X313500Y245600D02*
Y241200D01*
G01X322500Y245600D02*
X313500D01*
G01X322500Y241200D02*
Y245600D01*
G01X313500Y241200D02*
X322500D01*
G01Y254600D02*
X313500D01*
G01X322500Y254700D02*
Y259100D01*
G01X313500Y254700D02*
X322500D01*
G01X313500Y259100D02*
Y254700D01*
G01X322500Y259100D02*
X313500D01*
G01X352256Y271307D02*
X315744D01*
G01D02*
Y291693D01*
G01D02*
X352256D01*
G01X323300Y364000D02*
X327700D01*
G01X323300Y373000D02*
Y364000D01*
G01X319976Y404013D02*
Y368987D01*
G01X327700Y373000D02*
X323300D01*
G01X322600Y416500D02*
X335000D01*
G01X322600Y423900D02*
Y416500D01*
G01X335000Y423900D02*
X322600D01*
G01X328100Y194500D02*
Y203500D01*
G01X323700Y194500D02*
X328100D01*
G01X323700Y203500D02*
Y194500D01*
G01X332000Y214300D02*
Y218700D01*
G01X328100Y203500D02*
X323700D01*
G01X328100Y213000D02*
X323700D01*
G01X328100Y204000D02*
Y213000D01*
G01X323700Y204000D02*
X328100D01*
G01X323700Y213000D02*
Y204000D01*
G01X347502Y220146D02*
X330498D01*
G01D02*
Y242654D01*
G01X336284Y248700D02*
X340684D01*
G01X336284Y257700D02*
Y248700D01*
G01X340684D02*
Y257700D01*
G01X335700Y248700D02*
Y257700D01*
G01X331300Y248700D02*
X335700D01*
G01X331300Y257700D02*
Y248700D01*
G01X326300D02*
X330700D01*
G01X326300Y257700D02*
Y248700D01*
G01X330700D02*
Y257700D01*
G01X330498Y242654D02*
X347502D01*
G01X340684Y257700D02*
X336284D01*
G01X335700D02*
X331300D01*
G01X330700D02*
X326300D01*
G01X332250Y342350D02*
Y320650D01*
G01X327700Y364000D02*
Y373000D01*
G01X336300Y362300D02*
X343700D01*
G01X336300Y374700D02*
Y362300D01*
G01X328300D02*
X335700D01*
G01X328300Y374700D02*
Y362300D01*
G01X335700D02*
Y374700D01*
G01X328300Y386500D02*
X337300D01*
G01X328300Y390900D02*
Y386500D01*
G01X337300D02*
Y390900D01*
G01X343700Y374700D02*
X336300D01*
G01X335700D02*
X328300D01*
G01X325600Y379000D02*
X338000D01*
G01X325600Y386400D02*
Y379000D01*
G01X338000Y386400D02*
X325600D01*
G01X338000Y379000D02*
Y386400D01*
G01X337300Y390900D02*
X328300D01*
G01X326638Y392504D02*
Y409896D01*
G01X343996Y392504D02*
X326638D01*
G01X326300Y411500D02*
X335300D01*
G01X326300Y415900D02*
Y411500D01*
G01X335300Y415900D02*
X326300D01*
G01X335300Y411500D02*
Y415900D01*
G01X335000Y416500D02*
Y423900D01*
G01X326638Y409896D02*
X343996D01*
G01X338600Y423000D02*
X349000D01*
G01X338600Y417400D02*
Y423000D01*
G01X349000Y417400D02*
X338600D01*
G01X355300Y164500D02*
Y155500D01*
G01D02*
X359700D01*
G01X355200Y155300D02*
Y167700D01*
G01X347800D02*
Y155300D01*
G01D02*
X355200D01*
G01X359700Y164500D02*
X355300D01*
G01X355200Y167700D02*
X347800D01*
G01X357600Y172149D02*
Y181149D01*
G01X353200D02*
Y172149D01*
G01D02*
X357600D01*
G01X358200Y181149D02*
Y172149D01*
G01D02*
X362600D01*
G01X357600Y181149D02*
X353200D01*
G01X362600D02*
X358200D01*
G01X347745Y184893D02*
X361057D01*
G01X347745Y198205D02*
Y184893D01*
G01X361057Y198205D02*
X347745D01*
G01X353250Y230593D02*
Y241207D01*
G01X360750Y230593D02*
X353250D01*
G01X347502Y242654D02*
Y220146D01*
G01X356800Y248900D02*
Y257900D01*
G01X352400Y248900D02*
X356800D01*
G01X352400Y257900D02*
Y248900D01*
G01X341300Y248700D02*
X345700D01*
G01X341300Y257700D02*
Y248700D01*
G01X345700D02*
Y257700D01*
G01X353250Y241207D02*
X360750D01*
G01X351900Y248400D02*
X346300D01*
G01D02*
Y258800D01*
G01X351900D02*
Y248400D01*
G01X356800Y257900D02*
X352400D01*
G01X345700Y257700D02*
X341300D01*
G01X346300Y258800D02*
X351900D01*
G01X356000Y283200D02*
X360400D01*
G01X356000Y292200D02*
Y283200D01*
G01X360400Y282700D02*
X356000D01*
G01Y273700D02*
X360400D01*
G01X356000Y282700D02*
Y273700D01*
G01X352256Y291693D02*
Y271307D01*
G01X360400Y292200D02*
X356000D01*
G01X343500Y319193D02*
X381500D01*
G01X343500Y342807D02*
Y319193D01*
G01X381500Y342807D02*
X343500D01*
G01X343700Y362300D02*
Y374700D01*
G01X344300Y362300D02*
X351700D01*
G01X344300Y374700D02*
Y362300D01*
G01X351700D02*
Y374700D01*
G01D02*
X344300D01*
G01X351157Y387450D02*
Y390950D01*
G01X356443Y387450D02*
X351157D01*
G01X356443Y390950D02*
Y387450D01*
G01X349800Y381100D02*
X358800D01*
G01X349800Y385500D02*
Y381100D01*
G01X358800Y385500D02*
X349800D01*
G01X347000Y375800D02*
X356000D01*
G01X347000Y380200D02*
Y375800D01*
G01X356000Y380200D02*
X347000D01*
G01X356000Y375800D02*
Y380200D01*
G01X346500Y388200D02*
X342100D01*
G01X346500Y379200D02*
Y388200D01*
G01X342100Y379200D02*
X346500D01*
G01X342100Y388200D02*
Y379200D01*
G01X349800Y405400D02*
Y401000D01*
G01X358800Y405400D02*
X349800D01*
G01Y401000D02*
X358800D01*
G01X349800Y400900D02*
Y396500D01*
G01X358800Y400900D02*
X349800D01*
G01Y396500D02*
X358800D01*
G01X351157Y390950D02*
X356443D01*
G01Y392950D02*
X351157D01*
G01X356443Y396450D02*
Y392950D01*
G01X351157Y396450D02*
X356443D01*
G01X351157Y392950D02*
Y396450D01*
G01X349800Y409900D02*
Y405500D01*
G01D02*
X358800D01*
G01X343996Y409896D02*
Y392504D01*
G01X352800Y421900D02*
Y417500D01*
G01X361800Y421900D02*
X352800D01*
G01Y417500D02*
X361800D01*
G01X351057Y413850D02*
X356343D01*
G01X351057Y410350D02*
Y413850D01*
G01X356343Y410350D02*
X351057D01*
G01X356343Y413850D02*
Y410350D01*
G01X358800Y409900D02*
X349800D01*
G01X349000Y423000D02*
Y417400D01*
G01X374800Y94000D02*
Y85000D01*
G01D02*
X379200D01*
G01X383500Y99200D02*
X374500D01*
G01D02*
Y94800D01*
G01D02*
X383500D01*
G01X370300Y102300D02*
X382700D01*
G01Y109700D02*
X370300D01*
G01D02*
Y102300D01*
G01X379200Y94000D02*
X374800D01*
G01X369700Y149800D02*
Y144200D01*
G01D02*
X359300D01*
G01D02*
Y149800D01*
G01X359700Y155500D02*
Y164500D01*
G01X374200Y155300D02*
Y167700D01*
G01X366800D02*
Y155300D01*
G01D02*
X374200D01*
G01X359300Y149800D02*
X369700D01*
G01X374200Y167700D02*
X366800D01*
G01X362600Y172149D02*
Y181149D01*
G01X361057Y184893D02*
Y198205D01*
G01X361923Y230957D02*
Y236243D01*
G01X365423Y230957D02*
X361923D01*
G01X365423Y236243D02*
Y230957D01*
G01X360750Y241207D02*
Y230593D01*
G01X360300Y223300D02*
X370700D01*
G01X360300Y217700D02*
Y223300D01*
G01X370700Y217700D02*
X360300D01*
G01X370700Y223300D02*
Y217700D01*
G01X363760Y248000D02*
X375240D01*
G01X363760Y252850D02*
Y248000D01*
G01X375240D02*
Y252850D01*
G01X372700Y245000D02*
X368300D01*
G01X372700Y236000D02*
Y245000D01*
G01X368300Y236000D02*
X372700D01*
G01X368300Y245000D02*
Y236000D01*
G01X361923Y236243D02*
X365423D01*
G01X361923Y242843D02*
X365423D01*
G01X361923Y237557D02*
Y242843D01*
G01X365423Y237557D02*
X361923D01*
G01X365423Y242843D02*
Y237557D01*
G01X373800Y236000D02*
X378200D01*
G01X373800Y245000D02*
Y236000D01*
G01X378200Y245000D02*
X373800D01*
G01X375240Y266000D02*
X363760D01*
G01D02*
Y261150D01*
G01D02*
X362791D01*
G01D02*
Y252850D01*
G01D02*
X363760D01*
G01X375240D02*
X376209D01*
G01Y261150D02*
X375240D01*
G01D02*
Y266000D01*
G01X360400Y283200D02*
Y292200D01*
G01X369200Y277500D02*
X376600D01*
G01X369200Y289900D02*
Y277500D01*
G01X366500Y273200D02*
Y268800D01*
G01X375500Y273200D02*
X366500D01*
G01X375500Y268800D02*
Y273200D01*
G01X366500Y268800D02*
X375500D01*
G01X360400Y273700D02*
Y282700D01*
G01X364000Y295200D02*
X368400D01*
G01X364000Y304200D02*
Y295200D01*
G01X368400D02*
Y304200D01*
G01X369500Y292300D02*
X376900D01*
G01X369500Y304700D02*
Y292300D01*
G01X376600Y289900D02*
X369200D01*
G01X368400Y304200D02*
X364000D01*
G01X376900Y304700D02*
X369500D01*
G01X362900Y307100D02*
Y312700D01*
G01X373300Y307100D02*
X362900D01*
G01Y312700D02*
X373300D01*
G01D02*
Y307100D01*
G01X358800Y381100D02*
Y385500D01*
G01X360100Y381200D02*
X364500D01*
G01X360100Y390200D02*
Y381200D01*
G01X364500D02*
Y390200D01*
G01X358800Y401000D02*
Y405400D01*
G01Y396500D02*
Y400900D01*
G01X364500Y390200D02*
X360100D01*
G01X358800Y405500D02*
Y409900D01*
G01X361800Y417500D02*
Y421900D01*
G01X412976Y71461D02*
X383024D01*
G01D02*
Y93539D01*
G01X379200Y85000D02*
Y94000D01*
G01X383024Y93539D02*
X412976D01*
G01X384500Y94800D02*
X393500D01*
G01Y99200D02*
X384500D01*
G01D02*
Y94800D01*
G01X383500D02*
Y99200D01*
G01X382700Y102300D02*
Y109700D01*
G01X384224Y128224D02*
Y220776D01*
G01X476776Y128224D02*
X384224D01*
G01Y220776D02*
X476776D01*
G01X389700Y248600D02*
X394100D01*
G01X389700Y257600D02*
Y248600D01*
G01X388200D02*
Y257600D01*
G01X383800Y248600D02*
X388200D01*
G01X383800Y257600D02*
Y248600D01*
G01X382300D02*
Y257600D01*
G01X377900Y248600D02*
X382300D01*
G01X377900Y257600D02*
Y248600D01*
G01X378200Y236000D02*
Y245000D01*
G01X376209Y252850D02*
Y261150D01*
G01X394100Y257600D02*
X389700D01*
G01X390200Y265800D02*
X399200D01*
G01X390200Y270200D02*
Y265800D01*
G01X379200Y270200D02*
Y265800D01*
G01D02*
X388200D01*
G01D02*
Y270200D01*
G01Y257600D02*
X383800D01*
G01X382300D02*
X377900D01*
G01X377500Y282500D02*
X381900D01*
G01X377500Y291500D02*
Y282500D01*
G01X381900D02*
Y291500D01*
G01X376600Y277500D02*
Y289900D01*
G01X392557Y275650D02*
Y279150D01*
G01D02*
X397843D01*
G01Y275650D02*
X392557D01*
G01X379200Y279700D02*
Y275300D01*
G01X388200Y279700D02*
X379200D01*
G01Y275300D02*
X388200D01*
G01D02*
Y279700D01*
G01X399200Y270200D02*
X390200D01*
G01Y274700D02*
Y270300D01*
G01X399200Y274700D02*
X390200D01*
G01Y270300D02*
X399200D01*
G01X388200Y270200D02*
X379200D01*
G01Y274700D02*
Y270300D01*
G01X388200Y274700D02*
X379200D01*
G01Y270300D02*
X388200D01*
G01D02*
Y274700D01*
G01X381900Y294500D02*
Y303500D01*
G01X377500Y294500D02*
X381900D01*
G01X377500Y303500D02*
Y294500D01*
G01X381900Y291500D02*
X377500D01*
G01X376900Y292300D02*
Y304700D01*
G01X384196Y285483D02*
Y303517D01*
G01X398204Y285483D02*
X384196D01*
G01X386700Y311400D02*
Y307000D01*
G01X395700Y311400D02*
X386700D01*
G01Y307000D02*
X395700D01*
G01X381900Y303500D02*
X377500D01*
G01X376900Y311400D02*
Y307000D01*
G01X385900Y311400D02*
X376900D01*
G01Y307000D02*
X385900D01*
G01D02*
Y311400D01*
G01X381500Y319193D02*
Y342807D01*
G01X384196Y303517D02*
X398204D01*
G01X384800Y340000D02*
X389200D01*
G01X384800Y349000D02*
Y340000D01*
G01X389200Y349000D02*
X384800D01*
G01X389200Y340000D02*
Y349000D01*
G01X392669Y350240D02*
X403331D01*
G01X392669Y338360D02*
Y350240D01*
G01X403331Y338360D02*
X392669D01*
G01X381500Y378800D02*
X390500D01*
G01X381500Y383200D02*
Y378800D01*
G01X390500Y383200D02*
X381500D01*
G01X390500Y378800D02*
Y383200D01*
G01X381500Y373600D02*
X390500D01*
G01X381500Y378000D02*
Y373600D01*
G01X390500Y378000D02*
X381500D01*
G01X390500Y373600D02*
Y378000D01*
G01X393500Y94800D02*
Y99200D01*
G01X403200Y100500D02*
Y109500D01*
G01D02*
X398800D01*
G01D02*
Y100500D01*
G01D02*
X403200D01*
G01X407700D02*
Y109500D01*
G01D02*
X403300D01*
G01D02*
Y100500D01*
G01D02*
X407700D01*
G01X403500Y94800D02*
X412500D01*
G01Y99200D02*
X403500D01*
G01D02*
Y94800D01*
G01X403000D02*
Y99200D01*
G01D02*
X394000D01*
G01D02*
Y94800D01*
G01D02*
X403000D01*
G01X405900Y248600D02*
Y257600D01*
G01X401500Y248600D02*
X405900D01*
G01X401500Y257600D02*
Y248600D01*
G01X394100D02*
Y257600D01*
G01X400000Y248600D02*
Y257600D01*
G01X395600Y248600D02*
X400000D01*
G01X395600Y257600D02*
Y248600D01*
G01X407100D02*
X411500D01*
G01X407100Y257600D02*
Y248600D01*
G01X405900Y257600D02*
X401500D01*
G01X400000D02*
X395600D01*
G01X399200Y265800D02*
Y270200D01*
G01X411500Y257600D02*
X407100D01*
G01X410500Y281800D02*
X422900D01*
G01X410500Y289200D02*
Y281800D01*
G01X397843Y279150D02*
Y275650D01*
G01X399200Y270300D02*
Y274700D01*
G01X422900Y289200D02*
X410500D01*
G01Y289900D02*
X422900D01*
G01X410500Y297300D02*
Y289900D01*
G01X422900Y297300D02*
X410500D01*
G01X398204Y303517D02*
Y285483D01*
G01X395700Y307000D02*
Y311400D01*
G01X399950Y311643D02*
Y306357D01*
G01X396450Y311643D02*
X399950D01*
G01X396450Y306357D02*
Y311643D01*
G01X399950Y306357D02*
X396450D01*
G01X394900Y331300D02*
Y326900D01*
G01X403900Y331300D02*
X394900D01*
G01Y326900D02*
X403900D01*
G01D02*
Y331300D01*
G01X394900Y326100D02*
Y321700D01*
G01X403900Y326100D02*
X394900D01*
G01Y321700D02*
X403900D01*
G01D02*
Y326100D01*
G01X405800Y340500D02*
X410200D01*
G01X405800Y349500D02*
Y340500D01*
G01X410200Y349500D02*
X405800D01*
G01X410200Y340500D02*
Y349500D01*
G01X403331Y350240D02*
Y338360D01*
G01X399450Y356650D02*
Y378350D01*
G01X431550Y356650D02*
X399450D01*
G01X401440Y386240D02*
X427360D01*
G01X401440Y412160D02*
Y386240D01*
G01X399450Y378350D02*
X431550D01*
G01X427360Y412160D02*
X401440D01*
G01X412976Y93539D02*
Y71461D01*
G01X422700Y85500D02*
Y94500D01*
G01X418300Y85500D02*
X422700D01*
G01X418300Y94500D02*
Y85500D01*
G01X425361Y79004D02*
Y93996D01*
G01X447439Y79004D02*
X425361D01*
G01X422700Y94500D02*
X418300D01*
G01X412500Y94800D02*
Y99200D01*
G01X425361Y93996D02*
X447439D01*
G01X411500Y248600D02*
Y257600D01*
G01X423100Y248600D02*
Y257600D01*
G01X418700Y248600D02*
X423100D01*
G01X418700Y257600D02*
Y248600D01*
G01X417200D02*
Y257600D01*
G01X412800Y248600D02*
X417200D01*
G01X412800Y257600D02*
Y248600D01*
G01X423100Y257600D02*
X418700D01*
G01X417200D02*
X412800D01*
G01X412100Y277000D02*
X421100D01*
G01X412100Y281400D02*
Y277000D01*
G01X421100Y281400D02*
X412100D01*
G01X421100Y277000D02*
Y281400D01*
G01X422900Y281800D02*
Y289200D01*
G01X426575Y280579D02*
Y294506D01*
G01X444625Y280579D02*
X426575D01*
G01X422900Y289900D02*
Y297300D01*
G01X426575Y294506D02*
X444625D01*
G01X412850Y304750D02*
Y326450D01*
G01X444950Y304750D02*
X412850D01*
G01Y326450D02*
X444950D01*
G01X422831Y338560D02*
X412169D01*
G01D02*
Y350440D01*
G01D02*
X422831D01*
G01D02*
Y338560D01*
G01X427360Y386240D02*
Y412160D01*
G01X434700Y100700D02*
X439100D01*
G01X434700Y109700D02*
Y100700D01*
G01X439100Y109700D02*
X434700D01*
G01X439100Y100700D02*
Y109700D01*
G01X439200Y100700D02*
X443600D01*
G01X439200Y109700D02*
Y100700D01*
G01X443600Y109700D02*
X439200D01*
G01X443600Y100700D02*
Y109700D01*
G01X429800Y95100D02*
X438800D01*
G01X429800Y99500D02*
Y95100D01*
G01X438800Y99500D02*
X429800D01*
G01X438800Y95100D02*
Y99500D01*
G01X439400D02*
Y95100D01*
G01X448400Y99500D02*
X439400D01*
G01Y95100D02*
X448400D01*
G01X430050Y110100D02*
X439050D01*
G01X430050Y114500D02*
Y110100D01*
G01X439050D02*
Y114500D01*
G01X439250D02*
Y110100D01*
G01D02*
X448250D01*
G01X439050Y114500D02*
X430050D01*
G01X448250D02*
X439250D01*
G01X441700Y248500D02*
X437300D01*
G01X441700Y239500D02*
Y248500D01*
G01X437300Y239500D02*
X441700D01*
G01X437300Y248500D02*
Y239500D01*
G01X441800D02*
X446200D01*
G01X441800Y248500D02*
Y239500D01*
G01X446200Y248500D02*
X441800D01*
G01X441200Y267500D02*
Y276500D01*
G01X436800Y267500D02*
X441200D01*
G01X436800Y276500D02*
Y267500D01*
G01X441800Y264300D02*
X449200D01*
G01X441800Y276700D02*
Y264300D01*
G01X441200Y276500D02*
X436800D01*
G01X449200Y276700D02*
X441800D01*
G01X444625Y294506D02*
Y280579D01*
G01X444950Y326450D02*
Y304750D01*
G01X436200Y352000D02*
X431800D01*
G01Y343000D02*
X436200D01*
G01X431800Y352000D02*
Y343000D01*
G01X436200D02*
Y352000D01*
G01X450200Y349400D02*
X444250D01*
G01D02*
Y353900D01*
G01D02*
X442750D01*
G01D02*
Y349400D01*
G01D02*
X436800D01*
G01D02*
Y361100D01*
G01X436000Y376700D02*
Y372300D01*
G01X445000D02*
Y376700D01*
G01X436000Y372300D02*
X445000D01*
G01X436000Y372200D02*
Y367800D01*
G01X445000Y372200D02*
X436000D01*
G01X445000Y367800D02*
Y372200D01*
G01X436000Y367800D02*
X445000D01*
G01X436800Y361100D02*
X440550D01*
G01D02*
Y365600D01*
G01D02*
X446450D01*
G01X431550Y378350D02*
Y356650D01*
G01X436000Y381200D02*
Y376800D01*
G01X445000Y381200D02*
X436000D01*
G01X445000Y376800D02*
Y381200D01*
G01X436000Y376800D02*
X445000D01*
G01X433000Y389300D02*
X442000D01*
G01X433000Y393700D02*
Y389300D01*
G01X442000D02*
Y393700D01*
G01X433000Y384300D02*
X442000D01*
G01X433000Y388700D02*
Y384300D01*
G01X442000Y388700D02*
X433000D01*
G01X442000Y384300D02*
Y388700D01*
G01X445000Y376700D02*
X436000D01*
G01X433000Y398700D02*
Y394300D01*
G01X442000Y398700D02*
X433000D01*
G01Y394300D02*
X442000D01*
G01D02*
Y398700D01*
G01X433000Y403700D02*
Y399300D01*
G01X442000Y403700D02*
X433000D01*
G01Y399300D02*
X442000D01*
G01D02*
Y403700D01*
G01Y393700D02*
X433000D01*
G01Y404300D02*
X442000D01*
G01X433000Y408700D02*
Y404300D01*
G01X442000D02*
Y408700D01*
G01D02*
X433000D01*
G01Y409300D02*
X442000D01*
G01X433000Y413700D02*
Y409300D01*
G01X442000Y413700D02*
X433000D01*
G01X442000Y409300D02*
Y413700D01*
G01X447439Y93996D02*
Y79004D01*
G01X448400Y95100D02*
Y99500D01*
G01X448250Y110100D02*
Y114500D01*
G01X460700Y120500D02*
X456300D01*
G01X460700Y111500D02*
Y120500D01*
G01X456300Y111500D02*
X460700D01*
G01X456300Y120500D02*
Y111500D01*
G01X455200Y120500D02*
X450800D01*
G01Y111500D02*
X455200D01*
G01X450800Y120500D02*
Y111500D01*
G01X455200D02*
Y120500D01*
G01X451300Y230000D02*
X455700D01*
G01X451300Y239000D02*
Y230000D01*
G01X455700D02*
Y239000D01*
G01X462800Y227500D02*
X467200D01*
G01X462800Y236500D02*
Y227500D01*
G01X446200Y239500D02*
Y248500D01*
G01X455300Y239500D02*
X459700D01*
G01X455300Y248500D02*
Y239500D01*
G01X459700Y248500D02*
X455300D01*
G01X459700Y239500D02*
Y248500D01*
G01X446300Y239500D02*
X450700D01*
G01X446300Y248500D02*
Y239500D01*
G01X450700Y248500D02*
X446300D01*
G01X450700Y239500D02*
Y248500D01*
G01X455700Y239000D02*
X451300D01*
G01X450800Y239500D02*
X455200D01*
G01X450800Y248500D02*
Y239500D01*
G01X455200Y248500D02*
X450800D01*
G01X455200Y239500D02*
Y248500D01*
G01X459800Y239500D02*
X464200D01*
G01X459800Y248500D02*
Y239500D01*
G01X464200Y248500D02*
X459800D01*
G01X467200Y236500D02*
X462800D01*
G01X449200Y264300D02*
Y276700D01*
G01X450000Y286700D02*
Y282300D01*
G01D02*
X459000D01*
G01D02*
Y286700D01*
G01X450000Y291700D02*
Y287300D01*
G01X459000Y291700D02*
X450000D01*
G01Y287300D02*
X459000D01*
G01D02*
Y291700D01*
G01X450000Y296700D02*
Y292300D01*
G01X459000Y296700D02*
X450000D01*
G01Y292300D02*
X459000D01*
G01D02*
Y296700D01*
G01X450000Y297300D02*
X459000D01*
G01X450000Y301700D02*
Y297300D01*
G01X459000Y301700D02*
X450000D01*
G01X459000Y297300D02*
Y301700D01*
G01Y286700D02*
X450000D01*
G01X448800Y319800D02*
X457800D01*
G01X448800Y324200D02*
Y319800D01*
G01X457800D02*
Y324200D01*
G01X448500Y329200D02*
Y324800D01*
G01X457500Y329200D02*
X448500D01*
G01Y324800D02*
X457500D01*
G01D02*
Y329200D01*
G01X457800Y324200D02*
X448800D01*
G01X450200Y361100D02*
Y349400D01*
G01X446450Y365600D02*
Y361100D01*
G01D02*
X450200D01*
G01X450800Y382500D02*
X455200D01*
G01X450800Y391500D02*
Y382500D01*
G01X455200D02*
Y391500D01*
G01X455900Y389000D02*
X468300D01*
G01X455900Y396400D02*
Y389000D01*
G01X457300Y388800D02*
X467700D01*
G01X457300Y383200D02*
Y388800D01*
G01X467700Y383200D02*
X457300D01*
G01X455200Y391500D02*
X450800D01*
G01X468300Y396400D02*
X455900D01*
G01X467000Y88700D02*
Y84300D01*
G01X476000Y88700D02*
X467000D01*
G01Y84300D02*
X476000D01*
G01D02*
Y88700D01*
G01X467000Y80700D02*
Y76300D01*
G01X476000Y80700D02*
X467000D01*
G01Y76300D02*
X476000D01*
G01D02*
Y80700D01*
G01X467000Y93700D02*
Y89300D01*
G01D02*
X476000D01*
G01Y93700D02*
X467000D01*
G01X476000Y89300D02*
Y93700D01*
G01X467000Y98700D02*
Y94300D01*
G01X476000Y98700D02*
X467000D01*
G01Y94300D02*
X476000D01*
G01D02*
Y98700D01*
G01X476776Y220776D02*
Y128224D01*
G01X467200Y227500D02*
Y236500D01*
G01X464200Y239500D02*
Y248500D01*
G01X467800Y240400D02*
Y257400D01*
G01X480200Y240400D02*
X467800D01*
G01X480200Y257400D02*
Y240400D01*
G01X467800Y257400D02*
X480200D01*
G01X475700Y348000D02*
Y357000D01*
G01X471300Y348000D02*
X475700D01*
G01X471300Y357000D02*
Y348000D01*
G01X476300D02*
X480700D01*
G01X476300Y357000D02*
Y348000D01*
G01X475700Y357000D02*
X471300D01*
G01X480700D02*
X476300D01*
G01X496949Y361191D02*
X473256D01*
G01D02*
Y396841D01*
G01X468300Y389000D02*
Y396400D01*
G01X467700Y388800D02*
Y383200D01*
G01X473256Y396841D02*
X496949D01*
G01X484450Y72150D02*
Y93850D01*
G01X516550Y72150D02*
X484450D01*
G01Y93850D02*
X516550D01*
G01X490400Y122700D02*
X502800D01*
G01X490400Y130100D02*
Y122700D01*
G01X502800Y130100D02*
X490400D01*
G01X493500Y136300D02*
X502500D01*
G01X493500Y140700D02*
Y136300D01*
G01X502500Y140700D02*
X493500D01*
G01Y145200D02*
Y140800D01*
G01D02*
X502500D01*
G01Y145200D02*
X493500D01*
G01Y131300D02*
X502500D01*
G01X493500Y135700D02*
Y131300D01*
G01X502500Y135700D02*
X493500D01*
G01X486000Y160800D02*
X495000D01*
G01X486000Y165200D02*
Y160800D01*
G01X495000D02*
Y165200D01*
G01X486000Y165300D02*
X495000D01*
G01X486000Y169700D02*
Y165300D01*
G01X495000Y169700D02*
X486000D01*
G01X495000Y165300D02*
Y169700D01*
G01Y165200D02*
X486000D01*
G01Y174300D02*
X495000D01*
G01X486000Y178700D02*
Y174300D01*
G01X495000Y178700D02*
X486000D01*
G01X495000Y174300D02*
Y178700D01*
G01X486000Y174200D02*
Y169800D01*
G01X495000Y174200D02*
X486000D01*
G01Y169800D02*
X495000D01*
G01D02*
Y174200D01*
G01X486000Y195300D02*
X495000D01*
G01X486000Y199700D02*
Y195300D01*
G01X495000D02*
Y199700D01*
G01X486000Y209300D02*
X495000D01*
G01X486000Y213700D02*
Y209300D01*
G01X495000Y213700D02*
X486000D01*
G01X495000Y209300D02*
Y213700D01*
G01X486000Y200300D02*
X495000D01*
G01X486000Y204700D02*
Y200300D01*
G01X495000Y204700D02*
X486000D01*
G01X495000Y200300D02*
Y204700D01*
G01Y199700D02*
X486000D01*
G01Y204800D02*
X495000D01*
G01X486000Y209200D02*
Y204800D01*
G01X495000Y209200D02*
X486000D01*
G01X495000Y204800D02*
Y209200D01*
G01X496100Y244100D02*
X490500D01*
G01X496100Y254500D02*
Y244100D01*
G01X490500D02*
Y254500D01*
G01X493900Y266200D02*
X498300D01*
G01X493900Y275200D02*
Y266200D01*
G01X493800Y257000D02*
X498200D01*
G01X493800Y266000D02*
Y257000D01*
G01X498200Y266000D02*
X493800D01*
G01X486700Y266200D02*
X491100D01*
G01X486700Y275200D02*
Y266200D01*
G01X491100D02*
Y275200D01*
G01X490500Y254500D02*
X496100D01*
G01X498300Y275200D02*
X493900D01*
G01X493657Y279450D02*
X498943D01*
G01X493657Y275950D02*
Y279450D01*
G01X498943Y275950D02*
X493657D01*
G01X491100Y275200D02*
X486700D01*
G01X507294Y309646D02*
G02I-13200J0D01*
G01X486300Y357000D02*
Y348000D01*
G01D02*
X490700D01*
G01D02*
Y357000D01*
G01X485700Y348000D02*
Y357000D01*
G01X481300Y348000D02*
X485700D01*
G01X481300Y357000D02*
Y348000D01*
G01X480700D02*
Y357000D01*
G01X496300Y348000D02*
X500700D01*
G01X496300Y357000D02*
Y348000D01*
G01X491300D02*
X495700D01*
G01X491300Y357000D02*
Y348000D01*
G01X495700D02*
Y357000D01*
G01X490700D02*
X486300D01*
G01X485700D02*
X481300D01*
G01X500700D02*
X496300D01*
G01X495700D02*
X491300D01*
G01X496949Y396841D02*
Y361191D01*
G01X507294Y412008D02*
G02I-13200J0D01*
G01X502800Y122700D02*
Y130100D01*
G01X502500Y136300D02*
Y140700D01*
G01Y140800D02*
Y145200D01*
G01Y131300D02*
Y135700D01*
G01X499000Y249600D02*
Y245200D01*
G01X508000Y249600D02*
X499000D01*
G01Y245200D02*
X508000D01*
G01D02*
Y249600D01*
G01X513300Y248400D02*
X525700D01*
G01X513300Y255800D02*
Y248400D01*
G01X498500Y257100D02*
Y249700D01*
G01D02*
X510900D01*
G01D02*
Y257100D01*
G01X501800Y261900D02*
Y257500D01*
G01X510800Y261900D02*
X501800D01*
G01Y257500D02*
X510800D01*
G01D02*
Y261900D01*
G01X513800Y257000D02*
X522800D01*
G01X513800Y261400D02*
Y257000D01*
G01X522800Y261400D02*
X513800D01*
G01X498300Y266200D02*
Y275200D01*
G01X525700Y255800D02*
X513300D01*
G01X510900Y257100D02*
X498500D01*
G01X498200Y257000D02*
Y266000D01*
G01X519817Y263696D02*
X501783D01*
G01D02*
Y277704D01*
G01X498943Y279450D02*
Y275950D01*
G01X501783Y277704D02*
X519817D01*
G01X500700Y348000D02*
Y357000D01*
G01X506500Y375300D02*
X515500D01*
G01X506500Y379700D02*
Y375300D01*
G01X515500Y379700D02*
X506500D01*
G01X501300Y380800D02*
X508700D01*
G01X501300Y393200D02*
Y380800D01*
G01X508700D02*
Y393200D01*
G01X514800Y382800D02*
X509200D01*
G01X514800Y393200D02*
Y382800D01*
G01X509200D02*
Y393200D01*
G01X508700D02*
X501300D01*
G01X509200D02*
X514800D01*
G01X522500Y73800D02*
X531500D01*
G01X522500Y78200D02*
Y73800D01*
G01X531500D02*
Y78200D01*
G01X516550Y93850D02*
Y72150D01*
G01X522500Y94200D02*
Y89800D01*
G01D02*
X531500D01*
G01D02*
Y94200D01*
G01Y78200D02*
X522500D01*
G01Y79800D02*
X531500D01*
G01X522500Y84200D02*
Y79800D01*
G01X531500Y84200D02*
X522500D01*
G01X531500Y79800D02*
Y84200D01*
G01X522500Y84800D02*
X531500D01*
G01X522500Y89200D02*
Y84800D01*
G01X531500Y89200D02*
X522500D01*
G01X531500Y84800D02*
Y89200D01*
G01Y94200D02*
X522500D01*
G01X517800Y127700D02*
Y120300D01*
G01D02*
X530200D01*
G01Y127700D02*
X517800D01*
G01X530200Y120300D02*
Y127700D01*
G01X533000Y128300D02*
X516000D01*
G01D02*
Y140700D01*
G01X533000Y140800D02*
X516000D01*
G01D02*
Y153200D01*
G01Y140700D02*
X533000D01*
G01X516000Y153200D02*
X533000D01*
G01Y153300D02*
X516000D01*
G01D02*
Y165700D01*
G01X531300Y175800D02*
X538700D01*
G01X531300Y188200D02*
Y175800D01*
G01X516000Y165700D02*
X533000D01*
G01X515800Y169700D02*
Y175300D01*
G01X526200Y169700D02*
X515800D01*
G01Y175300D02*
X526200D01*
G01D02*
Y169700D01*
G01X538700Y188200D02*
X531300D01*
G01X535300Y230400D02*
X530900D01*
G01Y221400D02*
X535300D01*
G01X530900Y230400D02*
Y221400D01*
G01X525700Y248400D02*
Y255800D01*
G01X522800Y257000D02*
Y261400D01*
G01X525600Y258700D02*
X530000D01*
G01X525600Y267700D02*
Y258700D01*
G01X530000D02*
Y267700D01*
G01D02*
X525600D01*
G01X530600Y258700D02*
X535000D01*
G01X530600Y267700D02*
Y258700D01*
G01X535000Y267700D02*
X530600D01*
G01X519817Y277704D02*
Y263696D01*
G01X530643Y270750D02*
X525357D01*
G01X530643Y274250D02*
Y270750D01*
G01X525357Y274250D02*
X530643D01*
G01X525357Y270750D02*
Y274250D01*
G01X529200Y283500D02*
X524800D01*
G01X529200Y274500D02*
Y283500D01*
G01X524800Y274500D02*
X529200D01*
G01X524800Y283500D02*
Y274500D01*
G01X529300D02*
X533700D01*
G01X529300Y283500D02*
Y274500D01*
G01X533700Y283500D02*
X529300D01*
G01X560792Y317356D02*
X523408D01*
G01D02*
Y343844D01*
G01X519752Y335568D02*
Y340568D01*
G01X517252Y338068D02*
X522252D01*
G01X523408Y343844D02*
X560792D01*
G01X521700Y364300D02*
X529100D01*
G01X521700Y376700D02*
Y364300D01*
G01X529100D02*
Y376700D01*
G01X529900Y364300D02*
X537300D01*
G01X529900Y376700D02*
Y364300D01*
G01X515500Y375300D02*
Y379700D01*
G01X526900Y379000D02*
X539300D01*
G01X526900Y386400D02*
Y379000D01*
G01X539300Y386400D02*
X526900D01*
G01X529100Y376700D02*
X521700D01*
G01X537300D02*
X529900D01*
G01X528900Y387400D02*
Y393000D01*
G01X539300Y387400D02*
X528900D01*
G01X529600Y397900D02*
Y393500D01*
G01X538600Y397900D02*
X529600D01*
G01Y393500D02*
X538600D01*
G01X528900Y393000D02*
X539300D01*
G01X523000Y423201D02*
Y428201D01*
G01X525528Y423503D02*
X531072D01*
G01D02*
Y412499D01*
G01D02*
X525528D01*
G01D02*
Y423503D01*
G01X525500Y425701D02*
X520500D01*
G01X547643Y65250D02*
Y61750D01*
G01D02*
X542357D01*
G01D02*
Y65250D01*
G01D02*
X547643D01*
G01X538000Y71200D02*
Y66800D01*
G01X547000Y71200D02*
X538000D01*
G01Y66800D02*
X547000D01*
G01D02*
Y71200D01*
G01X545500Y90000D02*
Y82600D01*
G01X557900Y90000D02*
X545500D01*
G01Y82600D02*
X557900D01*
G01X533000Y140700D02*
Y128300D01*
G01Y153200D02*
Y140800D01*
G01X535300Y156800D02*
X542700D01*
G01X535300Y169200D02*
Y156800D01*
G01X542700D02*
Y169200D01*
G01X533000Y165700D02*
Y153300D01*
G01X538800Y177000D02*
X543200D01*
G01X538800Y186000D02*
Y177000D01*
G01X543200D02*
Y186000D01*
G01X538700Y175800D02*
Y188200D01*
G01X542700Y169200D02*
X535300D01*
G01X545117Y166272D02*
Y201329D01*
G01X574283Y166272D02*
X545117D01*
G01X543200Y186000D02*
X538800D01*
G01X547200Y206500D02*
Y215500D01*
G01X542800Y206500D02*
X547200D01*
G01X542800Y215500D02*
Y206500D01*
G01X547200Y215500D02*
X542800D01*
G01X534800Y202800D02*
X542200D01*
G01X534800Y215200D02*
Y202800D01*
G01X542200Y215200D02*
X534800D01*
G01X542200Y202800D02*
Y215200D01*
G01X566196Y206838D02*
X548804D01*
G01D02*
Y224196D01*
G01X545117Y201329D02*
X574283D01*
G01X535300Y221400D02*
Y230400D01*
G01X552750Y231357D02*
X549250D01*
G01D02*
Y236643D01*
G01X548700Y230000D02*
Y239000D01*
G01X544300Y230000D02*
X548700D01*
G01X544300Y239000D02*
Y230000D01*
G01X548804Y224196D02*
X566196D01*
G01X536700Y230800D02*
X542300D01*
G01X536700Y220400D02*
Y230800D01*
G01X542300Y220400D02*
X536700D01*
G01X542300Y230800D02*
Y220400D01*
G01X549250Y236643D02*
X552750D01*
G01X548700Y239000D02*
X544300D01*
G01X542550Y256900D02*
Y307300D01*
G01X579050Y256900D02*
X542550D01*
G01X535000Y258700D02*
Y267700D01*
G01X533700Y274500D02*
Y283500D01*
G01X542550Y307300D02*
X579050D01*
G01X545400Y354100D02*
Y359700D01*
G01X555800Y354100D02*
X545400D01*
G01X537300Y364300D02*
Y376700D01*
G01X544579Y360744D02*
Y386656D01*
G01X562621Y360744D02*
X544579D01*
G01X545400Y359700D02*
X555800D01*
G01X539300Y379000D02*
Y386400D01*
G01X552243Y389450D02*
X546957D01*
G01D02*
Y392950D01*
G01X544579Y386656D02*
X562621D01*
G01X539300Y393000D02*
Y387400D01*
G01X546957Y392950D02*
X552243D01*
G01X546276Y416329D02*
Y405325D01*
G01D02*
X540732D01*
G01D02*
Y416329D01*
G01X544043Y394500D02*
X553043D01*
G01X544043Y398900D02*
Y394500D01*
G01X553043Y398900D02*
X544043D01*
G01X538600Y393500D02*
Y397900D01*
G01X553015Y417527D02*
X548015D01*
G01X540732Y419104D02*
Y430108D01*
G01X546276Y419104D02*
X540732D01*
G01X546276Y430108D02*
Y419104D01*
G01X538704Y416527D02*
X533704D01*
G01X536204Y414027D02*
Y419027D01*
G01X540732Y416329D02*
X546276D01*
G01X553515Y432306D02*
X548515D01*
G01X538704Y429806D02*
Y434806D01*
G01X541204Y432306D02*
X536204D01*
G01X540732Y430108D02*
X546276D01*
G01X571517Y60896D02*
X553483D01*
G01Y74904D02*
X571517D01*
G01X553483Y60896D02*
Y74904D01*
G01X566200Y92000D02*
Y101000D01*
G01X561800Y92000D02*
X566200D01*
G01X561800Y101000D02*
Y92000D01*
G01X562500Y77000D02*
X571500D01*
G01X562500Y81400D02*
Y77000D01*
G01X571500Y81400D02*
X562500D01*
G01X550300D02*
Y77000D01*
G01X559300Y81400D02*
X550300D01*
G01Y77000D02*
X559300D01*
G01D02*
Y81400D01*
G01X553800Y90300D02*
X561200D01*
G01X553800Y102700D02*
Y90300D01*
G01X561200D02*
Y102700D01*
G01X560300Y82200D02*
X572700D01*
G01X560300Y89600D02*
Y82200D01*
G01X572700Y89600D02*
X560300D01*
G01X557900Y82600D02*
Y90000D01*
G01X567200Y90800D02*
Y101200D01*
G01X572800Y90800D02*
X567200D01*
G01X566200Y101000D02*
X561800D01*
G01X561200Y102700D02*
X553800D01*
G01X567200Y101200D02*
X572800D01*
G01X562800Y164700D02*
Y157300D01*
G01D02*
X575200D01*
G01Y164700D02*
X562800D01*
G01X566196Y224196D02*
Y206838D01*
G01X553300Y230000D02*
X557700D01*
G01X553300Y239000D02*
Y230000D01*
G01X557700D02*
Y239000D01*
G01X557800Y230000D02*
X562200D01*
G01X557800Y239000D02*
Y230000D01*
G01X562200D02*
Y239000D01*
G01X565750Y231357D02*
X562250D01*
G01D02*
Y236643D01*
G01X565750D02*
Y231357D01*
G01X552750Y236643D02*
Y231357D01*
G01X557700Y239000D02*
X553300D01*
G01X562200D02*
X557800D01*
G01X562250Y236643D02*
X565750D01*
G01X563000Y242200D02*
Y237800D01*
G01X572000Y242200D02*
X563000D01*
G01Y237800D02*
X572000D01*
G01X560792Y343844D02*
Y317356D01*
G01X557100Y359100D02*
Y354700D01*
G01D02*
X566100D01*
G01D02*
Y359100D01*
G01X555800Y359700D02*
Y354100D01*
G01X566100Y359100D02*
X557100D01*
G01X562621Y386656D02*
Y360744D01*
G01X552243Y392950D02*
Y389450D01*
G01X553500Y393700D02*
Y389300D01*
G01D02*
X562500D01*
G01D02*
Y393700D01*
G01X564354Y405325D02*
Y416329D01*
G01X569898Y405325D02*
X564354D01*
G01X552543D02*
Y416329D01*
G01X558087Y405325D02*
X552543D01*
G01X558087Y416329D02*
Y405325D01*
G01X562500Y393700D02*
X553500D01*
G01X553043Y394500D02*
Y398900D01*
G01X553500Y393800D02*
X562500D01*
G01X553500Y398200D02*
Y393800D01*
G01X562500Y398200D02*
X553500D01*
G01X562500Y393800D02*
Y398200D01*
G01X552543Y419104D02*
Y430108D01*
G01X558087Y419104D02*
X552543D01*
G01X558087Y430108D02*
Y419104D01*
G01X561826Y415027D02*
Y420027D01*
G01X564326Y417527D02*
X559326D01*
G01X564354Y416329D02*
X569898D01*
G01X550515Y415027D02*
Y420027D01*
G01X552543Y416329D02*
X558087D01*
G01X564354Y419104D02*
Y430108D01*
G01X569898Y419104D02*
X564354D01*
G01X551015Y429806D02*
Y434806D01*
G01X552543Y430108D02*
X558087D01*
G01X564826Y432306D02*
X559826D01*
G01X562326Y429806D02*
Y434806D01*
G01X564354Y430108D02*
X569898D01*
G01X579400Y72400D02*
X575000D01*
G01Y63400D02*
X579400D01*
G01X575000Y72400D02*
Y63400D01*
G01X579400D02*
Y72400D01*
G01X579643Y59150D02*
X574357D01*
G01Y62650D02*
X579643D01*
G01X574357Y59150D02*
Y62650D01*
G01X579643D02*
Y59150D01*
G01X575300Y73000D02*
X579700D01*
G01X575300Y82000D02*
Y73000D01*
G01X579700D02*
Y82000D01*
G01X571517Y74904D02*
Y60896D01*
G01X571500Y77000D02*
Y81400D01*
G01X572700Y82200D02*
Y89600D01*
G01X579700Y82000D02*
X575300D01*
G01X572800Y101200D02*
Y90800D01*
G01X575200Y157300D02*
Y164700D01*
G01X574283Y201329D02*
Y166272D01*
G01X572200Y208500D02*
Y217500D01*
G01X567800Y208500D02*
X572200D01*
G01X567800Y217500D02*
Y208500D01*
G01X572300Y205800D02*
X579700D01*
G01X572300Y218200D02*
Y205800D01*
G01X579700D02*
Y218200D01*
G01X572200Y217500D02*
X567800D01*
G01X579700Y218200D02*
X572300D01*
G01X571250Y237143D02*
Y231857D01*
G01D02*
X567750D01*
G01D02*
Y237143D01*
G01X573200Y230000D02*
X577600D01*
G01X573200Y239000D02*
Y230000D01*
G01X577600D02*
Y239000D01*
G01X570500Y226700D02*
Y222300D01*
G01X579500Y226700D02*
X570500D01*
G01Y222300D02*
X579500D01*
G01D02*
Y226700D01*
G01X567750Y237143D02*
X571250D01*
G01X577600Y239000D02*
X573200D01*
G01X572000Y237800D02*
Y242200D01*
G01X579050Y307300D02*
Y256900D01*
G01X661787Y322071D02*
X582579D01*
G01D02*
Y379897D01*
G01X569600Y358900D02*
Y354500D01*
G01D02*
X578600D01*
G01D02*
Y358900D01*
G01X569600Y353900D02*
Y349500D01*
G01X578600Y353900D02*
X569600D01*
G01Y349500D02*
X578600D01*
G01D02*
Y353900D01*
G01X569600Y344500D02*
X578600D01*
G01X569600Y348900D02*
Y344500D01*
G01X578600Y348900D02*
X569600D01*
G01X578600Y344500D02*
Y348900D01*
G01Y358900D02*
X569600D01*
G01X574743Y372950D02*
Y369450D01*
G01D02*
X569457D01*
G01D02*
Y372950D01*
G01X569600Y364500D02*
X578600D01*
G01X569600Y368900D02*
Y364500D01*
G01X578600Y368900D02*
X569600D01*
G01X578600Y364500D02*
Y368900D01*
G01X569600Y359500D02*
X578600D01*
G01X569600Y363900D02*
Y359500D01*
G01X578600Y363900D02*
X569600D01*
G01X578600Y359500D02*
Y363900D01*
G01X569600Y387900D02*
Y383500D01*
G01X578600Y387900D02*
X569600D01*
G01Y383500D02*
X578600D01*
G01D02*
Y387900D01*
G01X569600Y382900D02*
Y378500D01*
G01X578600Y382900D02*
X569600D01*
G01Y378500D02*
X578600D01*
G01D02*
Y382900D01*
G01X569457Y372950D02*
X574743D01*
G01X569600Y388500D02*
X578600D01*
G01X569600Y392900D02*
Y388500D01*
G01X578600D02*
Y392900D01*
G01X569600Y373500D02*
X578600D01*
G01X569600Y377900D02*
Y373500D01*
G01X578600Y377900D02*
X569600D01*
G01X578600Y373500D02*
Y377900D01*
G01X582579Y379897D02*
X661787D01*
G01X569898Y416329D02*
Y405325D01*
G01X576165D02*
Y416329D01*
G01X581709Y405325D02*
X576165D01*
G01X581709Y416329D02*
Y405325D01*
G01X578600Y392900D02*
X569600D01*
G01X573637Y414527D02*
Y419527D01*
G01X576137Y417027D02*
X571137D01*
G01X576165Y416329D02*
X581709D01*
G01X576165Y419104D02*
Y430108D01*
G01X581709Y419104D02*
X576165D01*
G01X581709Y430108D02*
Y419104D01*
G01X569898Y430108D02*
Y419104D01*
G01X577137Y432306D02*
X572137D01*
G01X574637Y429806D02*
Y434806D01*
G01X576165Y430108D02*
X581709D01*
G01X591098Y73974D02*
X591114Y74021D01*
G01X591221Y74186D02*
X591257Y74221D01*
G01X591188Y74149D02*
X591221Y74186D01*
G01X591160Y74109D02*
X591188Y74149D01*
G01X591135Y74066D02*
X591160Y74109D01*
G01X591114Y74021D02*
X591135Y74066D01*
G01X591017Y74953D02*
Y74609D01*
G01X591296Y74251D02*
X591337Y74278D01*
G01X591257Y74221D02*
X591296Y74251D01*
G01X591524Y74343D02*
X591573Y74347D01*
G01X591475Y74334D02*
X591524Y74343D01*
G01X591428Y74319D02*
X591475Y74334D01*
G01X591381Y74301D02*
X591428Y74319D01*
G01X591337Y74278D02*
X591381Y74301D01*
G01X591815D02*
X591859Y74278D01*
G01X591769Y74319D02*
X591815Y74301D01*
G01X591721Y74334D02*
X591769Y74319D01*
G01X591672Y74343D02*
X591721Y74334D01*
G01X591624Y74347D02*
X591672Y74343D01*
G01X591573Y74347D02*
X591624D01*
G01X592083Y74020D02*
X592099Y73974D01*
G01X592062Y74066D02*
X592083Y74020D01*
G01X592037Y74109D02*
X592062Y74066D01*
G01X592008Y74149D02*
X592037Y74109D01*
G01X591976Y74186D02*
X592008Y74149D01*
G01X591940Y74221D02*
X591976Y74186D01*
G01X591901Y74251D02*
X591940Y74221D01*
G01X591859Y74278D02*
X591901Y74251D01*
G01X591076Y71918D02*
X591080Y71969D01*
G01X591188Y72241D02*
X591221Y72278D01*
G01X591160Y72200D02*
X591188Y72241D01*
G01X591135Y72158D02*
X591160Y72200D01*
G01X591114Y72112D02*
X591135Y72158D01*
G01X591098Y72066D02*
X591114Y72112D01*
G01X591086Y72018D02*
X591098Y72066D01*
G01X591080Y71969D02*
X591086Y72018D01*
G01X591221Y72278D02*
X591257Y72312D01*
G01X591017Y73044D02*
Y72700D01*
G01X591257Y73433D02*
X591221Y73466D01*
G01D02*
X591188Y73504D01*
G01D02*
X591160Y73545D01*
G01X591135Y73587D02*
X591114Y73633D01*
G01X591160Y73545D02*
X591135Y73587D01*
G01X591098Y73679D02*
X591086Y73727D01*
G01X591114Y73633D02*
X591098Y73679D01*
G01X591086Y73926D02*
X591098Y73974D01*
G01X591080Y73877D02*
X591086Y73926D01*
G01X591076Y73826D02*
X591080Y73877D01*
G01Y73776D02*
X591076Y73826D01*
G01X591086Y73727D02*
X591080Y73776D01*
G01X591524Y72434D02*
X591573Y72439D01*
G01X591475Y72425D02*
X591524Y72434D01*
G01X591428Y72411D02*
X591475Y72425D01*
G01X591381Y72393D02*
X591428Y72411D01*
G01X591337Y72370D02*
X591381Y72393D01*
G01X591296Y72343D02*
X591337Y72370D01*
G01X591257Y72312D02*
X591296Y72343D01*
G01X591573Y73306D02*
X591524Y73310D01*
G01D02*
X591475Y73320D01*
G01D02*
X591428Y73334D01*
G01D02*
X591381Y73352D01*
G01D02*
X591337Y73375D01*
G01D02*
X591296Y73402D01*
G01D02*
X591257Y73433D01*
G01X591815Y72393D02*
X591859Y72370D01*
G01X591769Y72411D02*
X591815Y72393D01*
G01X591721Y72425D02*
X591769Y72411D01*
G01X591672Y72434D02*
X591721Y72425D01*
G01X591624Y72439D02*
X591672Y72434D01*
G01X591573Y72439D02*
X591624D01*
G01X591859Y73375D02*
X591815Y73352D01*
G01D02*
X591769Y73334D01*
G01D02*
X591721Y73320D01*
G01D02*
X591672Y73310D01*
G01D02*
X591624Y73306D01*
G01D02*
X591573D01*
G01X592099Y72066D02*
X592110Y72018D01*
G01X592062Y72158D02*
X592083Y72112D01*
G01D02*
X592099Y72066D01*
G01X592037Y72200D02*
X592062Y72158D01*
G01X592008Y72241D02*
X592037Y72200D01*
G01X591976Y72278D02*
X592008Y72241D01*
G01X591940Y72312D02*
X591976Y72278D01*
G01X591901Y72343D02*
X591940Y72312D01*
G01X591859Y72370D02*
X591901Y72343D01*
G01Y73402D02*
X591859Y73375D01*
G01X592110Y73727D02*
X592099Y73679D01*
G01D02*
X592083Y73633D01*
G01D02*
X592062Y73587D01*
G01D02*
X592037Y73545D01*
G01D02*
X592008Y73504D01*
G01D02*
X591976Y73466D01*
G01D02*
X591940Y73433D01*
G01D02*
X591901Y73402D01*
G01X592099Y73974D02*
X592110Y73926D01*
G01X592117Y71969D02*
X592120Y71918D01*
G01X592110Y72018D02*
X592117Y71969D01*
G01X592380Y73044D02*
Y74609D01*
G01X592117Y73877D02*
X592120Y73826D01*
G01X592110Y73926D02*
X592117Y73877D01*
G01X592120Y73826D02*
X592117Y73776D01*
G01D02*
X592110Y73727D01*
G01X591257Y71524D02*
X591221Y71558D01*
G01D02*
X591188Y71596D01*
G01D02*
X591160Y71636D01*
G01D02*
X591135Y71679D01*
G01D02*
X591114Y71724D01*
G01X591098Y71771D02*
X591086Y71818D01*
G01X591114Y71724D02*
X591098Y71771D01*
G01X591080Y71868D02*
X591076Y71918D01*
G01X591086Y71818D02*
X591080Y71868D01*
G01X591573Y71398D02*
X591524Y71402D01*
G01D02*
X591475Y71411D01*
G01D02*
X591428Y71426D01*
G01D02*
X591381Y71444D01*
G01D02*
X591337Y71466D01*
G01D02*
X591296Y71494D01*
G01D02*
X591257Y71524D01*
G01X591859Y71466D02*
X591815Y71444D01*
G01D02*
X591769Y71426D01*
G01D02*
X591721Y71411D01*
G01D02*
X591672Y71402D01*
G01D02*
X591624Y71398D01*
G01D02*
X591573D01*
G01X592062Y71679D02*
X592037Y71636D01*
G01D02*
X592008Y71596D01*
G01D02*
X591976Y71558D01*
G01D02*
X591940Y71524D01*
G01D02*
X591901Y71494D01*
G01D02*
X591859Y71466D01*
G01X592110Y71818D02*
X592099Y71771D01*
G01D02*
X592083Y71724D01*
G01D02*
X592062Y71679D01*
G01X592380Y71136D02*
Y72700D01*
G01X592120Y71918D02*
X592117Y71868D01*
G01D02*
X592110Y71818D01*
G01X591017Y71136D02*
Y69872D01*
G01D02*
X593112D01*
G01X589966Y74348D02*
X589339D01*
G01X590816D02*
X590492D01*
G01X590816Y74609D02*
Y74348D01*
G01X592380Y74609D02*
X590816D01*
G01X589966Y72439D02*
X589339D01*
G01Y74348D02*
Y73305D01*
G01D02*
X589966D01*
G01X589339Y72439D02*
Y71397D01*
G01D02*
X589966D01*
G01X590816Y72439D02*
X590492D01*
G01Y73305D02*
X590816D01*
G01Y72700D02*
Y72439D01*
G01X592380Y72700D02*
X590816D01*
G01Y73305D02*
Y73044D01*
G01D02*
X592380D01*
G01X590492Y71397D02*
X590816D01*
G01D02*
Y71136D01*
G01D02*
X592380D01*
G01X589966Y83159D02*
Y67942D01*
G01X590492D02*
Y83210D01*
G01X587864Y84057D02*
Y67942D01*
G01D02*
X618795D01*
G01X592380Y74953D02*
Y76518D01*
G01X591257Y75341D02*
X591221Y75375D01*
G01D02*
X591188Y75413D01*
G01D02*
X591160Y75453D01*
G01X591135Y75496D02*
X591114Y75541D01*
G01X591160Y75453D02*
X591135Y75496D01*
G01X591573Y75214D02*
X591524Y75218D01*
G01D02*
X591475Y75228D01*
G01D02*
X591428Y75242D01*
G01D02*
X591381Y75261D01*
G01D02*
X591337Y75283D01*
G01D02*
X591296Y75310D01*
G01D02*
X591257Y75341D01*
G01X591859Y75283D02*
X591815Y75261D01*
G01D02*
X591769Y75242D01*
G01D02*
X591721Y75228D01*
G01D02*
X591672Y75218D01*
G01D02*
X591624Y75214D01*
G01D02*
X591573D01*
G01X592037Y75453D02*
X592008Y75413D01*
G01D02*
X591976Y75375D01*
G01D02*
X591940Y75341D01*
G01D02*
X591901Y75310D01*
G01D02*
X591859Y75283D01*
G01X592083Y75542D02*
X592062Y75496D01*
G01D02*
X592037Y75453D01*
G01X590816Y75214D02*
Y74953D01*
G01D02*
X592380D01*
G01X589339Y76257D02*
Y75214D01*
G01D02*
X589966D01*
G01X590492D02*
X590816D01*
G01X591524Y76251D02*
X591573Y76256D01*
G01X591475Y76242D02*
X591524Y76251D01*
G01X591428Y76228D02*
X591475Y76242D01*
G01X591381Y76210D02*
X591428Y76228D01*
G01X591769D02*
X591815Y76210D01*
G01X591721Y76242D02*
X591769Y76228D01*
G01X591672Y76251D02*
X591721Y76242D01*
G01X591624Y76256D02*
X591672Y76251D01*
G01X591573Y76256D02*
X591624D01*
G01X589966Y76257D02*
X589339D01*
G01X590816D02*
X590492D01*
G01X590816Y76518D02*
Y76257D01*
G01X591098Y75588D02*
X591086Y75635D01*
G01X591114Y75541D02*
X591098Y75588D01*
G01X591080Y75685D02*
X591076Y75735D01*
G01X591086Y75635D02*
X591080Y75685D01*
G01X591135Y75974D02*
X591160Y76017D01*
G01X591114Y75929D02*
X591135Y75974D01*
G01X591098Y75882D02*
X591114Y75929D01*
G01X591086Y75834D02*
X591098Y75882D01*
G01X591080Y75786D02*
X591086Y75834D01*
G01X591076Y75735D02*
X591080Y75786D01*
G01X591221Y76095D02*
X591257Y76129D01*
G01X591188Y76058D02*
X591221Y76095D01*
G01X591160Y76017D02*
X591188Y76058D01*
G01X591337Y76186D02*
X591381Y76210D01*
G01X591296Y76160D02*
X591337Y76186D01*
G01X591257Y76129D02*
X591296Y76160D01*
G01X591815Y76210D02*
X591859Y76186D01*
G01X592110Y75636D02*
X592099Y75588D01*
G01D02*
X592083Y75542D01*
G01X592099Y75882D02*
X592110Y75834D01*
G01X592083Y75929D02*
X592099Y75882D01*
G01X592062Y75974D02*
X592083Y75929D01*
G01X592037Y76017D02*
X592062Y75974D01*
G01X592008Y76058D02*
X592037Y76017D01*
G01X591976Y76095D02*
X592008Y76058D01*
G01X591940Y76129D02*
X591976Y76095D01*
G01X591901Y76160D02*
X591940Y76129D01*
G01X591859Y76186D02*
X591901Y76160D01*
G01X592120Y75735D02*
X592117Y75685D01*
G01D02*
X592110Y75636D01*
G01X592117Y75786D02*
X592120Y75735D01*
G01X592110Y75834D02*
X592117Y75786D01*
G01X593113Y71076D02*
X593116Y71092D01*
G01X593112Y71059D02*
X593113Y71076D01*
G01X593239Y71186D02*
X595352D01*
G01X593222Y71184D02*
X593239Y71186D01*
G01X593206Y71181D02*
X593222Y71184D01*
G01X593190Y71175D02*
X593206Y71181D01*
G01X593176Y71169D02*
X593190Y71175D01*
G01X593161Y71159D02*
X593176Y71169D01*
G01X593149Y71148D02*
X593161Y71159D01*
G01X593139Y71136D02*
X593149Y71148D01*
G01X593129Y71122D02*
X593139Y71136D01*
G01X593122Y71107D02*
X593129Y71122D01*
G01X593116Y71092D02*
X593122Y71107D01*
G01X595033Y74826D02*
X594900Y75079D01*
G01X595739Y76694D02*
Y74810D01*
G01X594956Y74404D02*
X595130Y74150D01*
G01X594796Y74665D02*
X594956Y74404D01*
G01X595339Y74342D02*
X595180Y74580D01*
G01D02*
X595033Y74826D01*
G01X595511Y74112D02*
X595339Y74342D01*
G01X595760Y74686D02*
X595767Y74671D01*
G01X595755Y74702D02*
X595760Y74686D01*
G01X595774Y74657D02*
X596176Y74254D01*
G01X595767Y74671D02*
X595774Y74657D01*
G01X595739Y74810D02*
X595740Y74791D01*
G01X595741Y74772D02*
X595744Y74754D01*
G01X595740Y74791D02*
X595741Y74772D01*
G01X595744Y74754D02*
X595746Y74735D01*
G01X595750Y74718D02*
X595755Y74702D01*
G01X595746Y74735D02*
X595750Y74718D01*
G01X595557Y70156D02*
X595572Y70150D01*
G01X595528Y70172D02*
X595543Y70163D01*
G01D02*
X595557Y70156D01*
G01X595496Y70210D02*
X595505Y70195D01*
G01X595516Y70183D02*
X595528Y70172D01*
G01X595505Y70195D02*
X595516Y70183D01*
G01X595489Y70224D02*
X595496Y70210D01*
G01X595479Y71059D02*
Y70273D01*
G01D02*
X595480Y70255D01*
G01X595484Y70239D02*
X595489Y70224D01*
G01X595480Y70255D02*
X595484Y70239D01*
G01X595605Y70146D02*
X596406D01*
G01X595588Y70147D02*
X595605Y70146D01*
G01X595572Y70150D02*
X595588Y70147D01*
G01X595130Y74150D02*
X595317Y73908D01*
G01X595518Y73675D02*
X595731Y73453D01*
G01X595317Y73908D02*
X595518Y73675D01*
G01X595695Y73892D02*
X595511Y74112D01*
G01X595731Y73453D02*
X595955Y73243D01*
G01X595891Y73681D02*
X595695Y73892D01*
G01X595478Y71076D02*
X595479Y71059D01*
G01X595475Y71092D02*
X595478Y71076D01*
G01X595469Y71107D02*
X595475Y71092D01*
G01X595462Y71122D02*
X595469Y71107D01*
G01X595452Y71136D02*
X595462Y71122D01*
G01X595442Y71148D02*
X595452Y71136D01*
G01X595430Y71159D02*
X595442Y71148D01*
G01X595416Y71169D02*
X595430Y71159D01*
G01X595401Y71175D02*
X595416Y71169D01*
G01X595385Y71181D02*
X595401Y71175D01*
G01X595369Y71184D02*
X595385Y71181D01*
G01X595352Y71186D02*
X595369Y71184D01*
G01X594650Y74934D02*
X594796Y74665D01*
G01X593112Y69872D02*
Y71059D01*
G01X600892Y72198D02*
X600611Y72144D01*
G01X600811Y71918D02*
X601109Y71984D01*
G01X601168Y72268D02*
X600892Y72198D01*
G01X600320Y74223D02*
X600929D01*
G01X600308Y74225D02*
X600320Y74223D01*
G01X600297Y74226D02*
X600308Y74225D01*
G01X600288Y74230D02*
X600297Y74226D01*
G01X600278Y74234D02*
X600288Y74230D01*
G01X600270Y74239D02*
X600278Y74234D01*
G01X600263Y74246D02*
X600270Y74239D01*
G01X600256Y74253D02*
X600263Y74246D01*
G01X600247Y74270D02*
X600252Y74261D01*
G01D02*
X600256Y74253D01*
G01X600241Y75090D02*
Y74302D01*
G01D02*
X600242Y74290D01*
G01X600244Y74280D02*
X600247Y74270D01*
G01X600242Y74290D02*
X600244Y74280D01*
G01X600040Y72081D02*
X599752Y72071D01*
G01X600326Y72105D02*
X600040Y72081D01*
G01X600611Y72144D02*
X600326Y72105D01*
G01X599896Y71817D02*
X600203Y71834D01*
G01D02*
X600508Y71868D01*
G01D02*
X600811Y71918D01*
G01X601001Y74262D02*
X601006Y74271D01*
G01X600995Y74254D02*
X601001Y74262D01*
G01X600988Y74246D02*
X600995Y74254D01*
G01X600980Y74239D02*
X600988Y74246D01*
G01X600972Y74234D02*
X600980Y74239D01*
G01X600962Y74230D02*
X600972Y74234D01*
G01X600952Y74226D02*
X600962Y74230D01*
G01X600940Y74225D02*
X600952Y74226D01*
G01X600929Y74223D02*
X600940Y74225D01*
G01X601012Y74302D02*
Y76694D01*
G01X601011Y74291D02*
X601012Y74302D01*
G01X601009Y74281D02*
X601011Y74291D01*
G01X601006Y74271D02*
X601009Y74281D01*
G01X601336Y74249D02*
X601340Y74242D01*
G01X601332Y74257D02*
X601336Y74249D01*
G01X601328Y74265D02*
X601332Y74257D01*
G01X601326Y74273D02*
X601328Y74265D01*
G01X601324Y74282D02*
X601326Y74273D01*
G01X601323Y74292D02*
X601324Y74282D01*
G01X601322Y74302D02*
X601323Y74292D01*
G01X601322Y77202D02*
Y74302D01*
G01X601405Y74219D02*
X602010D01*
G01X601395D02*
X601405D01*
G01X601385Y74221D02*
X601395Y74219D01*
G01X601376Y74222D02*
X601385Y74221D01*
G01X601368Y74225D02*
X601376Y74222D01*
G01X601360Y74228D02*
X601368Y74225D01*
G01X601352Y74233D02*
X601360Y74228D01*
G01X601346Y74238D02*
X601352Y74233D01*
G01X601340Y74242D02*
X601346Y74238D01*
G01X602084Y74257D02*
X602087Y74265D01*
G01X602080Y74249D02*
X602084Y74257D01*
G01X602075Y74242D02*
X602080Y74249D01*
G01X602069Y74238D02*
X602075Y74242D01*
G01X602063Y74233D02*
X602069Y74238D01*
G01X602056Y74228D02*
X602063Y74233D01*
G01X602048Y74225D02*
X602056Y74228D01*
G01X602039Y74222D02*
X602048Y74225D01*
G01X602030Y74221D02*
X602039Y74222D01*
G01X602020Y74219D02*
X602030Y74221D01*
G01X602010Y74219D02*
X602020D01*
G01X602093Y74302D02*
Y75117D01*
G01X602092Y74292D02*
X602093Y74302D01*
G01X602092Y74282D02*
Y74292D01*
G01X602089Y74273D02*
X602092Y74282D01*
G01X602087Y74265D02*
X602089Y74273D01*
G01X601109Y71984D02*
X601403Y72066D01*
G01X601441Y72351D02*
X601168Y72268D01*
G01X601403Y72066D02*
X601692Y72164D01*
G01X601708Y72450D02*
X601441Y72351D01*
G01X601692Y72164D02*
X601976Y72278D01*
G01X601969Y72562D02*
X601708Y72450D01*
G01X601792Y71086D02*
X601796Y71103D01*
G01X601788Y71068D02*
X601792Y71086D01*
G01X601787Y71048D02*
X601788Y71068D01*
G01X601839Y71158D02*
X601853Y71168D01*
G01X601825Y71147D02*
X601839Y71158D01*
G01X601814Y71134D02*
X601825Y71147D01*
G01X601804Y71119D02*
X601814Y71134D01*
G01X601796Y71103D02*
X601804Y71119D01*
G01X602523Y72550D02*
X602784Y72707D01*
G01X601976Y72278D02*
X602252Y72406D01*
G01X602225Y72689D02*
X601969Y72562D01*
G01X602252Y72406D02*
X602523Y72550D01*
G01X602475Y72828D02*
X602225Y72689D01*
G01X602716Y72982D02*
X602475Y72828D01*
G01X601904Y71184D02*
X601924Y71186D01*
G01X601887Y71181D02*
X601904Y71184D01*
G01X601869Y71175D02*
X601887Y71181D01*
G01X601853Y71168D02*
X601869Y71175D01*
G01X601924Y71186D02*
X604548Y71182D01*
G01X601750Y69646D02*
X601760Y69658D01*
G01X601737Y69636D02*
X601750Y69646D01*
G01X601724Y69626D02*
X601737Y69636D01*
G01X601708Y69619D02*
X601724Y69626D01*
G01X601693Y69614D02*
X601708Y69619D01*
G01X601677Y69610D02*
X601693Y69614D01*
G01X601660Y69610D02*
X601677D01*
G01X601787Y69735D02*
Y71048D01*
G01X601785Y69719D02*
X601787Y69735D01*
G01X601782Y69702D02*
X601785Y69719D01*
G01X601777Y69687D02*
X601782Y69702D01*
G01X601770Y69673D02*
X601777Y69687D01*
G01X601760Y69658D02*
X601770Y69673D01*
G01X598443Y74271D02*
X598448Y74262D01*
G01X598453Y74254D02*
X598460Y74246D01*
G01X598448Y74262D02*
X598453Y74254D01*
G01X598440Y74281D02*
X598443Y74271D01*
G01X598437Y74291D02*
X598440Y74281D01*
G01X598436Y74302D02*
X598437Y74291D01*
G01X598436Y75374D02*
Y74302D01*
G01X598520Y74223D02*
X599128D01*
G01X598508Y74225D02*
X598520Y74223D01*
G01X598496Y74226D02*
X598508Y74225D01*
G01X598468Y74239D02*
X598476Y74234D01*
G01X598486Y74230D02*
X598496Y74226D01*
G01X598476Y74234D02*
X598486Y74230D01*
G01X598460Y74246D02*
X598468Y74239D01*
G01X599196Y74261D02*
X599201Y74270D01*
G01X599192Y74253D02*
X599196Y74261D01*
G01X599185Y74246D02*
X599192Y74253D01*
G01X599178Y74239D02*
X599185Y74246D01*
G01X599169Y74234D02*
X599178Y74239D01*
G01X599160Y74230D02*
X599169Y74234D01*
G01X599151Y74226D02*
X599160Y74230D01*
G01X599140Y74225D02*
X599151Y74226D01*
G01X599128Y74223D02*
X599140Y74225D01*
G01X599207Y74302D02*
Y75090D01*
G01X599206Y74290D02*
X599207Y74302D01*
G01X599204Y74280D02*
X599206Y74290D01*
G01X599201Y74270D02*
X599204Y74280D01*
G01X598652Y70587D02*
X598663Y70602D01*
G01X598644Y70572D02*
X598652Y70587D01*
G01X598639Y70558D02*
X598644Y70572D01*
G01X598636Y70543D02*
X598639Y70558D01*
G01X598635Y70529D02*
X598636Y70543D01*
G01X598880Y70587D02*
X598888Y70572D01*
G01X598893Y70558D02*
X598896Y70543D01*
G01X598888Y70572D02*
X598893Y70558D01*
G01X598896Y70543D02*
X598897Y70529D01*
G01X598869Y70602D02*
X598880Y70587D01*
G01X598611Y72186D02*
X598333Y72253D01*
G01X598892Y72135D02*
X598611Y72186D01*
G01X599176Y72098D02*
X598892Y72135D01*
G01X599463Y72078D02*
X599176Y72098D01*
G01X599752Y72071D02*
X599463Y72078D01*
G01X598371Y71976D02*
X598670Y71912D01*
G01X598735Y70655D02*
X598750Y70658D01*
G01X598720Y70649D02*
X598735Y70655D01*
G01X598704Y70640D02*
X598720Y70649D01*
G01X598688Y70629D02*
X598704Y70640D01*
G01X598675Y70617D02*
X598688Y70629D01*
G01X598663Y70602D02*
X598675Y70617D01*
G01X598670Y71912D02*
X598973Y71863D01*
G01X598857Y70617D02*
X598869Y70602D01*
G01X598844Y70629D02*
X598857Y70617D01*
G01X598828Y70640D02*
X598844Y70629D01*
G01X598812Y70649D02*
X598828Y70640D01*
G01X598797Y70655D02*
X598812Y70649D01*
G01X598782Y70658D02*
X598797Y70655D01*
G01X598766Y70660D02*
X598782Y70658D01*
G01X598750D02*
X598766Y70660D01*
G01X598973Y71863D02*
X599278Y71831D01*
G01D02*
X599586Y71816D01*
G01D02*
X599896Y71817D01*
G01X598585Y69636D02*
X598598Y69646D01*
G01X598571Y69626D02*
X598585Y69636D01*
G01X598556Y69619D02*
X598571Y69626D01*
G01X598541Y69614D02*
X598556Y69619D01*
G01X598525Y69610D02*
X598541Y69614D01*
G01X598508Y69610D02*
X598525D01*
G01X598635Y69736D02*
Y70529D01*
G01X598633Y69719D02*
X598635Y69736D01*
G01X598630Y69703D02*
X598633Y69719D01*
G01X598625Y69687D02*
X598630Y69703D01*
G01X598617Y69673D02*
X598625Y69687D01*
G01X598608Y69659D02*
X598617Y69673D01*
G01X598598Y69646D02*
X598608Y69659D01*
G01X599024Y69610D02*
X601660D01*
G01X599007D02*
X599024D01*
G01X598991Y69614D02*
X599007Y69610D01*
G01X598976Y69619D02*
X598991Y69614D01*
G01X598960Y69626D02*
X598976Y69619D01*
G01X598947Y69636D02*
X598960Y69626D01*
G01X598934Y69646D02*
X598947Y69636D01*
G01X598907Y69687D02*
X598915Y69673D01*
G01X598902Y69703D02*
X598907Y69687D01*
G01X598924Y69659D02*
X598934Y69646D01*
G01X598915Y69673D02*
X598924Y69659D01*
G01X598897Y70529D02*
Y69736D01*
G01X598899Y69719D02*
X598902Y69703D01*
G01X598897Y69736D02*
X598899Y69719D01*
G01X598071Y74921D02*
X598065Y74930D01*
G01X598076Y74911D02*
X598071Y74921D01*
G01X598080Y74902D02*
X598076Y74911D01*
G01X598081Y74892D02*
X598080Y74902D01*
G01X598082Y74881D02*
X598081Y74892D01*
G01X598065Y74930D02*
X598059Y74937D01*
G01X598071Y74260D02*
X598076Y74270D01*
G01X598065Y74251D02*
X598071Y74260D01*
G01X598058Y74243D02*
X598065Y74251D01*
G01X598050Y74236D02*
X598058Y74243D01*
G01X598041Y74230D02*
X598050Y74236D01*
G01X598032Y74226D02*
X598041Y74230D01*
G01X598021Y74222D02*
X598032Y74226D01*
G01X598011Y74220D02*
X598021Y74222D01*
G01X597999Y74219D02*
X598011Y74220D01*
G01X598082Y74302D02*
Y74881D01*
G01X598081Y74291D02*
X598082Y74302D01*
G01X598080Y74280D02*
X598081Y74291D01*
G01X598076Y74270D02*
X598080Y74280D01*
G01X596330Y74219D02*
X597999D01*
G01X596310Y74220D02*
X596330Y74219D01*
G01X596291Y74222D02*
X596310Y74220D01*
G01X596273Y74224D02*
X596291Y74222D01*
G01X596255Y74226D02*
X596273Y74224D01*
G01X596221Y74235D02*
X596238Y74230D01*
G01D02*
X596255Y74226D01*
G01X596205Y74241D02*
X596221Y74235D01*
G01X596191Y74247D02*
X596205Y74241D01*
G01X596176Y74254D02*
X596191Y74247D01*
G01X595955Y73243D02*
X596190Y73046D01*
G01X596097Y73482D02*
X595891Y73681D01*
G01X596423Y70147D02*
X596439Y70150D01*
G01X596406Y70146D02*
X596423Y70147D01*
G01X596516Y70210D02*
X596523Y70224D01*
G01X596506Y70195D02*
X596516Y70210D01*
G01X596496Y70183D02*
X596506Y70195D01*
G01X596483Y70172D02*
X596496Y70183D01*
G01X596469Y70163D02*
X596483Y70172D01*
G01X596454Y70156D02*
X596469Y70163D01*
G01X596439Y70150D02*
X596454Y70156D01*
G01X596532Y70273D02*
Y70922D01*
G01X596531Y70255D02*
X596532Y70273D01*
G01X596528Y70239D02*
X596531Y70255D01*
G01X596523Y70224D02*
X596528Y70239D01*
G01X596953Y72534D02*
X597225Y72391D01*
G01X597020Y72802D02*
X596776Y72952D01*
G01X597225Y72391D02*
X597503Y72265D01*
G01X597528Y72539D02*
X597271Y72663D01*
G01D02*
X597020Y72802D01*
G01X597503Y72265D02*
X597787Y72153D01*
G01X597792Y72430D02*
X597528Y72539D01*
G01X597787Y72153D02*
X598076Y72057D01*
G01X598060Y72334D02*
X597792Y72430D01*
G01X598076Y72057D02*
X598371Y71976D01*
G01X598333Y72253D02*
X598060Y72334D01*
G01X596720Y71174D02*
X596750Y71182D01*
G01X596996Y71092D02*
X597015Y71066D01*
G01X596976Y71114D02*
X596996Y71092D01*
G01X596952Y71134D02*
X596976Y71114D01*
G01X596927Y71150D02*
X596952Y71134D01*
G01X596900Y71164D02*
X596927Y71150D01*
G01X596870Y71174D02*
X596900Y71164D01*
G01X596840Y71182D02*
X596870Y71174D01*
G01X596811Y71185D02*
X596840Y71182D01*
G01X596780Y71185D02*
X596811D01*
G01X596750Y71182D02*
X596780Y71185D01*
G01X597056Y70953D02*
X597059Y70922D01*
G01X597030Y71039D02*
X597043Y71011D01*
G01X597051Y70982D02*
X597056Y70953D01*
G01X597043Y71011D02*
X597051Y70982D01*
G01X597015Y71066D02*
X597030Y71039D01*
G01X596314Y73294D02*
X596097Y73482D01*
G01X596190Y73046D02*
X596436Y72862D01*
G01X596541Y73116D02*
X596314Y73294D01*
G01X596691Y72690D02*
X596953Y72534D01*
G01X596436Y72862D02*
X596691Y72690D01*
G01X596776Y72952D02*
X596541Y73116D01*
G01X596576Y71066D02*
X596595Y71092D01*
G01X596560Y71039D02*
X596576Y71066D01*
G01X596548Y71011D02*
X596560Y71039D01*
G01X596540Y70982D02*
X596548Y71011D01*
G01X596534Y70953D02*
X596540Y70982D01*
G01X596532Y70922D02*
X596534Y70953D01*
G01X596692Y71164D02*
X596720Y71174D01*
G01X596664Y71150D02*
X596692Y71164D01*
G01X596639Y71134D02*
X596664Y71150D01*
G01X596616Y71114D02*
X596639Y71134D01*
G01X596595Y71092D02*
X596616Y71114D01*
G01X597185Y69610D02*
X598508D01*
G01X597168D02*
X597185D01*
G01X597152Y69614D02*
X597168Y69610D01*
G01X597136Y69619D02*
X597152Y69614D01*
G01X597122Y69626D02*
X597136Y69619D01*
G01X597108Y69636D02*
X597122Y69626D01*
G01X597096Y69646D02*
X597108Y69636D01*
G01X597084Y69659D02*
X597096Y69646D01*
G01X597059Y70922D02*
Y69736D01*
G01X597060Y69719D02*
X597063Y69703D01*
G01X597059Y69736D02*
X597060Y69719D01*
G01X597068Y69687D02*
X597076Y69673D01*
G01X597063Y69703D02*
X597068Y69687D01*
G01X597076Y69673D02*
X597084Y69659D01*
G01X594520Y75211D02*
X594650Y74934D01*
G01X594404Y75494D02*
X594520Y75211D01*
G01X594304Y75782D02*
X594404Y75494D01*
G01X594782Y75340D02*
X594676Y75606D01*
G01X594900Y75079D02*
X594782Y75340D01*
G01X594220Y76074D02*
X594304Y75782D01*
G01X594152Y76372D02*
X594220Y76074D01*
G01X594676Y75606D02*
X594587Y75876D01*
G01D02*
X594511Y76151D01*
G01D02*
X594450Y76430D01*
G01X600181Y75166D02*
X600192Y75164D01*
G01X600170Y75169D02*
X600181Y75166D01*
G01X600158Y75170D02*
X600170Y75169D01*
G01X600238Y75112D02*
X600240Y75102D01*
G01X600235Y75122D02*
X600238Y75112D01*
G01X600230Y75131D02*
X600235Y75122D01*
G01X600240Y75102D02*
X600241Y75090D01*
G01X600201Y75159D02*
X600209Y75154D01*
G01X600224Y75140D02*
X600230Y75131D01*
G01X600217Y75147D02*
X600224Y75140D01*
G01X600209Y75154D02*
X600217Y75147D01*
G01X600192Y75164D02*
X600201Y75159D01*
G01X602096Y75127D02*
X602099Y75130D01*
G01X602095Y75124D02*
X602096Y75127D01*
G01X602094Y75121D02*
X602095Y75124D01*
G01X602093Y75117D02*
X602094Y75121D01*
G01X602115Y75139D02*
X602610D01*
G01X602112Y75138D02*
X602115Y75139D01*
G01X602108Y75138D02*
X602112D01*
G01X602105Y75136D02*
X602108Y75138D01*
G01X602102Y75134D02*
X602105Y75136D01*
G01X602099Y75130D02*
X602102Y75134D01*
G01X599207Y76138D02*
X598436Y75374D01*
G01X599214Y75122D02*
X599218Y75131D01*
G01X599210Y75112D02*
X599214Y75122D01*
G01X599208Y75102D02*
X599210Y75112D01*
G01X599207Y75090D02*
X599208Y75102D01*
G01X599291Y75170D02*
X600158D01*
G01X599278Y75169D02*
X599291Y75170D01*
G01X599267Y75166D02*
X599278Y75169D01*
G01X599257Y75164D02*
X599267Y75166D01*
G01X599248Y75159D02*
X599257Y75164D01*
G01X599239Y75154D02*
X599248Y75159D01*
G01X599231Y75147D02*
X599239Y75154D01*
G01X599224Y75140D02*
X599231Y75147D01*
G01X599218Y75131D02*
X599224Y75140D01*
G01X598051Y74943D02*
X598042Y74949D01*
G01X598059Y74937D02*
X598051Y74943D01*
G01X598022Y74956D02*
X598011Y74958D01*
G01X598032Y74953D02*
X598022Y74956D01*
G01X598042Y74949D02*
X598032Y74953D01*
G01X598011Y74958D02*
X597999Y74959D01*
G01D02*
X596593D01*
G01X596581Y74960D02*
X596571Y74962D01*
G01X596593Y74959D02*
X596581Y74960D01*
G01X596560Y74966D02*
X596551Y74970D01*
G01X596571Y74962D02*
X596560Y74966D01*
G01X597808Y75402D02*
X597820Y75390D01*
G01D02*
X597944Y75266D01*
G01X597787Y75429D02*
X597798Y75415D01*
G01D02*
X597808Y75402D01*
G01X597777Y75443D02*
X597787Y75429D01*
G01X597749Y75491D02*
X597758Y75474D01*
G01X597768Y75458D02*
X597777Y75443D01*
G01X597758Y75474D02*
X597768Y75458D01*
G01X597732Y76096D02*
Y75526D01*
G01X597740Y75509D02*
X597749Y75491D01*
G01X597732Y75526D02*
X597740Y75509D01*
G01X597944Y75266D02*
X599892Y77191D01*
G01X596542Y74977D02*
X596534Y74983D01*
G01X596551Y74970D02*
X596542Y74977D01*
G01X596509Y75042D02*
Y76462D01*
G01X596510Y75031D02*
X596509Y75042D01*
G01X596512Y75020D02*
X596510Y75031D01*
G01X596516Y75010D02*
X596512Y75020D01*
G01X596520Y75001D02*
X596516Y75010D01*
G01X596527Y74991D02*
X596520Y75001D01*
G01X596534Y74983D02*
X596527Y74991D01*
G01X600241Y76602D02*
Y75826D01*
G01X602062D02*
Y76571D01*
G01X603123Y75826D02*
X602062D01*
G01X597974Y76387D02*
X597816Y76230D01*
G01D02*
X597805Y76218D01*
G01D02*
X597795Y76205D01*
G01X599207Y75826D02*
Y76138D01*
G01X600241Y75826D02*
X599207D01*
G01X597785Y76192D02*
X597776Y76178D01*
G01X597795Y76205D02*
X597785Y76192D01*
G01X597766Y76162D02*
X597757Y76147D01*
G01X597776Y76178D02*
X597766Y76162D01*
G01X597757Y76147D02*
X597748Y76130D01*
G01D02*
X597740Y76114D01*
G01D02*
X597732Y76096D01*
G01X618795Y84057D02*
X591017D01*
G01X589780Y83482D02*
X589813Y83460D01*
G01X589744Y83499D02*
X589780Y83482D01*
G01X589708Y83514D02*
X589744Y83499D01*
G01X589670Y83523D02*
X589708Y83514D01*
G01X589633Y83530D02*
X589670Y83523D01*
G01X589594Y83531D02*
X589633Y83530D01*
G01X589859Y84028D02*
X589788Y84044D01*
G01D02*
X589716Y84054D01*
G01D02*
X589644Y84057D01*
G01X590131Y83902D02*
X590068Y83942D01*
G01D02*
X590001Y83976D01*
G01D02*
X589931Y84006D01*
G01D02*
X589859Y84028D01*
G01X590337Y83697D02*
X590292Y83754D01*
G01D02*
X590244Y83809D01*
G01D02*
X590189Y83858D01*
G01D02*
X590131Y83902D01*
G01X589843Y83436D02*
X589871Y83409D01*
G01X589813Y83460D02*
X589843Y83436D01*
G01X590376Y83634D02*
X590337Y83697D01*
G01X590440Y83496D02*
X590411Y83567D01*
G01D02*
X590376Y83634D01*
G01X590463Y83425D02*
X590440Y83496D01*
G01X587864Y83531D02*
X589594D01*
G01X591017Y84057D02*
X587864D01*
G01X591080Y77694D02*
X591086Y77743D01*
G01X591221Y78003D02*
X591257Y78038D01*
G01X591188Y77966D02*
X591221Y78003D01*
G01X591160Y77926D02*
X591188Y77966D01*
G01X591135Y77882D02*
X591160Y77926D01*
G01X591114Y77838D02*
X591135Y77882D01*
G01X591098Y77790D02*
X591114Y77838D01*
G01X591086Y77743D02*
X591098Y77790D01*
G01X591017Y84057D02*
Y78426D01*
G01X591524Y78160D02*
X591573Y78164D01*
G01X591475Y78150D02*
X591524Y78160D01*
G01X591428Y78136D02*
X591475Y78150D01*
G01X591381Y78118D02*
X591428Y78136D01*
G01X591337Y78095D02*
X591381Y78118D01*
G01X591296Y78068D02*
X591337Y78095D01*
G01X591257Y78038D02*
X591296Y78068D01*
G01X591815Y78118D02*
X591859Y78095D01*
G01X591769Y78136D02*
X591815Y78118D01*
G01X591721Y78150D02*
X591769Y78136D01*
G01X591672Y78160D02*
X591721Y78150D01*
G01X591624Y78164D02*
X591672Y78160D01*
G01X591573Y78164D02*
X591624D01*
G01X592099Y77790D02*
X592110Y77743D01*
G01X592062Y77882D02*
X592083Y77838D01*
G01D02*
X592099Y77790D01*
G01X592037Y77926D02*
X592062Y77882D01*
G01X592008Y77966D02*
X592037Y77926D01*
G01X591976Y78003D02*
X592008Y77966D01*
G01X591940Y78038D02*
X591976Y78003D01*
G01X591901Y78068D02*
X591940Y78038D01*
G01X591859Y78095D02*
X591901Y78068D01*
G01X592110Y77743D02*
X592117Y77694D01*
G01X591257Y77250D02*
X591221Y77283D01*
G01D02*
X591188Y77321D01*
G01D02*
X591160Y77362D01*
G01X591135Y77404D02*
X591114Y77450D01*
G01X591160Y77362D02*
X591135Y77404D01*
G01X591098Y77496D02*
X591086Y77544D01*
G01X591114Y77450D02*
X591098Y77496D01*
G01X591076Y77643D02*
X591080Y77694D01*
G01Y77593D02*
X591076Y77643D01*
G01X591086Y77544D02*
X591080Y77593D01*
G01X591337Y77192D02*
X591296Y77218D01*
G01D02*
X591257Y77250D01*
G01X592083Y77450D02*
X592062Y77404D01*
G01D02*
X592037Y77362D01*
G01D02*
X592008Y77321D01*
G01D02*
X591976Y77284D01*
G01D02*
X591940Y77250D01*
G01D02*
X591901Y77218D01*
G01D02*
X591859Y77192D01*
G01X592110Y77544D02*
X592099Y77496D01*
G01D02*
X592083Y77450D01*
G01X592117Y77694D02*
X592120Y77643D01*
G01D02*
X592117Y77593D01*
G01D02*
X592110Y77544D01*
G01X591017Y76862D02*
Y76518D01*
G01X591573Y77122D02*
X591524Y77127D01*
G01D02*
X591475Y77137D01*
G01D02*
X591428Y77150D01*
G01D02*
X591381Y77169D01*
G01D02*
X591337Y77192D01*
G01X591769Y77150D02*
X591721Y77137D01*
G01D02*
X591672Y77127D01*
G01D02*
X591624Y77122D01*
G01D02*
X591573D01*
G01X591859Y77192D02*
X591815Y77169D01*
G01D02*
X591769Y77150D01*
G01X592380Y76862D02*
Y78426D01*
G01X589966Y78165D02*
X589339D01*
G01X590816D02*
X590492D01*
G01X590816Y78426D02*
Y78165D01*
G01X592380Y78426D02*
X590816D01*
G01X589958Y83236D02*
X589964Y83198D01*
G01D02*
X589966Y83159D01*
G01X589934Y83310D02*
X589948Y83273D01*
G01D02*
X589958Y83236D01*
G01X589916Y83345D02*
X589934Y83310D01*
G01X589871Y83409D02*
X589895Y83378D01*
G01D02*
X589916Y83345D01*
G01X590488Y83282D02*
X590479Y83354D01*
G01X590492Y83210D02*
X590488Y83282D01*
G01X590479Y83354D02*
X590463Y83425D01*
G01X589339Y78165D02*
Y77122D01*
G01D02*
X589966D01*
G01X590492D02*
X590816D01*
G01X592380Y76518D02*
X590816D01*
G01Y77122D02*
Y76862D01*
G01D02*
X592380D01*
G01X593176Y80610D02*
X593168Y80606D01*
G01X593185Y80612D02*
X593176Y80610D01*
G01X593168Y80606D02*
X593161Y80602D01*
G01X593144Y80586D02*
X593140Y80578D01*
G01X593149Y80592D02*
X593144Y80586D01*
G01X593155Y80598D02*
X593149Y80592D01*
G01X593161Y80602D02*
X593155Y80598D01*
G01X593140Y80578D02*
X593137Y80570D01*
G01X595392Y80616D02*
X593214D01*
G01X593204Y80615D02*
X593194Y80614D01*
G01X593214Y80616D02*
X593204Y80615D01*
G01X593194Y80614D02*
X593185Y80612D01*
G01X593214Y79871D02*
X593836D01*
G01X593203Y79872D02*
X593214Y79871D01*
G01X593192Y79874D02*
X593203Y79872D01*
G01X593182Y79878D02*
X593192Y79874D01*
G01X593172Y79882D02*
X593182Y79878D01*
G01X593163Y79888D02*
X593172Y79882D01*
G01X593131Y80532D02*
Y79954D01*
G01X593134Y79932D02*
X593137Y79922D01*
G01X593132Y79943D02*
X593134Y79932D01*
G01X593131Y79954D02*
X593132Y79943D01*
G01X593155Y79895D02*
X593163Y79888D01*
G01X593148Y79903D02*
X593155Y79895D01*
G01X593142Y79912D02*
X593148Y79903D01*
G01X593137Y79922D02*
X593142Y79912D01*
G01X593135Y80562D02*
X593132Y80553D01*
G01X593137Y80570D02*
X593135Y80562D01*
G01X593132Y80543D02*
X593131Y80532D01*
G01X593132Y80553D02*
Y80543D01*
G01X595329Y81103D02*
X595134Y80850D01*
G01D02*
X595577D01*
G01X595451Y80591D02*
X595443Y80598D01*
G01X595457Y80583D02*
X595451Y80591D01*
G01X595464Y80574D02*
X595457Y80583D01*
G01X595424Y80609D02*
X595414Y80613D01*
G01X595433Y80605D02*
X595424Y80609D01*
G01X595443Y80598D02*
X595433Y80605D01*
G01X595403Y80615D02*
X595392Y80616D01*
G01X595414Y80613D02*
X595403Y80615D01*
G01X595537Y81342D02*
X595329Y81103D01*
G01X595758Y81570D02*
X595537Y81342D01*
G01X595708Y80610D02*
X595700Y80606D01*
G01X595716Y80612D02*
X595708Y80610D01*
G01X595676Y80586D02*
X595672Y80578D01*
G01X595680Y80592D02*
X595676Y80586D01*
G01X595686Y80598D02*
X595680Y80592D01*
G01X595692Y80602D02*
X595686Y80598D01*
G01X595700Y80606D02*
X595692Y80602D01*
G01X595672Y80578D02*
X595668Y80570D01*
G01X596350Y80616D02*
X595745D01*
G01X595735Y80615D02*
X595725Y80614D01*
G01X595745Y80616D02*
X595735Y80615D01*
G01X595725Y80614D02*
X595716Y80612D01*
G01X595577Y80850D02*
X595771Y81073D01*
G01D02*
X595974Y81282D01*
G01X595992Y81785D02*
X595758Y81570D01*
G01X595475Y79954D02*
Y80532D01*
G01X595474Y79943D02*
X595475Y79954D01*
G01X595472Y79932D02*
X595474Y79943D01*
G01X595468Y79922D02*
X595472Y79932D01*
G01X595464Y79912D02*
X595468Y79922D01*
G01X595457Y79903D02*
X595464Y79912D01*
G01X595451Y79895D02*
X595457Y79903D01*
G01X595443Y79888D02*
X595451Y79895D01*
G01X595433Y79882D02*
X595443Y79888D01*
G01X595424Y79878D02*
X595433Y79882D01*
G01X595414Y79874D02*
X595424Y79878D01*
G01X595403Y79872D02*
X595414Y79874D01*
G01X595392Y79871D02*
X595403Y79872D01*
G01X595472Y80554D02*
X595468Y80565D01*
G01X595474Y80544D02*
X595472Y80554D01*
G01X595475Y80532D02*
X595474Y80544D01*
G01X595468Y80565D02*
X595464Y80574D01*
G01X595665Y80562D02*
X595664Y80553D01*
G01X595668Y80570D02*
X595665Y80562D01*
G01X595663Y80543D02*
X595662Y80532D01*
G01X595664Y80553D02*
X595663Y80543D01*
G01X595745Y77550D02*
X596350D01*
G01X595735D02*
X595745D01*
G01X595725D02*
X595735D01*
G01X595716Y77553D02*
X595725Y77550D01*
G01X595708Y77555D02*
X595716Y77553D01*
G01X595700Y77558D02*
X595708Y77555D01*
G01X595672Y77586D02*
X595676Y77579D01*
G01X595668Y77594D02*
X595672Y77586D01*
G01X595692Y77562D02*
X595700Y77558D01*
G01X595686Y77567D02*
X595692Y77562D01*
G01X595680Y77573D02*
X595686Y77567D01*
G01X595676Y77579D02*
X595680Y77573D01*
G01X595662Y80532D02*
Y77633D01*
G01X595663Y77622D02*
X595664Y77612D01*
G01X595662Y77633D02*
X595663Y77622D01*
G01X595665Y77603D02*
X595668Y77594D01*
G01X595664Y77612D02*
X595665Y77603D01*
G01X593836Y79871D02*
X593848Y79870D01*
G01X593912Y79814D02*
X593914Y79804D01*
G01X593909Y79825D02*
X593912Y79814D01*
G01X593914Y79804D02*
X593915Y79792D01*
G01X593905Y79834D02*
X593909Y79825D01*
G01X593900Y79842D02*
X593905Y79834D01*
G01X593893Y79849D02*
X593900Y79842D01*
G01X593886Y79855D02*
X593893Y79849D01*
G01X593878Y79861D02*
X593886Y79855D01*
G01X593868Y79865D02*
X593878Y79861D01*
G01X593859Y79868D02*
X593868Y79865D01*
G01X593848Y79870D02*
X593859Y79868D01*
G01X594704Y79841D02*
X594710Y79849D01*
G01X594697Y79833D02*
X594704Y79841D01*
G01X594692Y79823D02*
X594697Y79833D01*
G01X594689Y79814D02*
X594692Y79823D01*
G01X594688Y79803D02*
X594689Y79814D01*
G01X594686Y79792D02*
X594688Y79803D01*
G01X594769Y79871D02*
X595392D01*
G01X594757Y79870D02*
X594769Y79871D01*
G01X594746Y79868D02*
X594757Y79870D01*
G01X594736Y79865D02*
X594746Y79868D01*
G01X594726Y79861D02*
X594736Y79865D01*
G01X594718Y79855D02*
X594726Y79861D01*
G01X594710Y79849D02*
X594718Y79855D01*
G01X594357Y77286D02*
X594044D01*
G01X593998Y77550D02*
X594608D01*
G01X593987D02*
X593998D01*
G01X593976Y77552D02*
X593987Y77550D01*
G01X593966Y77556D02*
X593976Y77552D01*
G01X593956Y77561D02*
X593966Y77556D01*
G01X593948Y77566D02*
X593956Y77561D01*
G01X593940Y77574D02*
X593948Y77566D01*
G01X593915Y79792D02*
Y77633D01*
G01X593916Y77621D02*
X593918Y77610D01*
G01X593915Y77633D02*
X593916Y77621D01*
G01X593932Y77582D02*
X593940Y77574D01*
G01X593926Y77590D02*
X593932Y77582D01*
G01X593922Y77600D02*
X593926Y77590D01*
G01X593918Y77610D02*
X593922Y77600D01*
G01X594686Y77633D02*
Y79792D01*
G01X594685Y77620D02*
X594686Y77633D01*
G01X594683Y77609D02*
X594685Y77620D01*
G01X594680Y77599D02*
X594683Y77609D01*
G01X594676Y77590D02*
X594680Y77599D01*
G01X594670Y77581D02*
X594676Y77590D01*
G01X594664Y77573D02*
X594670Y77581D01*
G01X594656Y77566D02*
X594664Y77573D01*
G01X594648Y77560D02*
X594656Y77566D01*
G01X594639Y77556D02*
X594648Y77560D01*
G01X594628Y77552D02*
X594639Y77556D01*
G01X594619Y77550D02*
X594628Y77552D01*
G01X594608Y77550D02*
X594619D01*
G01X596176Y77250D02*
X595774Y76847D01*
G01D02*
X595767Y76834D01*
G01X595760Y76818D02*
X595755Y76803D01*
G01X595767Y76834D02*
X595760Y76818D01*
G01X595750Y76786D02*
X595747Y76769D01*
G01X595755Y76803D02*
X595750Y76786D01*
G01X595747Y76769D02*
X595744Y76751D01*
G01X595741Y76733D02*
X595740Y76714D01*
G01X595744Y76751D02*
X595741Y76733D01*
G01X595740Y76714D02*
X595739Y76694D01*
G01X594100Y76673D02*
X594152Y76372D01*
G01X594064Y76977D02*
X594100Y76673D01*
G01X594044Y77286D02*
X594064Y76977D01*
G01X594450Y76430D02*
X594404Y76711D01*
G01D02*
X594373Y76997D01*
G01D02*
X594357Y77286D01*
G01X600904Y80611D02*
X600887Y80608D01*
G01D02*
X600870Y80604D01*
G01X600852Y80599D02*
X600835Y80594D01*
G01X600870Y80604D02*
X600852Y80599D01*
G01X600835Y80594D02*
X600817Y80588D01*
G01D02*
X600799Y80581D01*
G01X600920Y80614D02*
X600904Y80611D01*
G01X600896Y77554D02*
X600913Y77551D01*
G01X600877Y77557D02*
X600896Y77554D01*
G01X600860Y77561D02*
X600877Y77557D01*
G01X600844Y77566D02*
X600860Y77561D01*
G01X600828Y77571D02*
X600844Y77566D01*
G01X600813Y77577D02*
X600828Y77571D01*
G01X600799Y77584D02*
X600813Y77577D01*
G01X600016Y81762D02*
X600015Y81770D01*
G01X600018Y81753D02*
X600016Y81762D01*
G01X600019Y81744D02*
X600018Y81753D01*
G01X600020Y81735D02*
X600019Y81744D01*
G01X600020Y81727D02*
Y81735D01*
G01Y81718D02*
Y81727D01*
G01X600000Y81832D02*
X599997Y81840D01*
G01X600002Y81823D02*
X600000Y81832D01*
G01X600004Y81815D02*
X600002Y81823D01*
G01X600007Y81806D02*
X600004Y81815D01*
G01X600009Y81798D02*
X600007Y81806D01*
G01X600012Y81788D02*
X600009Y81798D01*
G01X600013Y81779D02*
X600012Y81788D01*
G01X600015Y81770D02*
X600013Y81779D01*
G01X599988Y81864D02*
X599985Y81872D01*
G01X599992Y81856D02*
X599988Y81864D01*
G01X599994Y81848D02*
X599992Y81856D01*
G01X599997Y81840D02*
X599994Y81848D01*
G01X600361Y80044D02*
Y80024D01*
G01X600799Y80581D02*
X600396Y80178D01*
G01X600388Y80163D02*
X600383Y80149D01*
G01X600396Y80178D02*
X600388Y80163D01*
G01X600377Y80133D02*
X600372Y80117D01*
G01X600383Y80149D02*
X600377Y80133D01*
G01X600372Y80117D02*
X600368Y80099D01*
G01X600366Y80082D02*
X600363Y80063D01*
G01X600368Y80099D02*
X600366Y80082D01*
G01X600363Y80063D02*
X600361Y80044D01*
G01X600388Y78002D02*
X600396Y77987D01*
G01X600383Y78016D02*
X600388Y78002D01*
G01X600377Y78032D02*
X600383Y78016D01*
G01X600372Y78049D02*
X600377Y78032D01*
G01X600361Y80024D02*
Y78141D01*
G01Y78121D02*
X600363Y78102D01*
G01X600361Y78141D02*
Y78121D01*
G01X600363Y78102D02*
X600366Y78084D01*
G01X600368Y78066D02*
X600372Y78049D01*
G01X600366Y78084D02*
X600368Y78066D01*
G01X599892Y77191D02*
X599916Y77218D01*
G01X600013Y77427D02*
X600019Y77463D01*
G01X600005Y77390D02*
X600013Y77427D01*
G01X599992Y77353D02*
X600005Y77390D01*
G01X599977Y77315D02*
X599992Y77353D01*
G01X599959Y77280D02*
X599977Y77315D01*
G01X599939Y77248D02*
X599959Y77280D01*
G01X599916Y77218D02*
X599939Y77248D01*
G01X600020Y77500D02*
Y81718D01*
G01X600019Y77463D02*
X600020Y77500D01*
G01X600484Y77282D02*
X600466Y77286D01*
G01X600449Y77287D02*
X600432Y77289D01*
G01X600466Y77286D02*
X600449Y77287D01*
G01X600432Y77289D02*
X600416Y77290D01*
G01D02*
X600288D01*
G01X600396Y77987D02*
X600799Y77584D01*
G01X600574Y77255D02*
X600556Y77262D01*
G01X600537Y77268D02*
X600520Y77274D01*
G01X600556Y77262D02*
X600537Y77268D01*
G01X600520Y77274D02*
X600502Y77278D01*
G01D02*
X600484Y77282D01*
G01X601034Y83030D02*
X600724Y83094D01*
G01X600811Y82699D02*
X601093Y82633D01*
G01X600093Y83170D02*
X599775Y83182D01*
G01X599943Y82805D02*
X600235Y82785D01*
G01X600409Y83141D02*
X600093Y83170D01*
G01X600235Y82785D02*
X600524Y82750D01*
G01X600724Y83094D02*
X600409Y83141D01*
G01X600524Y82750D02*
X600811Y82699D01*
G01X602621Y80616D02*
X600952D01*
G01X600936Y80615D02*
X600920Y80614D01*
G01X600952Y80616D02*
X600936Y80615D01*
G01X601154Y79902D02*
X602621D01*
G01X601150D02*
X601154D01*
G01X601147Y79900D02*
X601150Y79902D01*
G01X601144Y79898D02*
X601147Y79900D01*
G01X601140Y79896D02*
X601144Y79898D01*
G01X601137Y79893D02*
X601140Y79896D01*
G01X601135Y79890D02*
X601137Y79893D01*
G01X601133Y79886D02*
X601135Y79890D01*
G01X601132Y79883D02*
X601133Y79886D01*
G01X601132Y79880D02*
Y79883D01*
G01X602175Y82218D02*
X602431Y82078D01*
G01D02*
X602678Y81924D01*
G01X602621Y78263D02*
X601154D01*
G01D02*
X601150Y78264D01*
G01X601132Y78286D02*
Y78758D01*
G01Y78282D02*
Y78286D01*
G01X601133Y78278D02*
X601132Y78282D01*
G01X601135Y78275D02*
X601133Y78278D01*
G01X601137Y78272D02*
X601135Y78275D01*
G01X601140Y78269D02*
X601137Y78272D01*
G01X601144Y78266D02*
X601140Y78269D01*
G01X601147Y78265D02*
X601144Y78266D01*
G01X601150Y78264D02*
X601147Y78265D01*
G01X601154Y78780D02*
X602402D01*
G01X601150D02*
X601154D01*
G01X601147Y78778D02*
X601150Y78780D01*
G01X601144Y78777D02*
X601147Y78778D01*
G01X601140Y78774D02*
X601144Y78777D01*
G01X601137Y78772D02*
X601140Y78774D01*
G01X601135Y78769D02*
X601137Y78772D01*
G01X601133Y78766D02*
X601135Y78769D01*
G01X601132Y78762D02*
X601133Y78766D01*
G01X601132Y78758D02*
Y78762D01*
G01X602402Y79385D02*
X601154D01*
G01D02*
X601150D01*
G01X601132Y79402D02*
Y79880D01*
G01Y79399D02*
Y79402D01*
G01X601133Y79397D02*
X601132Y79399D01*
G01X601135Y79394D02*
X601133Y79397D01*
G01X601137Y79392D02*
X601135Y79394D01*
G01X601140Y79390D02*
X601137Y79392D01*
G01X601143Y79388D02*
X601140Y79390D01*
G01X601146Y79386D02*
X601143Y79388D01*
G01X601150Y79385D02*
X601146Y79386D01*
G01X600952Y77550D02*
X602621D01*
G01X600932D02*
X600952D01*
G01X600913Y77551D02*
X600932Y77550D01*
G01X601333Y77244D02*
X601328Y77234D01*
G01X601339Y77254D02*
X601333Y77244D01*
G01X601346Y77262D02*
X601339Y77254D01*
G01X601325Y77225D02*
X601323Y77214D01*
G01X601328Y77234D02*
X601325Y77225D01*
G01X601323Y77214D02*
X601322Y77202D01*
G01X603302Y77286D02*
X601405D01*
G01X601394Y77285D02*
X601383Y77282D01*
G01X601405Y77286D02*
X601394Y77285D01*
G01X601363Y77274D02*
X601354Y77268D01*
G01X601373Y77279D02*
X601363Y77274D01*
G01X601383Y77282D02*
X601373Y77279D01*
G01X601354Y77268D02*
X601346Y77262D01*
G01X602485Y78863D02*
Y79302D01*
G01Y78853D02*
Y78863D01*
G01X602484Y78843D02*
X602485Y78853D01*
G01X602482Y78834D02*
X602484Y78843D01*
G01X602480Y78826D02*
X602482Y78834D01*
G01X602476Y78818D02*
X602480Y78826D01*
G01X602472Y78810D02*
X602476Y78818D01*
G01X602468Y78804D02*
X602472Y78810D01*
G01X602462Y78798D02*
X602468Y78804D01*
G01X602456Y78794D02*
X602462Y78798D01*
G01X602448Y78790D02*
X602456Y78794D01*
G01X602440Y78786D02*
X602448Y78790D01*
G01X602432Y78783D02*
X602440Y78786D01*
G01X602422Y78782D02*
X602432Y78783D01*
G01X602412Y78781D02*
X602422Y78782D01*
G01X602402Y78780D02*
X602412Y78781D01*
G01X602483Y79324D02*
X602479Y79334D01*
G01X602484Y79313D02*
X602483Y79324D01*
G01X602485Y79302D02*
X602484Y79313D01*
G01X602461Y79361D02*
X602453Y79367D01*
G01X602468Y79353D02*
X602461Y79361D01*
G01X602474Y79343D02*
X602468Y79353D01*
G01X602479Y79334D02*
X602474Y79343D01*
G01X602435Y79378D02*
X602424Y79382D01*
G01X602444Y79374D02*
X602435Y79378D01*
G01X602453Y79367D02*
X602444Y79374D01*
G01X602414Y79384D02*
X602402Y79385D01*
G01X602424Y79382D02*
X602414Y79384D01*
G01X601340Y82949D02*
X601034Y83030D01*
G01X601093Y82633D02*
X601372Y82551D01*
G01X601640Y82850D02*
X601340Y82949D01*
G01X601372Y82551D02*
X601645Y82455D01*
G01D02*
X601913Y82344D01*
G01X601934Y82736D02*
X601640Y82850D01*
G01X602774Y82295D02*
X602502Y82458D01*
G01X601913Y82344D02*
X602175Y82218D01*
G01X602221Y82605D02*
X601934Y82736D01*
G01X602502Y82458D02*
X602221Y82605D01*
G01X600977Y76852D02*
X600574Y77255D01*
G01X601007Y76747D02*
X601005Y76757D01*
G01X601008Y76738D02*
X601007Y76747D01*
G01X601009Y76730D02*
X601008Y76738D01*
G01X601011Y76721D02*
X601009Y76730D01*
G01X601012Y76711D02*
X601011Y76721D01*
G01X601012Y76703D02*
Y76711D01*
G01Y76694D02*
Y76703D01*
G01X600980Y76844D02*
X600977Y76852D01*
G01X600984Y76836D02*
X600980Y76844D01*
G01X600986Y76828D02*
X600984Y76836D01*
G01X600989Y76819D02*
X600986Y76828D01*
G01X600992Y76810D02*
X600989Y76819D01*
G01X600994Y76802D02*
X600992Y76810D01*
G01X600996Y76793D02*
X600994Y76802D01*
G01X600999Y76784D02*
X600996Y76793D01*
G01X601001Y76775D02*
X600999Y76784D01*
G01X601003Y76766D02*
X601001Y76775D01*
G01X601005Y76757D02*
X601003Y76766D01*
G01X602062Y76571D02*
X603123D01*
G01X599985Y81872D02*
X599582Y82274D01*
G01X599009Y79871D02*
Y80616D01*
G01X598758Y79871D02*
X599009D01*
G01X598128Y77550D02*
X598680D01*
G01X598116D02*
X598128D01*
G01X598105Y77552D02*
X598116Y77550D01*
G01X598743Y77581D02*
X598748Y77590D01*
G01X598736Y77573D02*
X598743Y77581D01*
G01X598728Y77566D02*
X598736Y77573D01*
G01X598720Y77560D02*
X598728Y77566D01*
G01X598711Y77556D02*
X598720Y77560D01*
G01X598701Y77552D02*
X598711Y77556D01*
G01X598691Y77550D02*
X598701Y77552D01*
G01X598680Y77550D02*
X598691D01*
G01X598758Y77633D02*
Y79871D01*
G01X598757Y77620D02*
X598758Y77633D01*
G01X598756Y77609D02*
X598757Y77620D01*
G01X598752Y77599D02*
X598756Y77609D01*
G01X598748Y77590D02*
X598752Y77599D01*
G01X599249Y82310D02*
Y77644D01*
G01X599648Y82809D02*
X599943Y82805D01*
G01X598211Y82593D02*
X598492Y82667D01*
G01X598511Y83052D02*
X598204Y82976D01*
G01X598492Y82667D02*
X598776Y82726D01*
G01X598822Y83110D02*
X598511Y83052D01*
G01X598776Y82726D02*
X599065Y82769D01*
G01X599137Y83152D02*
X598822Y83110D01*
G01X599424Y82310D02*
X599249D01*
G01X599065Y82769D02*
X599356Y82797D01*
G01X599454Y83175D02*
X599137Y83152D01*
G01X599582Y82274D02*
X599564Y82282D01*
G01D02*
X599546Y82288D01*
G01X599528Y82294D02*
X599510Y82298D01*
G01X599546Y82288D02*
X599528Y82294D01*
G01X599510Y82298D02*
X599492Y82302D01*
G01X599475Y82306D02*
X599457Y82308D01*
G01X599492Y82302D02*
X599475Y82306D01*
G01X599440Y82310D02*
X599424D01*
G01X599457Y82308D02*
X599440Y82310D01*
G01X599356Y82797D02*
X599648Y82809D01*
G01X599775Y83182D02*
X599454Y83175D01*
G01X600288Y77290D02*
X599594Y76602D01*
G01D02*
X600241D01*
G01X595974Y81282D02*
X596188Y81480D01*
G01X596237Y81986D02*
X595992Y81785D01*
G01X596844Y80613D02*
X596833Y80609D01*
G01D02*
X596824Y80605D01*
G01X596807Y80591D02*
X596800Y80583D01*
G01X596815Y80598D02*
X596807Y80591D01*
G01X596824Y80605D02*
X596815Y80598D01*
G01X596800Y80583D02*
X596794Y80574D01*
G01X599009Y80616D02*
X596866D01*
G01D02*
X596855Y80615D01*
G01D02*
X596844Y80613D01*
G01X596891Y82002D02*
X597141Y82148D01*
G01X596789Y80565D02*
X596786Y80554D01*
G01X596794Y80574D02*
X596789Y80565D01*
G01X596784Y80544D02*
X596783Y80532D01*
G01X596786Y80554D02*
X596784Y80544D01*
G01X597554Y79871D02*
X598044D01*
G01X596424Y80578D02*
X596420Y80586D01*
G01X596427Y80570D02*
X596424Y80578D01*
G01X596403Y80602D02*
X596396Y80606D01*
G01X596409Y80598D02*
X596403Y80602D01*
G01X596415Y80592D02*
X596409Y80598D01*
G01X596420Y80586D02*
X596415Y80592D01*
G01X596388Y80610D02*
X596379Y80612D01*
G01X596396Y80606D02*
X596388Y80610D01*
G01X596370Y80614D02*
X596360Y80615D01*
G01X596379Y80612D02*
X596370Y80614D01*
G01X596360Y80615D02*
X596350Y80616D01*
G01X596412Y81666D02*
X596648Y81841D01*
G01X596188Y81480D02*
X596412Y81666D01*
G01X596492Y82174D02*
X596237Y81986D01*
G01X596648Y81841D02*
X596891Y82002D01*
G01X596430Y80562D02*
X596427Y80570D01*
G01X596432Y80553D02*
X596430Y80562D01*
G01X596433Y80543D02*
X596432Y80553D01*
G01X596433Y80532D02*
Y80543D01*
G01X597141Y82148D02*
X597400Y82281D01*
G01X596758Y82347D02*
X596492Y82174D01*
G01X596866Y77550D02*
X597471D01*
G01X596856D02*
X596866D01*
G01X596846Y77551D02*
X596856Y77550D01*
G01X596836Y77553D02*
X596846Y77551D01*
G01X596828Y77555D02*
X596836Y77553D01*
G01X596820Y77558D02*
X596828Y77555D01*
G01X596813Y77562D02*
X596820Y77558D01*
G01X596807Y77567D02*
X596813Y77562D01*
G01X596801Y77573D02*
X596807Y77567D01*
G01X596796Y77579D02*
X596801Y77573D01*
G01X596783Y80532D02*
Y77633D01*
G01X596784Y77622D02*
Y77612D01*
G01X596783Y77633D02*
X596784Y77622D01*
G01X596792Y77586D02*
X596796Y77579D01*
G01X596788Y77594D02*
X596792Y77586D01*
G01X596786Y77603D02*
X596788Y77594D01*
G01X596784Y77612D02*
X596786Y77603D01*
G01X597554Y77633D02*
Y79871D01*
G01X597553Y77622D02*
X597554Y77633D01*
G01X597552Y77612D02*
X597553Y77622D01*
G01X597550Y77603D02*
X597552Y77612D01*
G01X597548Y77594D02*
X597550Y77603D01*
G01X597544Y77586D02*
X597548Y77594D01*
G01X597540Y77579D02*
X597544Y77586D01*
G01X597536Y77573D02*
X597540Y77579D01*
G01X597530Y77567D02*
X597536Y77573D01*
G01X597524Y77562D02*
X597530Y77567D01*
G01X597516Y77558D02*
X597524Y77562D01*
G01X597508Y77555D02*
X597516Y77558D01*
G01X597500Y77553D02*
X597508Y77555D01*
G01X597491Y77551D02*
X597500Y77553D01*
G01X597481Y77550D02*
X597491Y77551D01*
G01X597471Y77550D02*
X597481D01*
G01X598071Y77244D02*
X598065Y77254D01*
G01X598076Y77234D02*
X598071Y77244D01*
G01X598080Y77225D02*
X598076Y77234D01*
G01X598081Y77214D02*
X598080Y77225D01*
G01X598082Y77202D02*
X598081Y77214D01*
G01X598050Y77268D02*
X598041Y77274D01*
G01X598058Y77262D02*
X598050Y77268D01*
G01X598065Y77254D02*
X598058Y77262D01*
G01X598021Y77282D02*
X598011Y77285D01*
G01X598032Y77279D02*
X598021Y77282D01*
G01X598041Y77274D02*
X598032Y77279D01*
G01X598011Y77285D02*
X597999Y77286D01*
G01X598096Y77556D02*
X598105Y77552D01*
G01X598086Y77561D02*
X598096Y77556D01*
G01X598076Y77566D02*
X598086Y77561D01*
G01X598068Y77574D02*
X598076Y77566D01*
G01X598044Y79871D02*
Y77633D01*
G01X598045Y77621D02*
X598048Y77610D01*
G01X598044Y77633D02*
X598045Y77621D01*
G01X598061Y77582D02*
X598068Y77574D01*
G01X598056Y77590D02*
X598061Y77582D01*
G01X598051Y77600D02*
X598056Y77590D01*
G01X598048Y77610D02*
X598051Y77600D01*
G01X597999Y77286D02*
X596291D01*
G01D02*
X596279Y77284D01*
G01X596267Y77282D02*
X596255Y77279D01*
G01X596279Y77284D02*
X596267Y77282D01*
G01X596230Y77271D02*
X596216Y77266D01*
G01X596242Y77276D02*
X596230Y77271D01*
G01X596255Y77279D02*
X596242Y77276D01*
G01X596216Y77266D02*
X596204Y77262D01*
G01D02*
X596190Y77256D01*
G01D02*
X596176Y77250D01*
G01X596433Y77633D02*
Y80532D01*
G01Y77622D02*
Y77633D01*
G01X596432Y77612D02*
X596433Y77622D01*
G01X596430Y77603D02*
X596432Y77612D01*
G01X596427Y77594D02*
X596430Y77603D01*
G01X596424Y77586D02*
X596427Y77594D01*
G01X596420Y77579D02*
X596424Y77586D01*
G01X596415Y77573D02*
X596420Y77579D01*
G01X596409Y77567D02*
X596415Y77573D01*
G01X596403Y77562D02*
X596409Y77567D01*
G01X596396Y77558D02*
X596403Y77562D01*
G01X596388Y77555D02*
X596396Y77558D01*
G01X596379Y77553D02*
X596388Y77555D01*
G01X596370Y77550D02*
X596379Y77553D01*
G01X596360Y77550D02*
X596370D01*
G01X596350D02*
X596360D01*
G01X597033Y82506D02*
X596758Y82347D01*
G01X597316Y82648D02*
X597033Y82506D01*
G01X597400Y82281D02*
X597664Y82400D01*
G01X597605Y82774D02*
X597316Y82648D01*
G01X597664Y82400D02*
X597935Y82503D01*
G01X597902Y82883D02*
X597605Y82774D01*
G01X597935Y82503D02*
X598211Y82593D01*
G01X598204Y82976D02*
X597902Y82883D01*
G01X598058Y76565D02*
X598065Y76573D01*
G01X598050Y76558D02*
X598058Y76565D01*
G01X598041Y76552D02*
X598050Y76558D01*
G01X598032Y76547D02*
X598041Y76552D01*
G01X598021Y76544D02*
X598032Y76547D01*
G01X598011Y76542D02*
X598021Y76544D01*
G01X597999Y76541D02*
X598011Y76542D01*
G01X599249Y77644D02*
X597974Y76387D01*
G01X598082Y76624D02*
Y77202D01*
G01X598081Y76613D02*
X598082Y76624D01*
G01X598080Y76602D02*
X598081Y76613D01*
G01X598076Y76591D02*
X598080Y76602D01*
G01X598071Y76582D02*
X598076Y76591D01*
G01X598065Y76573D02*
X598071Y76582D01*
G01X596593Y76541D02*
X597999D01*
G01X596585Y76540D02*
X596593Y76541D01*
G01X596578Y76540D02*
X596585D01*
G01X596571Y76538D02*
X596578Y76540D01*
G01X596564Y76536D02*
X596571Y76538D01*
G01X596556Y76534D02*
X596564Y76536D01*
G01X596550Y76530D02*
X596556Y76534D01*
G01X596544Y76527D02*
X596550Y76530D01*
G01X596539Y76523D02*
X596544Y76527D01*
G01X596534Y76519D02*
X596539Y76523D01*
G01X596529Y76514D02*
X596534Y76519D01*
G01X596525Y76510D02*
X596529Y76514D01*
G01X596521Y76504D02*
X596525Y76510D01*
G01X596518Y76498D02*
X596521Y76504D01*
G01X596515Y76490D02*
X596518Y76498D01*
G01X596512Y76484D02*
X596515Y76490D01*
G01X596511Y76477D02*
X596512Y76484D01*
G01X596510Y76470D02*
X596511Y76477D01*
G01X596509Y76462D02*
X596510Y76470D01*
G01X589000Y110200D02*
Y105800D01*
G01D02*
X598000D01*
G01Y110200D02*
X589000D01*
G01X598000Y105800D02*
Y110200D01*
G01X589000Y94300D02*
X598000D01*
G01Y98700D02*
X589000D01*
G01D02*
Y94300D01*
G01X598000D02*
Y98700D01*
G01Y110300D02*
Y114700D01*
G01X589000Y110300D02*
X598000D01*
G01X589000Y114700D02*
Y110300D01*
G01Y104700D02*
Y100300D01*
G01X598000Y104700D02*
X589000D01*
G01X598000Y100300D02*
Y104700D01*
G01X589000Y100300D02*
X598000D01*
G01Y114700D02*
X589000D01*
G01X594050Y119567D02*
Y184559D01*
G01X661297Y119567D02*
X594050D01*
G01X589702Y188465D02*
X594102D01*
G01X589702Y197465D02*
Y188465D01*
G01X594102Y197465D02*
X589702D01*
G01X594102Y188465D02*
Y197465D01*
G01X594702Y188465D02*
X599102D01*
G01X594702Y197465D02*
Y188465D01*
G01X599102Y197465D02*
X594702D01*
G01X599102Y188465D02*
Y197465D01*
G01X604102D02*
X599702D01*
G01Y188465D02*
X604102D01*
G01X599702Y197465D02*
Y188465D01*
G01X594050Y184559D02*
X661297D01*
G01X592882Y201368D02*
Y217432D01*
G01X605118Y201368D02*
X592882D01*
G01X600500Y229200D02*
Y224800D01*
G01X609500Y229200D02*
X600500D01*
G01Y224800D02*
X609500D01*
G01X600500Y224700D02*
Y220300D01*
G01X609500Y224700D02*
X600500D01*
G01Y220300D02*
X609500D01*
G01X587553Y226100D02*
Y221700D01*
G01X596553Y226100D02*
X587553D01*
G01Y221700D02*
X596553D01*
G01D02*
Y226100D01*
G01X587553Y226202D02*
X596553D01*
G01X587553Y230602D02*
Y226202D01*
G01X596553Y230602D02*
X587553D01*
G01X596553Y226202D02*
Y230602D01*
G01X587553Y230800D02*
X596553D01*
G01X587553Y235200D02*
Y230800D01*
G01X596553D02*
Y235200D01*
G01X592882Y217432D02*
X605118D01*
G01X600800Y229600D02*
Y235200D01*
G01X611200Y229600D02*
X600800D01*
G01X596553Y235200D02*
X587553D01*
G01X600800D02*
X611200D01*
G01X593850Y256300D02*
Y306700D01*
G01X630350Y256300D02*
X593850D01*
G01Y306700D02*
X630350D01*
G01X587976Y405325D02*
Y416329D01*
G01X593520Y405325D02*
X587976D01*
G01X593520Y416329D02*
Y405325D01*
G01X599787D02*
Y416329D01*
G01X605331Y405325D02*
X599787D01*
G01Y419104D02*
Y430108D01*
G01X605331Y419104D02*
X599787D01*
G01X592948Y422527D02*
X587948D01*
G01X590448Y420027D02*
Y425027D01*
G01X587976Y416329D02*
X593520D01*
G01X598259Y418027D02*
X593259D01*
G01X595759Y415527D02*
Y420527D01*
G01X599787Y416329D02*
X605331D01*
G01X598259Y429306D02*
Y434306D01*
G01X600759Y431806D02*
X595759D01*
G01X599787Y430108D02*
X605331D01*
G01X608121Y74100D02*
X608139Y74178D01*
G01X608111Y74020D02*
X608121Y74100D01*
G01X608107Y73941D02*
X608111Y74020D01*
G01Y73861D02*
X608107Y73941D01*
G01X608121Y73782D02*
X608111Y73861D01*
G01X608139Y73703D02*
X608121Y73782D01*
G01X608807Y74828D02*
X608885Y74846D01*
G01X608726Y74802D02*
X608807Y74828D01*
G01X609044Y74860D02*
X613248D01*
G01X608964Y74857D02*
X609044Y74860D01*
G01X608885Y74846D02*
X608964Y74857D01*
G01X608321Y74527D02*
X608375Y74585D01*
G01X608273Y74465D02*
X608321Y74527D01*
G01X608500Y74688D02*
X608571Y74732D01*
G01X608435Y74638D02*
X608500Y74688D01*
G01X608375Y74585D02*
X608435Y74638D01*
G01X608646Y74770D02*
X608726Y74802D01*
G01X608571Y74732D02*
X608646Y74770D01*
G01X608163Y74254D02*
X608194Y74328D01*
G01X608139Y74178D02*
X608163Y74254D01*
G01X608231Y74398D02*
X608273Y74465D01*
G01X608194Y74328D02*
X608231Y74398D01*
G01X608571Y73150D02*
X608500Y73194D01*
G01D02*
X608435Y73242D01*
G01D02*
X608375Y73297D01*
G01D02*
X608321Y73354D01*
G01D02*
X608273Y73417D01*
G01X608885Y73035D02*
X608807Y73053D01*
G01D02*
X608726Y73078D01*
G01D02*
X608646Y73111D01*
G01D02*
X608571Y73150D01*
G01X611768Y73021D02*
X609044D01*
G01D02*
X608964Y73025D01*
G01D02*
X608885Y73035D01*
G01X608273Y73417D02*
X608231Y73483D01*
G01D02*
X608194Y73554D01*
G01D02*
X608163Y73627D01*
G01D02*
X608139Y73703D01*
G01X606898Y74810D02*
Y76694D01*
G01X606460Y74254D02*
X606863Y74657D01*
G01X606445Y74247D02*
X606460Y74254D01*
G01X606430Y74241D02*
X606445Y74247D01*
G01X606414Y74235D02*
X606430Y74241D01*
G01X606396Y74230D02*
X606414Y74235D01*
G01X606379Y74227D02*
X606396Y74230D01*
G01X606361Y74224D02*
X606379Y74227D01*
G01X606342Y74222D02*
X606361Y74224D01*
G01X606897Y74794D02*
X606898Y74810D01*
G01X606896Y74778D02*
X606897Y74794D01*
G01X606893Y74762D02*
X606896Y74778D01*
G01X606890Y74745D02*
X606893Y74762D01*
G01X606886Y74727D02*
X606890Y74745D01*
G01X606881Y74710D02*
X606886Y74727D01*
G01X606876Y74693D02*
X606881Y74710D01*
G01X606870Y74675D02*
X606876Y74693D01*
G01X606863Y74657D02*
X606870Y74675D01*
G01X606322Y74220D02*
X606342Y74222D01*
G01X606302Y74219D02*
X606322Y74220D01*
G01X602640Y75122D02*
X603132Y74289D01*
G01X603254Y74219D02*
X603951D01*
G01X603238Y74220D02*
X603254Y74219D01*
G01X603221Y74223D02*
X603238Y74220D01*
G01X603206Y74228D02*
X603221Y74223D01*
G01X603190Y74235D02*
X603206Y74228D01*
G01X603175Y74244D02*
X603190Y74235D01*
G01X603161Y74254D02*
X603175Y74244D01*
G01X603150Y74265D02*
X603161Y74254D01*
G01X603140Y74276D02*
X603150Y74265D01*
G01X603132Y74289D02*
X603140Y74276D01*
G01X603995Y74289D02*
X603451Y75196D01*
G01X604003Y74260D02*
X604002Y74267D01*
G01X604003Y74254D02*
Y74260D01*
G01X604002Y74247D02*
X604003Y74254D01*
G01X604000Y74241D02*
X604002Y74247D01*
G01X603996Y74236D02*
X604000Y74241D01*
G01X603992Y74232D02*
X603996Y74236D01*
G01X603987Y74228D02*
X603992Y74232D01*
G01X603981Y74225D02*
X603987Y74228D01*
G01X603974Y74222D02*
X603981Y74225D01*
G01X603967Y74221D02*
X603974Y74222D01*
G01X603959Y74219D02*
X603967Y74221D01*
G01X603951Y74219D02*
X603959D01*
G01X603998Y74282D02*
X603995Y74289D01*
G01X604000Y74274D02*
X603998Y74282D01*
G01X604002Y74267D02*
X604000Y74274D01*
G01X604405Y74219D02*
X606302D01*
G01X604395D02*
X604405D01*
G01X604385Y74221D02*
X604395Y74219D01*
G01X604376Y74222D02*
X604385Y74221D01*
G01X604368Y74225D02*
X604376Y74222D01*
G01X604360Y74228D02*
X604368Y74225D01*
G01X604352Y74233D02*
X604360Y74228D01*
G01X604346Y74238D02*
X604352Y74233D01*
G01X604340Y74242D02*
X604346Y74238D01*
G01X604336Y74249D02*
X604340Y74242D01*
G01X604331Y74257D02*
X604336Y74249D01*
G01X604328Y74265D02*
X604331Y74257D01*
G01X604325Y74273D02*
X604328Y74265D01*
G01X604324Y74282D02*
X604325Y74273D01*
G01X604322Y77202D02*
Y74302D01*
G01D02*
X604323Y74292D01*
G01D02*
X604324Y74282D01*
G01X602950Y73148D02*
X602716Y72982D01*
G01X602784Y72707D02*
X603038Y72879D01*
G01D02*
X603283Y73066D01*
G01X603175Y73327D02*
X602950Y73148D01*
G01X603283Y73066D02*
X603516Y73264D01*
G01X603389Y73518D02*
X603175Y73327D01*
G01X603516Y73264D02*
X603739Y73474D01*
G01X603594Y73719D02*
X603389Y73518D01*
G01X603789Y73933D02*
X603594Y73719D01*
G01X603739Y73474D02*
X603950Y73698D01*
G01X604152Y73933D02*
X603789D01*
G01X603950Y73698D02*
X604152Y73933D01*
G01X604548Y71182D02*
X611928D01*
G01X606123Y76541D02*
Y74959D01*
G01D02*
X605093D01*
G01D02*
Y76541D01*
G01X602636Y75127D02*
X602639Y75125D01*
G01X602634Y75130D02*
X602636Y75127D01*
G01X602639Y75125D02*
X602640Y75122D01*
G01X602630Y75133D02*
X602634Y75130D01*
G01X602627Y75135D02*
X602630Y75133D01*
G01X602623Y75137D02*
X602627Y75135D01*
G01X602619Y75138D02*
X602623Y75137D01*
G01X602614Y75138D02*
X602619D01*
G01X602610Y75139D02*
X602614Y75138D01*
G01X603451Y75196D02*
X603854Y75608D01*
G01X603123Y76571D02*
Y75826D01*
G01X603892Y75697D02*
X603895Y75711D01*
G01X603888Y75682D02*
X603892Y75697D01*
G01X603882Y75668D02*
X603888Y75682D01*
G01X603876Y75653D02*
X603882Y75668D01*
G01X603870Y75638D02*
X603876Y75653D01*
G01X603862Y75623D02*
X603870Y75638D01*
G01X603854Y75608D02*
X603862Y75623D01*
G01X603898Y75739D02*
Y76694D01*
G01X603897Y75726D02*
X603898Y75739D01*
G01X603895Y75711D02*
X603897Y75726D01*
G01X617123Y75771D02*
G02I-928J0D01*
G01X618795Y67942D02*
Y84057D01*
G01X613326Y74864D02*
X613405Y74874D01*
G01X613248Y74860D02*
X613326Y74864D01*
G01X613405Y74874D02*
X613484Y74892D01*
G01X613564Y74918D02*
X613644Y74950D01*
G01X613484Y74892D02*
X613564Y74918D01*
G01X612619Y72485D02*
X612582Y72556D01*
G01D02*
X612540Y72622D01*
G01X612688Y71934D02*
X612700Y72015D01*
G01Y72176D02*
X612691Y72255D01*
G01X612704Y72096D02*
X612700Y72176D01*
G01Y72015D02*
X612704Y72096D01*
G01X612691Y72255D02*
X612673Y72334D01*
G01D02*
X612649Y72410D01*
G01D02*
X612619Y72485D01*
G01X612571Y71618D02*
X612610Y71692D01*
G01X612527Y71548D02*
X612571Y71618D01*
G01X612670Y71853D02*
X612688Y71934D01*
G01X612644Y71772D02*
X612670Y71853D01*
G01X612610Y71692D02*
X612644Y71772D01*
G01X612314Y72846D02*
X612244Y72890D01*
G01D02*
X612168Y72929D01*
G01X612540Y72622D02*
X612492Y72684D01*
G01D02*
X612439Y72742D01*
G01D02*
X612380Y72796D01*
G01D02*
X612314Y72846D01*
G01X612254Y71286D02*
X612312Y71326D01*
G01X612197Y71253D02*
X612254Y71286D01*
G01X612140Y71226D02*
X612197Y71253D01*
G01X612369Y71372D02*
X612424Y71424D01*
G01X612312Y71326D02*
X612369Y71372D01*
G01X612476Y71483D02*
X612527Y71548D01*
G01X612424Y71424D02*
X612476Y71483D01*
G01X612087Y72962D02*
X612006Y72989D01*
G01D02*
X611927Y73006D01*
G01D02*
X611847Y73018D01*
G01D02*
X611768Y73021D01*
G01X612168Y72929D02*
X612087Y72962D01*
G01X611978Y71184D02*
X612031Y71192D01*
G01X611928Y71182D02*
X611978Y71184D01*
G01X612084Y71206D02*
X612140Y71226D01*
G01X612031Y71192D02*
X612084Y71206D01*
G01X613644Y74950D02*
X613720Y74989D01*
G01X614097Y75393D02*
X614128Y75466D01*
G01X614060Y75322D02*
X614097Y75393D01*
G01X614128Y75466D02*
X614152Y75542D01*
G01X613720Y74989D02*
X613790Y75033D01*
G01X613856Y75082D02*
X613916Y75136D01*
G01X613790Y75033D02*
X613856Y75082D01*
G01X614018Y75256D02*
X614060Y75322D01*
G01X613970Y75194D02*
X614018Y75256D01*
G01X613916Y75136D02*
X613970Y75194D01*
G01X614180Y75700D02*
X614184Y75780D01*
G01X614169Y75621D02*
X614180Y75700D01*
G01Y75860D02*
X614169Y75939D01*
G01X614184Y75780D02*
X614180Y75860D01*
G01X614060Y76238D02*
X614018Y76304D01*
G01X614152Y75542D02*
X614169Y75621D01*
G01Y75939D02*
X614152Y76017D01*
G01D02*
X614128Y76094D01*
G01D02*
X614097Y76167D01*
G01D02*
X614060Y76238D01*
G01X608902Y84054D02*
X608823Y84057D01*
G01X609140Y83999D02*
X609060Y84025D01*
G01D02*
X608980Y84042D01*
G01D02*
X608902Y84054D01*
G01X609432Y83835D02*
X609366Y83884D01*
G01D02*
X609296Y83928D01*
G01D02*
X609220Y83966D01*
G01D02*
X609140Y83999D01*
G01X609672Y83525D02*
X609636Y83595D01*
G01D02*
X609593Y83661D01*
G01D02*
X609545Y83723D01*
G01D02*
X609492Y83782D01*
G01D02*
X609432Y83835D01*
G01X609704Y83450D02*
X609672Y83525D01*
G01X609835Y77697D02*
X609846Y77773D01*
G01X609920Y78003D02*
X609957Y78076D01*
G01X609888Y77926D02*
X609920Y78003D01*
G01X609863Y77850D02*
X609888Y77926D01*
G01X609846Y77773D02*
X609863Y77850D01*
G01X609957Y78076D02*
X610000Y78144D01*
G01X610104Y78266D02*
X610162Y78321D01*
G01X610049Y78208D02*
X610104Y78266D01*
G01X610000Y78144D02*
X610049Y78208D01*
G01X610227Y78369D02*
X610296Y78412D01*
G01X610162Y78321D02*
X610227Y78369D01*
G01X609888Y77312D02*
X609863Y77389D01*
G01X609920Y77235D02*
X609888Y77312D01*
G01X609863Y77389D02*
X609846Y77466D01*
G01D02*
X609835Y77542D01*
G01X609832Y77619D02*
X609835Y77697D01*
G01Y77542D02*
X609832Y77619D01*
G01X608823Y82218D02*
X608902Y82221D01*
G01X609060Y82250D02*
X609140Y82275D01*
G01X608980Y82232D02*
X609060Y82250D01*
G01X608902Y82221D02*
X608980Y82232D01*
G01X609220Y82308D02*
X609296Y82346D01*
G01X609140Y82275D02*
X609220Y82308D01*
G01X609366Y82390D02*
X609432Y82439D01*
G01X609296Y82346D02*
X609366Y82390D01*
G01X609593Y82614D02*
X609636Y82679D01*
G01X609545Y82551D02*
X609593Y82614D01*
G01X609492Y82494D02*
X609545Y82551D01*
G01X609432Y82439D02*
X609492Y82494D01*
G01X609704Y82824D02*
X609728Y82900D01*
G01X609672Y82750D02*
X609704Y82824D01*
G01X609636Y82679D02*
X609672Y82750D01*
G01X609728Y83374D02*
X609704Y83450D01*
G01X609728Y82900D02*
X609745Y82978D01*
G01X609760Y83137D02*
X609756Y83217D01*
G01Y83058D02*
X609760Y83137D01*
G01X609745Y82978D02*
X609756Y83058D01*
G01X609745Y83297D02*
X609728Y83374D01*
G01X609756Y83217D02*
X609745Y83297D01*
G01X610000Y77094D02*
X609957Y77162D01*
G01D02*
X609920Y77235D01*
G01X610296Y76826D02*
X610227Y76870D01*
G01D02*
X610162Y76918D01*
G01D02*
X610104Y76972D01*
G01D02*
X610049Y77030D01*
G01D02*
X610000Y77094D01*
G01X606360Y82047D02*
X606429Y82090D01*
G01X606504Y82128D02*
X606582Y82161D01*
G01X606429Y82090D02*
X606504Y82128D01*
G01X606582Y80435D02*
X606504Y80468D01*
G01D02*
X606429Y80505D01*
G01D02*
X606360Y80548D01*
G01X606902Y80378D02*
X606821Y80382D01*
G01D02*
X606740Y80393D01*
G01D02*
X606661Y80410D01*
G01D02*
X606582Y80435D01*
G01X617859Y80378D02*
X606902D01*
G01X606582Y82161D02*
X606661Y82186D01*
G01X606460Y77250D02*
X606442Y77258D01*
G01X606424Y77263D02*
X606406Y77269D01*
G01X606442Y77258D02*
X606424Y77263D01*
G01X606406Y77269D02*
X606388Y77274D01*
G01X606370Y77278D02*
X606352Y77281D01*
G01X606388Y77274D02*
X606370Y77278D01*
G01X606296Y80597D02*
X606237Y80650D01*
G01D02*
X606184Y80710D01*
G01D02*
X606134Y80774D01*
G01D02*
X606091Y80841D01*
G01D02*
X606054Y80914D01*
G01X606022Y80990D02*
X605997Y81068D01*
G01X606054Y80914D02*
X606022Y80990D01*
G01X605980Y81144D02*
X605969Y81221D01*
G01X605997Y81068D02*
X605980Y81144D01*
G01Y81452D02*
X605997Y81528D01*
G01X605969Y81375D02*
X605980Y81452D01*
G01X605966Y81298D02*
X605969Y81375D01*
G01Y81221D02*
X605966Y81298D01*
G01X606091Y81754D02*
X606134Y81822D01*
G01X606054Y81682D02*
X606091Y81754D01*
G01X606022Y81606D02*
X606054Y81682D01*
G01X605997Y81528D02*
X606022Y81606D01*
G01X606237Y81946D02*
X606296Y81999D01*
G01X606184Y81886D02*
X606237Y81946D01*
G01X606134Y81822D02*
X606184Y81886D01*
G01X606296Y81999D02*
X606360Y82047D01*
G01Y80548D02*
X606296Y80597D01*
G01X605408Y77498D02*
X605399Y77818D01*
G01X606336Y77283D02*
X606319Y77285D01*
G01X606352Y77281D02*
X606336Y77283D01*
G01X606319Y77285D02*
X606302Y77286D01*
G01X605399Y77818D02*
X605372Y78136D01*
G01D02*
X605328Y78450D01*
G01X606821Y82214D02*
X606902Y82218D01*
G01X606740Y82203D02*
X606821Y82214D01*
G01X606661Y82186D02*
X606740Y82203D01*
G01X606902Y82218D02*
X608823D01*
G01X606863Y76847D02*
X606460Y77250D01*
G01X606896Y76726D02*
X606893Y76743D01*
G01X606897Y76710D02*
X606896Y76726D01*
G01X606898Y76694D02*
X606897Y76710D01*
G01X606870Y76830D02*
X606863Y76847D01*
G01X606876Y76811D02*
X606870Y76830D01*
G01X606881Y76794D02*
X606876Y76811D01*
G01X606886Y76777D02*
X606881Y76794D01*
G01X606890Y76759D02*
X606886Y76777D01*
G01X606893Y76743D02*
X606890Y76759D01*
G01X602688Y80583D02*
X602680Y80591D01*
G01X602693Y80574D02*
X602688Y80583D01*
G01X602664Y80605D02*
X602654Y80609D01*
G01X602672Y80598D02*
X602664Y80605D01*
G01X602680Y80591D02*
X602672Y80598D01*
G01X602654Y80609D02*
X602644Y80613D01*
G01X602632Y80615D02*
X602621Y80616D01*
G01X602644Y80613D02*
X602632Y80615D01*
G01X602678Y81924D02*
X602916Y81757D01*
G01X603036Y82118D02*
X602774Y82295D01*
G01X602916Y81757D02*
X603147Y81576D01*
G01X603289Y81925D02*
X603036Y82118D01*
G01X603147Y81576D02*
X603367Y81384D01*
G01X603531Y81719D02*
X603289Y81925D01*
G01X603576Y81180D02*
X603774Y80965D01*
G01X603367Y81384D02*
X603576Y81180D01*
G01X603760Y81500D02*
X603531Y81719D01*
G01X603774Y80965D02*
X603960Y80739D01*
G01X603978Y81267D02*
X603760Y81500D01*
G01X604372Y80770D02*
X604182Y81024D01*
G01D02*
X603978Y81267D01*
G01X602704Y79981D02*
Y80532D01*
G01Y79970D02*
Y79981D01*
G01X602701Y79959D02*
X602704Y79970D01*
G01X602698Y79950D02*
X602701Y79959D01*
G01X602693Y79940D02*
X602698Y79950D01*
G01X602688Y79931D02*
X602693Y79940D01*
G01X602681Y79924D02*
X602688Y79931D01*
G01X602673Y79918D02*
X602681Y79924D01*
G01X602664Y79912D02*
X602673Y79918D01*
G01X602655Y79908D02*
X602664Y79912D01*
G01X602644Y79905D02*
X602655Y79908D01*
G01X602633Y79902D02*
X602644Y79905D01*
G01X602621Y79902D02*
X602633D01*
G01X602698Y80565D02*
X602693Y80574D01*
G01X602701Y80554D02*
X602698Y80565D01*
G01X602704Y80544D02*
X602701Y80554D01*
G01X602704Y80532D02*
Y80544D01*
G01X604132Y80505D02*
X604293Y80261D01*
G01X603960Y80739D02*
X604132Y80505D01*
G01X604440Y80010D02*
X604572Y79750D01*
G01X604293Y80261D02*
X604440Y80010D01*
G01X604548Y80506D02*
X604372Y80770D01*
G01X604852Y79951D02*
X604708Y80233D01*
G01D02*
X604548Y80506D01*
G01X602688Y78231D02*
X602680Y78239D01*
G01X602693Y78222D02*
X602688Y78231D01*
G01X602698Y78212D02*
X602693Y78222D01*
G01X602701Y78202D02*
X602698Y78212D01*
G01X602704Y78191D02*
X602701Y78202D01*
G01X602704Y78180D02*
Y78191D01*
G01X602664Y78252D02*
X602654Y78257D01*
G01X602672Y78246D02*
X602664Y78252D01*
G01X602680Y78239D02*
X602672Y78246D01*
G01X602633Y78262D02*
X602621Y78263D01*
G01X602644Y78260D02*
X602633Y78262D01*
G01X602654Y78257D02*
X602644Y78260D01*
G01X604793Y79214D02*
X604881Y78938D01*
G01X604690Y79485D02*
X604793Y79214D01*
G01X604572Y79750D02*
X604690Y79485D01*
G01X605055Y78084D02*
X605081Y77793D01*
G01X605012Y78371D02*
X605055Y78084D01*
G01X604955Y78656D02*
X605012Y78371D01*
G01X604881Y78938D02*
X604955Y78656D01*
G01X605093Y79367D02*
X604981Y79662D01*
G01D02*
X604852Y79951D01*
G01X605328Y78450D02*
X605268Y78759D01*
G01D02*
X605188Y79066D01*
G01D02*
X605093Y79367D01*
G01X602704Y77633D02*
Y78180D01*
G01Y77621D02*
Y77633D01*
G01X602701Y77610D02*
X602704Y77621D01*
G01X602698Y77600D02*
X602701Y77610D01*
G01X602693Y77590D02*
X602698Y77600D01*
G01X602688Y77582D02*
X602693Y77590D01*
G01X602680Y77574D02*
X602688Y77582D01*
G01X602672Y77566D02*
X602680Y77574D01*
G01X602664Y77561D02*
X602672Y77566D01*
G01X602654Y77556D02*
X602664Y77561D01*
G01X602644Y77552D02*
X602654Y77556D01*
G01X602632Y77550D02*
X602644Y77552D01*
G01X602621Y77550D02*
X602632D01*
G01X603370Y77278D02*
X603352Y77281D01*
G01X603336Y77283D02*
X603319Y77285D01*
G01X603352Y77281D02*
X603336Y77283D01*
G01X603319Y77285D02*
X603302Y77286D01*
G01X603460Y77250D02*
X603442Y77258D01*
G01X603424Y77263D02*
X603406Y77269D01*
G01X603442Y77258D02*
X603424Y77263D01*
G01X603406Y77269D02*
X603388Y77274D01*
G01D02*
X603370Y77278D01*
G01X606302Y77286D02*
X604405D01*
G01X604394Y77285D02*
X604383Y77282D01*
G01X604405Y77286D02*
X604394Y77285D01*
G01X604363Y77274D02*
X604354Y77268D01*
G01X604372Y77279D02*
X604363Y77274D01*
G01X604383Y77282D02*
X604372Y77279D01*
G01X604354Y77268D02*
X604346Y77262D01*
G01X604333Y77244D02*
X604328Y77234D01*
G01X604339Y77254D02*
X604333Y77244D01*
G01X604346Y77262D02*
X604339Y77254D01*
G01X604328Y77234D02*
X604325Y77225D01*
G01X604323Y77214D02*
X604322Y77202D01*
G01X604325Y77225D02*
X604323Y77214D01*
G01X605081Y77793D02*
X605092Y77498D01*
G01D02*
X605408D01*
G01X603863Y76847D02*
X603460Y77250D01*
G01X603896Y76726D02*
X603893Y76743D01*
G01X603897Y76710D02*
X603896Y76726D01*
G01X603898Y76694D02*
X603897Y76710D01*
G01X603870Y76830D02*
X603863Y76847D01*
G01X603876Y76811D02*
X603870Y76830D01*
G01X603881Y76794D02*
X603876Y76811D01*
G01X603886Y76777D02*
X603881Y76794D01*
G01X603890Y76759D02*
X603886Y76777D01*
G01X603893Y76743D02*
X603890Y76759D01*
G01X605093Y76541D02*
X606123D01*
G01X610448Y78482D02*
X610528Y78506D01*
G01X610369Y78450D02*
X610448Y78482D01*
G01X610296Y78412D02*
X610369Y78450D01*
G01X610528Y76732D02*
X610448Y76757D01*
G01D02*
X610369Y76789D01*
G01D02*
X610296Y76826D01*
G01X618096Y80346D02*
X618017Y80364D01*
G01D02*
X617938Y80375D01*
G01X618402Y80206D02*
X618332Y80250D01*
G01D02*
X618256Y80288D01*
G01D02*
X618176Y80321D01*
G01D02*
X618096Y80346D01*
G01X618672Y79916D02*
X618629Y79982D01*
G01D02*
X618581Y80045D01*
G01D02*
X618528Y80102D01*
G01D02*
X618468Y80156D01*
G01D02*
X618402Y80206D01*
G01X618739Y79772D02*
X618708Y79846D01*
G01D02*
X618672Y79916D01*
G01X618017Y78553D02*
X618096Y78571D01*
G01X617938Y78542D02*
X618017Y78553D01*
G01X618096Y78571D02*
X618176Y78596D01*
G01X618332Y78668D02*
X618402Y78711D01*
G01X618256Y78630D02*
X618332Y78668D01*
G01X618176Y78596D02*
X618256Y78630D01*
G01X618581Y78873D02*
X618629Y78935D01*
G01X618528Y78814D02*
X618581Y78873D01*
G01X618468Y78761D02*
X618528Y78814D01*
G01X618402Y78711D02*
X618468Y78761D01*
G01X618629Y78935D02*
X618672Y79001D01*
G01X618739Y79146D02*
X618764Y79222D01*
G01X618708Y79071D02*
X618739Y79146D01*
G01X618672Y79001D02*
X618708Y79071D01*
G01X618792Y79379D02*
X618795Y79458D01*
G01X618780Y79299D02*
X618792Y79379D01*
G01X618764Y79222D02*
X618780Y79299D01*
G01X618792Y79538D02*
X618780Y79618D01*
G01X618795Y79458D02*
X618792Y79538D01*
G01X618780Y79618D02*
X618764Y79696D01*
G01D02*
X618739Y79772D01*
G01X617938Y80375D02*
X617859Y80378D01*
G01Y78539D02*
X617938Y78542D01*
G01X613229Y84042D02*
X613150Y84054D01*
G01D02*
X613068Y84057D01*
G01X613457Y83970D02*
X613383Y84002D01*
G01D02*
X613307Y84026D01*
G01D02*
X613229Y84042D01*
G01X613528Y83934D02*
X613457Y83970D01*
G01X613772Y83729D02*
X613718Y83788D01*
G01D02*
X613660Y83842D01*
G01D02*
X613596Y83891D01*
G01D02*
X613528Y83934D01*
G01X613902Y83526D02*
X613865Y83596D01*
G01D02*
X613822Y83664D01*
G01D02*
X613772Y83729D01*
G01X613933Y83452D02*
X613902Y83526D01*
G01X611338Y83787D02*
X611284Y83729D01*
G01D02*
X611236Y83666D01*
G01D02*
X611193Y83598D01*
G01D02*
X611156Y83526D01*
G01X611460Y83889D02*
X611396Y83841D01*
G01D02*
X611338Y83787D01*
G01X611755Y84026D02*
X611677Y84001D01*
G01D02*
X611600Y83969D01*
G01D02*
X611528Y83932D01*
G01D02*
X611460Y83889D01*
G01X611988Y84057D02*
X611910Y84054D01*
G01D02*
X611832Y84042D01*
G01D02*
X611755Y84026D01*
G01X611156Y83526D02*
X611124Y83448D01*
G01X613150Y82222D02*
X613229Y82232D01*
G01X613068Y82218D02*
X613150Y82222D01*
G01X613383Y82273D02*
X613457Y82304D01*
G01X613307Y82249D02*
X613383Y82273D01*
G01X613229Y82232D02*
X613307Y82249D01*
G01X613457Y82304D02*
X613528Y82341D01*
G01D02*
X613596Y82383D01*
G01X613718Y82486D02*
X613772Y82546D01*
G01X613660Y82433D02*
X613718Y82486D01*
G01X613596Y82383D02*
X613660Y82433D01*
G01X613822Y82610D02*
X613865Y82678D01*
G01X613772Y82546D02*
X613822Y82610D01*
G01X613957Y82899D02*
X613974Y82977D01*
G01X613933Y82823D02*
X613957Y82899D01*
G01X613902Y82749D02*
X613933Y82823D01*
G01X613865Y82678D02*
X613902Y82749D01*
G01X613988Y83137D02*
X613985Y83218D01*
G01Y83057D02*
X613988Y83137D01*
G01X613974Y82977D02*
X613985Y83057D01*
G01Y83218D02*
X613974Y83298D01*
G01X613957Y83375D02*
X613933Y83452D01*
G01X613974Y83298D02*
X613957Y83375D01*
G01X613405Y76686D02*
X613326Y76696D01*
G01D02*
X613248Y76700D01*
G01X614018Y76304D02*
X613970Y76366D01*
G01X613484Y76668D02*
X613405Y76686D01*
G01X613790Y76527D02*
X613720Y76571D01*
G01D02*
X613644Y76609D01*
G01D02*
X613564Y76642D01*
G01D02*
X613484Y76668D01*
G01X613970Y76366D02*
X613916Y76424D01*
G01D02*
X613856Y76478D01*
G01D02*
X613790Y76527D01*
G01X610528Y78506D02*
X610607Y78525D01*
G01X610768Y78539D02*
X617859D01*
G01X610687Y78535D02*
X610768Y78539D01*
G01X610607Y78525D02*
X610687Y78535D01*
G01X611396Y82434D02*
X611460Y82386D01*
G01X611338Y82487D02*
X611396Y82434D01*
G01X611284Y82546D02*
X611338Y82487D01*
G01X611236Y82609D02*
X611284Y82546D01*
G01X611193Y82677D02*
X611236Y82609D01*
G01X611156Y82750D02*
X611193Y82677D01*
G01X611677Y82274D02*
X611755Y82249D01*
G01X611600Y82306D02*
X611677Y82274D01*
G01X611528Y82342D02*
X611600Y82306D01*
G01X611460Y82386D02*
X611528Y82342D01*
G01X611988Y82218D02*
X613068D01*
G01X611910Y82222D02*
X611988Y82218D01*
G01X611832Y82231D02*
X611910Y82222D01*
G01X611755Y82249D02*
X611832Y82231D01*
G01X611124Y82826D02*
X611156Y82750D01*
G01X611100Y82904D02*
X611124Y82826D01*
G01X611083Y82981D02*
X611100Y82904D01*
G01X611072Y83216D02*
X611068Y83137D01*
G01X611072Y83058D02*
X611083Y82981D01*
G01X611068Y83137D02*
X611072Y83058D01*
G01X611124Y83448D02*
X611100Y83370D01*
G01D02*
X611083Y83294D01*
G01D02*
X611072Y83216D01*
G01X610607Y76714D02*
X610528Y76732D01*
G01X613248Y76700D02*
X610768D01*
G01D02*
X610687Y76703D01*
G01D02*
X610607Y76714D01*
G01X604450Y98760D02*
X610500D01*
G01X604450Y110240D02*
Y98760D01*
G01X610500Y110240D02*
X604450D01*
G01X610500Y97500D02*
X624500D01*
G01X610500Y98760D02*
Y97500D01*
G01Y111500D02*
Y110240D01*
G01X624500Y111500D02*
X610500D01*
G01X618800Y194174D02*
X626200D01*
G01X618800Y206574D02*
Y194174D01*
G01X604702Y188465D02*
X609102D01*
G01X604702Y197465D02*
Y188465D01*
G01X609102Y197465D02*
X604702D01*
G01X609102Y188465D02*
Y197465D01*
G01X604102Y188465D02*
Y197465D01*
G01X626200Y206574D02*
X618800D01*
G01X605118Y217432D02*
Y201368D01*
G01X609500Y224800D02*
Y229200D01*
G01Y220300D02*
Y224700D01*
G01X616300Y225400D02*
Y234400D01*
G01X611900Y225400D02*
X616300D01*
G01X611900Y234400D02*
Y225400D01*
G01X611200Y235200D02*
Y229600D01*
G01X616300Y234400D02*
X611900D01*
G01X605331Y416329D02*
Y405325D01*
G01X611598D02*
Y416329D01*
G01X617142Y405325D02*
X611598D01*
G01X617142Y416329D02*
Y405325D01*
G01X605331Y430108D02*
Y419104D01*
G01X611598D02*
Y430108D01*
G01X617142Y419104D02*
X611598D01*
G01X617142Y430108D02*
Y419104D01*
G01X611070Y417027D02*
X606070D01*
G01X608570Y414527D02*
Y419527D01*
G01X611598Y416329D02*
X617142D01*
G01X610070Y429806D02*
Y434806D01*
G01X612570Y432306D02*
X607570D01*
G01X611598Y430108D02*
X617142D01*
G01X635500Y94300D02*
X644500D01*
G01X635500Y98700D02*
Y94300D01*
G01X644500Y98700D02*
X635500D01*
G01Y99800D02*
X644500D01*
G01X635500Y104200D02*
Y99800D01*
G01X644500Y104200D02*
X635500D01*
G01Y105800D02*
X644500D01*
G01X635500Y110200D02*
Y105800D01*
G01X644500Y110200D02*
X635500D01*
G01X624500Y98760D02*
X630550D01*
G01X624500Y97500D02*
Y98760D01*
G01X630550Y110240D02*
X624500D01*
G01D02*
Y111500D01*
G01X630550Y98760D02*
Y110240D01*
G01X635500Y111300D02*
X644500D01*
G01X635500Y115700D02*
Y111300D01*
G01X644500Y115700D02*
X635500D01*
G01X637102Y193882D02*
Y228166D01*
G01X661637Y193882D02*
X637102D01*
G01X626700Y194674D02*
X631100D01*
G01X626700Y203674D02*
Y194674D01*
G01X631100D02*
Y203674D01*
G01X626200Y194174D02*
Y206574D01*
G01X631100Y203674D02*
X626700D01*
G01X637102Y228166D02*
X661637D01*
G01X621249Y221684D02*
Y216834D01*
G01X620280Y221684D02*
X621249D01*
G01X620280Y229984D02*
Y221684D01*
G01X621249Y229984D02*
X620280D01*
G01X621249Y234834D02*
Y229984D01*
G01Y216834D02*
X632729D01*
G01Y229984D02*
Y234834D01*
G01X633698Y229984D02*
X632729D01*
G01X633698Y221684D02*
Y229984D01*
G01X632729Y221684D02*
X633698D01*
G01X632729Y216834D02*
Y221684D01*
G01Y234834D02*
X621249D01*
G01X630350Y306700D02*
Y256300D01*
G01X644500Y94300D02*
Y98700D01*
G01Y99800D02*
Y104200D01*
G01Y105800D02*
Y110200D01*
G01Y111300D02*
Y115700D01*
G01X661297Y184559D02*
Y119567D01*
G01X661637Y228166D02*
Y193882D01*
G01X661787Y379897D02*
Y322071D01*
G01X6853Y25450D02*
Y28550D01*
X7850Y25967D01*
X8847Y28550D01*
Y25450D01*
G01X11717D02*
X10183D01*
Y28550D01*
X11717D01*
G01X11103Y27052D02*
X10183D01*
G01X14050Y25450D02*
Y28550D01*
X13590Y27930D01*
G01Y25450D02*
X14510D01*
G01X17150Y28550D02*
X16843Y28447D01*
X16613Y28188D01*
X16460Y27878D01*
X16345Y27465D01*
X16307Y27000D01*
X16345Y26535D01*
X16460Y26122D01*
X16613Y25812D01*
X16843Y25553D01*
X17150Y25450D01*
X17457Y25553D01*
X17687Y25812D01*
X17840Y26122D01*
X17955Y26535D01*
X17993Y27000D01*
X17955Y27465D01*
X17840Y27878D01*
X17687Y28188D01*
X17457Y28447D01*
X17150Y28550D01*
G01X6630Y53500D02*
X7397D01*
Y52570D01*
X7167Y52260D01*
X6898Y52053D01*
X6515Y51950D01*
X6132Y52053D01*
X5863Y52260D01*
X5633Y52570D01*
X5480Y52932D01*
X5403Y53345D01*
Y53707D01*
X5480Y54017D01*
X5633Y54378D01*
X5863Y54688D01*
X6093Y54895D01*
X6400Y55050D01*
X6668D01*
X6975Y54947D01*
X7205Y54740D01*
G01X8695Y51950D02*
Y55050D01*
G01X10305D02*
Y51950D01*
G01Y53500D02*
X8695D01*
G01X11757Y52570D02*
X11987Y52208D01*
X12293Y52002D01*
X12638Y51950D01*
X12945Y52002D01*
X13252Y52260D01*
X13443Y52570D01*
X13482Y52880D01*
X13405Y53242D01*
X13137Y53500D01*
X12868Y53603D01*
X12523D01*
G01X12868D02*
X13098Y53758D01*
X13290Y54017D01*
X13367Y54327D01*
X13290Y54637D01*
X13098Y54895D01*
X12753Y55050D01*
X12408Y54998D01*
X12063Y54792D01*
G01X7750Y88000D02*
X5250D01*
X5750Y87680D01*
G01X7750D02*
Y88320D01*
G01X3507Y105950D02*
Y109050D01*
X4273D01*
X4580Y108895D01*
X4810Y108688D01*
X5002Y108378D01*
X5155Y108017D01*
X5193Y107500D01*
X5155Y106983D01*
X5002Y106622D01*
X4810Y106312D01*
X4580Y106105D01*
X4273Y105950D01*
X3507D01*
G01X6645Y106363D02*
X6952Y106105D01*
X7297Y105950D01*
X7603D01*
X7910Y106105D01*
X8140Y106363D01*
X8255Y106725D01*
X8178Y107087D01*
X7987Y107397D01*
X7642Y107603D01*
X7182Y107707D01*
X6913Y107913D01*
X6798Y108275D01*
X6875Y108637D01*
X7067Y108895D01*
X7335Y109050D01*
X7603D01*
X7872Y108947D01*
X8102Y108688D01*
G01X10550Y105950D02*
Y109050D01*
X10090Y108430D01*
G01Y105950D02*
X11010D01*
G01X12807Y106415D02*
X13037Y106157D01*
X13305Y106002D01*
X13650Y105950D01*
X13995Y106053D01*
X14263Y106260D01*
X14455Y106622D01*
X14493Y107035D01*
X14417Y107448D01*
X14225Y107707D01*
X13957Y107913D01*
X13688Y107965D01*
X13420Y107913D01*
X13075Y107707D01*
X13190Y109050D01*
X14225D01*
G01X7960Y111500D02*
X8493D01*
Y110750D01*
X8333Y110500D01*
X8147Y110333D01*
X7880Y110250D01*
X7613Y110333D01*
X7427Y110500D01*
X7267Y110750D01*
X7160Y111042D01*
X7107Y111375D01*
Y111667D01*
X7160Y111917D01*
X7267Y112208D01*
X7427Y112458D01*
X7587Y112625D01*
X7800Y112750D01*
X7987D01*
X8200Y112667D01*
X8360Y112500D01*
G01X9440Y110250D02*
Y112750D01*
G01X10560D02*
Y110250D01*
G01Y111500D02*
X9440D01*
G01X11613Y110750D02*
X11773Y110458D01*
X11987Y110292D01*
X12227Y110250D01*
X12440Y110292D01*
X12653Y110500D01*
X12787Y110750D01*
X12813Y111000D01*
X12760Y111292D01*
X12573Y111500D01*
X12387Y111583D01*
X12147D01*
G01X12387D02*
X12547Y111708D01*
X12680Y111917D01*
X12733Y112167D01*
X12680Y112417D01*
X12547Y112625D01*
X12307Y112750D01*
X12067Y112708D01*
X11827Y112542D01*
G01X8785Y144582D02*
X5685D01*
X6305Y144122D01*
G01X8785D02*
Y145042D01*
G01X5507Y163450D02*
Y166550D01*
X6273D01*
X6580Y166395D01*
X6810Y166188D01*
X7002Y165878D01*
X7155Y165517D01*
X7193Y165000D01*
X7155Y164483D01*
X7002Y164122D01*
X6810Y163812D01*
X6580Y163605D01*
X6273Y163450D01*
X5507D01*
G01X8645Y163863D02*
X8952Y163605D01*
X9297Y163450D01*
X9603D01*
X9910Y163605D01*
X10140Y163863D01*
X10255Y164225D01*
X10178Y164587D01*
X9987Y164897D01*
X9642Y165103D01*
X9182Y165207D01*
X8913Y165413D01*
X8798Y165775D01*
X8875Y166137D01*
X9067Y166395D01*
X9335Y166550D01*
X9603D01*
X9872Y166447D01*
X10102Y166188D01*
G01X12550Y163450D02*
Y166550D01*
X12090Y165930D01*
G01Y163450D02*
X13010D01*
G01X16110D02*
Y166550D01*
X14692Y164328D01*
X16608D01*
G01X3820Y163750D02*
Y166250D01*
X2833Y164458D01*
X4167D01*
G01X7460Y168500D02*
X7993D01*
Y167750D01*
X7833Y167500D01*
X7647Y167333D01*
X7380Y167250D01*
X7113Y167333D01*
X6927Y167500D01*
X6767Y167750D01*
X6660Y168042D01*
X6607Y168375D01*
Y168667D01*
X6660Y168917D01*
X6767Y169208D01*
X6927Y169458D01*
X7087Y169625D01*
X7300Y169750D01*
X7487D01*
X7700Y169667D01*
X7860Y169500D01*
G01X8940Y167250D02*
Y169750D01*
G01X10060D02*
Y167250D01*
G01Y168500D02*
X8940D01*
G01X11113Y167750D02*
X11273Y167458D01*
X11487Y167292D01*
X11727Y167250D01*
X11940Y167292D01*
X12153Y167500D01*
X12287Y167750D01*
X12313Y168000D01*
X12260Y168292D01*
X12073Y168500D01*
X11887Y168583D01*
X11647D01*
G01X11887D02*
X12047Y168708D01*
X12180Y168917D01*
X12233Y169167D01*
X12180Y169417D01*
X12047Y169625D01*
X11807Y169750D01*
X11567Y169708D01*
X11327Y169542D01*
G01X8785Y201669D02*
X5685D01*
X6305Y201209D01*
G01X8785D02*
Y202129D01*
G01X3507Y220950D02*
Y224050D01*
X4273D01*
X4580Y223895D01*
X4810Y223688D01*
X5002Y223378D01*
X5155Y223017D01*
X5193Y222500D01*
X5155Y221983D01*
X5002Y221622D01*
X4810Y221312D01*
X4580Y221105D01*
X4273Y220950D01*
X3507D01*
G01X6645Y221363D02*
X6952Y221105D01*
X7297Y220950D01*
X7603D01*
X7910Y221105D01*
X8140Y221363D01*
X8255Y221725D01*
X8178Y222087D01*
X7987Y222397D01*
X7642Y222603D01*
X7182Y222707D01*
X6913Y222913D01*
X6798Y223275D01*
X6875Y223637D01*
X7067Y223895D01*
X7335Y224050D01*
X7603D01*
X7872Y223947D01*
X8102Y223688D01*
G01X10550Y220950D02*
Y224050D01*
X10090Y223430D01*
G01Y220950D02*
X11010D01*
G01X13573D02*
X13650Y221622D01*
X13765Y222190D01*
X13918Y222707D01*
X14110Y223275D01*
X14417Y224050D01*
X12883D01*
G01X8785Y258755D02*
X5685D01*
X6305Y258295D01*
G01X8785D02*
Y259215D01*
G01X10050Y303007D02*
X6950D01*
Y303773D01*
X7105Y304080D01*
X7312Y304310D01*
X7622Y304502D01*
X7983Y304655D01*
X8500Y304693D01*
X9017Y304655D01*
X9378Y304502D01*
X9688Y304310D01*
X9895Y304080D01*
X10050Y303773D01*
Y303007D01*
G01X9637Y306145D02*
X9895Y306452D01*
X10050Y306797D01*
Y307103D01*
X9895Y307410D01*
X9637Y307640D01*
X9275Y307755D01*
X8913Y307678D01*
X8603Y307487D01*
X8397Y307142D01*
X8293Y306682D01*
X8087Y306413D01*
X7725Y306298D01*
X7363Y306375D01*
X7105Y306567D01*
X6950Y306835D01*
Y307103D01*
X7053Y307372D01*
X7312Y307602D01*
G01X10050Y310050D02*
X6950D01*
X7570Y309590D01*
G01X10050D02*
Y310510D01*
G01Y313150D02*
X9998Y313418D01*
X9843Y313725D01*
X9585Y313917D01*
X9223Y313993D01*
X8862Y313917D01*
X8552Y313687D01*
X8397Y313342D01*
Y312958D01*
X8293Y312728D01*
X8035Y312537D01*
X7673Y312460D01*
X7312Y312575D01*
X7053Y312843D01*
X6950Y313150D01*
X7053Y313457D01*
X7312Y313725D01*
X7673Y313840D01*
X8035Y313763D01*
X8293Y313572D01*
X8397Y313342D01*
Y312958D01*
X8552Y312613D01*
X8862Y312383D01*
X9223Y312307D01*
X9585Y312383D01*
X9843Y312575D01*
X9998Y312882D01*
X10050Y313150D01*
G01X8785Y315842D02*
X6285D01*
X6785Y315522D01*
G01X8785D02*
Y316162D01*
G01X24130Y53000D02*
X24897D01*
Y52070D01*
X24667Y51760D01*
X24398Y51553D01*
X24015Y51450D01*
X23632Y51553D01*
X23363Y51760D01*
X23133Y52070D01*
X22980Y52432D01*
X22903Y52845D01*
Y53207D01*
X22980Y53517D01*
X23133Y53878D01*
X23363Y54188D01*
X23593Y54395D01*
X23900Y54550D01*
X24168D01*
X24475Y54447D01*
X24705Y54240D01*
G01X26195Y51450D02*
Y54550D01*
G01X27805D02*
Y51450D01*
G01Y53000D02*
X26195D01*
G01X30560Y51450D02*
Y54550D01*
X29142Y52328D01*
X31058D01*
G01X12167Y92993D02*
X11917Y93153D01*
X11792Y93340D01*
X11750Y93553D01*
X11833Y93820D01*
X12042Y94007D01*
X12292Y94060D01*
X12542Y94033D01*
X12750Y93927D01*
X13167Y93393D01*
X13458Y93153D01*
X13875Y92993D01*
X14250Y92940D01*
Y94060D01*
G01X12960Y88500D02*
X13493D01*
Y87750D01*
X13333Y87500D01*
X13147Y87333D01*
X12880Y87250D01*
X12613Y87333D01*
X12427Y87500D01*
X12267Y87750D01*
X12160Y88042D01*
X12107Y88375D01*
Y88667D01*
X12160Y88917D01*
X12267Y89208D01*
X12427Y89458D01*
X12587Y89625D01*
X12800Y89750D01*
X12987D01*
X13200Y89667D01*
X13360Y89500D01*
G01X14440Y87250D02*
Y89750D01*
G01X15560D02*
Y87250D01*
G01Y88500D02*
X14440D01*
G01X17200Y87250D02*
Y89750D01*
X16880Y89250D01*
G01Y87250D02*
X17520D01*
G01X22960Y88500D02*
X23493D01*
Y87750D01*
X23333Y87500D01*
X23147Y87333D01*
X22880Y87250D01*
X22613Y87333D01*
X22427Y87500D01*
X22267Y87750D01*
X22160Y88042D01*
X22107Y88375D01*
Y88667D01*
X22160Y88917D01*
X22267Y89208D01*
X22427Y89458D01*
X22587Y89625D01*
X22800Y89750D01*
X22987D01*
X23200Y89667D01*
X23360Y89500D01*
G01X24440Y87250D02*
Y89750D01*
G01X25560D02*
Y87250D01*
G01Y88500D02*
X24440D01*
G01X26693Y89333D02*
X26853Y89583D01*
X27040Y89708D01*
X27253Y89750D01*
X27520Y89667D01*
X27707Y89458D01*
X27760Y89208D01*
X27733Y88958D01*
X27627Y88750D01*
X27093Y88333D01*
X26853Y88042D01*
X26693Y87625D01*
X26640Y87250D01*
X27760D01*
G01X19456Y108757D02*
Y111257D01*
X18469Y109465D01*
X19803D01*
G01X13750Y98003D02*
X14042Y98163D01*
X14208Y98377D01*
X14250Y98617D01*
X14208Y98830D01*
X14000Y99043D01*
X13750Y99177D01*
X13500Y99203D01*
X13208Y99150D01*
X13000Y98963D01*
X12917Y98777D01*
Y98537D01*
G01Y98777D02*
X12792Y98937D01*
X12583Y99070D01*
X12333Y99123D01*
X12083Y99070D01*
X11875Y98937D01*
X11750Y98697D01*
X11792Y98457D01*
X11958Y98217D01*
G01X22960Y111000D02*
X23493D01*
Y110250D01*
X23333Y110000D01*
X23147Y109833D01*
X22880Y109750D01*
X22613Y109833D01*
X22427Y110000D01*
X22267Y110250D01*
X22160Y110542D01*
X22107Y110875D01*
Y111167D01*
X22160Y111417D01*
X22267Y111708D01*
X22427Y111958D01*
X22587Y112125D01*
X22800Y112250D01*
X22987D01*
X23200Y112167D01*
X23360Y112000D01*
G01X24440Y109750D02*
Y112250D01*
G01X25560D02*
Y109750D01*
G01Y111000D02*
X24440D01*
G01X27520Y109750D02*
Y112250D01*
X26533Y110458D01*
X27867D01*
G01X13960Y145500D02*
X14493D01*
Y144750D01*
X14333Y144500D01*
X14147Y144333D01*
X13880Y144250D01*
X13613Y144333D01*
X13427Y144500D01*
X13267Y144750D01*
X13160Y145042D01*
X13107Y145375D01*
Y145667D01*
X13160Y145917D01*
X13267Y146208D01*
X13427Y146458D01*
X13587Y146625D01*
X13800Y146750D01*
X13987D01*
X14200Y146667D01*
X14360Y146500D01*
G01X15440Y144250D02*
Y146750D01*
G01X16560D02*
Y144250D01*
G01Y145500D02*
X15440D01*
G01X18200Y144250D02*
Y146750D01*
X17880Y146250D01*
G01Y144250D02*
X18520D01*
G01X23999Y146196D02*
X24532D01*
Y145446D01*
X24372Y145196D01*
X24186Y145029D01*
X23919Y144946D01*
X23652Y145029D01*
X23466Y145196D01*
X23306Y145446D01*
X23199Y145738D01*
X23146Y146071D01*
Y146363D01*
X23199Y146613D01*
X23306Y146904D01*
X23466Y147154D01*
X23626Y147321D01*
X23839Y147446D01*
X24026D01*
X24239Y147363D01*
X24399Y147196D01*
G01X25479Y144946D02*
Y147446D01*
G01X26599D02*
Y144946D01*
G01Y146196D02*
X25479D01*
G01X27732Y147029D02*
X27892Y147279D01*
X28079Y147404D01*
X28292Y147446D01*
X28559Y147363D01*
X28746Y147154D01*
X28799Y146904D01*
X28772Y146654D01*
X28666Y146446D01*
X28132Y146029D01*
X27892Y145738D01*
X27732Y145321D01*
X27679Y144946D01*
X28799D01*
G01X29550Y160167D02*
X27050D01*
Y160833D01*
X27175Y161047D01*
X27342Y161180D01*
X27675Y161233D01*
X28008Y161180D01*
X28217Y161020D01*
X28342Y160833D01*
Y160167D01*
G01Y160833D02*
X29550Y161233D01*
G01X27467Y162393D02*
X27217Y162553D01*
X27092Y162740D01*
X27050Y162953D01*
X27133Y163220D01*
X27342Y163407D01*
X27592Y163460D01*
X27842Y163433D01*
X28050Y163327D01*
X28467Y162793D01*
X28758Y162553D01*
X29175Y162393D01*
X29550Y162340D01*
Y163460D01*
G01Y165047D02*
X29008Y165100D01*
X28550Y165180D01*
X28133Y165287D01*
X27675Y165420D01*
X27050Y165633D01*
Y164567D01*
G01X27467Y166793D02*
X27217Y166953D01*
X27092Y167140D01*
X27050Y167353D01*
X27133Y167620D01*
X27342Y167807D01*
X27592Y167860D01*
X27842Y167833D01*
X28050Y167727D01*
X28467Y167193D01*
X28758Y166953D01*
X29175Y166793D01*
X29550Y166740D01*
Y167860D01*
G01X25050Y160167D02*
X22550D01*
Y160833D01*
X22675Y161047D01*
X22842Y161180D01*
X23175Y161233D01*
X23508Y161180D01*
X23717Y161020D01*
X23842Y160833D01*
Y160167D01*
G01Y160833D02*
X25050Y161233D01*
G01Y162900D02*
X22550D01*
X23050Y162580D01*
G01X25050D02*
Y163220D01*
G01X22967Y164593D02*
X22717Y164753D01*
X22592Y164940D01*
X22550Y165153D01*
X22633Y165420D01*
X22842Y165607D01*
X23092Y165660D01*
X23342Y165633D01*
X23550Y165527D01*
X23967Y164993D01*
X24258Y164753D01*
X24675Y164593D01*
X25050Y164540D01*
Y165660D01*
G01Y167620D02*
X22550D01*
X24342Y166633D01*
Y167967D01*
G01X21050Y160167D02*
X18550D01*
Y160833D01*
X18675Y161047D01*
X18842Y161180D01*
X19175Y161233D01*
X19508Y161180D01*
X19717Y161020D01*
X19842Y160833D01*
Y160167D01*
G01Y160833D02*
X21050Y161233D01*
G01X20550Y162313D02*
X20842Y162473D01*
X21008Y162687D01*
X21050Y162927D01*
X21008Y163140D01*
X20800Y163353D01*
X20550Y163487D01*
X20300Y163513D01*
X20008Y163460D01*
X19800Y163273D01*
X19717Y163087D01*
Y162847D01*
G01Y163087D02*
X19592Y163247D01*
X19383Y163380D01*
X19133Y163433D01*
X18883Y163380D01*
X18675Y163247D01*
X18550Y163007D01*
X18592Y162767D01*
X18758Y162527D01*
G01X21050Y165100D02*
X21008Y165287D01*
X20883Y165500D01*
X20675Y165633D01*
X20383Y165687D01*
X20092Y165633D01*
X19842Y165473D01*
X19717Y165233D01*
Y164967D01*
X19633Y164807D01*
X19425Y164673D01*
X19133Y164620D01*
X18842Y164700D01*
X18633Y164887D01*
X18550Y165100D01*
X18633Y165313D01*
X18842Y165500D01*
X19133Y165580D01*
X19425Y165527D01*
X19633Y165393D01*
X19717Y165233D01*
Y164967D01*
X19842Y164727D01*
X20092Y164567D01*
X20383Y164513D01*
X20675Y164567D01*
X20883Y164700D01*
X21008Y164913D01*
X21050Y165100D01*
G01X20675Y166713D02*
X20883Y166873D01*
X21008Y167060D01*
X21050Y167300D01*
X20967Y167540D01*
X20800Y167727D01*
X20508Y167860D01*
X20175Y167887D01*
X19842Y167833D01*
X19633Y167700D01*
X19467Y167513D01*
X19425Y167327D01*
X19467Y167140D01*
X19633Y166900D01*
X18550Y166980D01*
Y167700D01*
G01X10993Y150333D02*
X11153Y150583D01*
X11340Y150708D01*
X11553Y150750D01*
X11820Y150667D01*
X12007Y150458D01*
X12060Y150208D01*
X12033Y149958D01*
X11927Y149750D01*
X11393Y149333D01*
X11153Y149042D01*
X10993Y148625D01*
X10940Y148250D01*
X12060D01*
G01X11413Y158450D02*
X11573Y158158D01*
X11787Y157992D01*
X12027Y157950D01*
X12240Y157992D01*
X12453Y158200D01*
X12587Y158450D01*
X12613Y158700D01*
X12560Y158992D01*
X12373Y159200D01*
X12187Y159283D01*
X11947D01*
G01X12187D02*
X12347Y159408D01*
X12480Y159617D01*
X12533Y159867D01*
X12480Y160117D01*
X12347Y160325D01*
X12107Y160450D01*
X11867Y160408D01*
X11627Y160242D01*
G01X10993Y207833D02*
X11153Y208083D01*
X11340Y208208D01*
X11553Y208250D01*
X11820Y208167D01*
X12007Y207958D01*
X12060Y207708D01*
X12033Y207458D01*
X11927Y207250D01*
X11393Y206833D01*
X11153Y206542D01*
X10993Y206125D01*
X10940Y205750D01*
X12060D01*
G01X11413Y216250D02*
X11573Y215958D01*
X11787Y215792D01*
X12027Y215750D01*
X12240Y215792D01*
X12453Y216000D01*
X12587Y216250D01*
X12613Y216500D01*
X12560Y216792D01*
X12373Y217000D01*
X12187Y217083D01*
X11947D01*
G01X12187D02*
X12347Y217208D01*
X12480Y217417D01*
X12533Y217667D01*
X12480Y217917D01*
X12347Y218125D01*
X12107Y218250D01*
X11867Y218208D01*
X11627Y218042D01*
G01X12960Y202200D02*
X13493D01*
Y201450D01*
X13333Y201200D01*
X13147Y201033D01*
X12880Y200950D01*
X12613Y201033D01*
X12427Y201200D01*
X12267Y201450D01*
X12160Y201742D01*
X12107Y202075D01*
Y202367D01*
X12160Y202617D01*
X12267Y202908D01*
X12427Y203158D01*
X12587Y203325D01*
X12800Y203450D01*
X12987D01*
X13200Y203367D01*
X13360Y203200D01*
G01X14440Y200950D02*
Y203450D01*
G01X15560D02*
Y200950D01*
G01Y202200D02*
X14440D01*
G01X17200Y200950D02*
Y203450D01*
X16880Y202950D01*
G01Y200950D02*
X17520D01*
G01X25460Y202700D02*
X25993D01*
Y201950D01*
X25833Y201700D01*
X25647Y201533D01*
X25380Y201450D01*
X25113Y201533D01*
X24927Y201700D01*
X24767Y201950D01*
X24660Y202242D01*
X24607Y202575D01*
Y202867D01*
X24660Y203117D01*
X24767Y203408D01*
X24927Y203658D01*
X25087Y203825D01*
X25300Y203950D01*
X25487D01*
X25700Y203867D01*
X25860Y203700D01*
G01X26940Y201450D02*
Y203950D01*
G01X28060D02*
Y201450D01*
G01Y202700D02*
X26940D01*
G01X29193Y203533D02*
X29353Y203783D01*
X29540Y203908D01*
X29753Y203950D01*
X30020Y203867D01*
X30207Y203658D01*
X30260Y203408D01*
X30233Y203158D01*
X30127Y202950D01*
X29593Y202533D01*
X29353Y202242D01*
X29193Y201825D01*
X29140Y201450D01*
X30260D01*
G01X15320Y218250D02*
Y220750D01*
X14333Y218958D01*
X15667D01*
G01X16960Y224200D02*
X17493D01*
Y223450D01*
X17333Y223200D01*
X17147Y223033D01*
X16880Y222950D01*
X16613Y223033D01*
X16427Y223200D01*
X16267Y223450D01*
X16160Y223742D01*
X16107Y224075D01*
Y224367D01*
X16160Y224617D01*
X16267Y224908D01*
X16427Y225158D01*
X16587Y225325D01*
X16800Y225450D01*
X16987D01*
X17200Y225367D01*
X17360Y225200D01*
G01X18440Y222950D02*
Y225450D01*
G01X19560D02*
Y222950D01*
G01Y224200D02*
X18440D01*
G01X20613Y223450D02*
X20773Y223158D01*
X20987Y222992D01*
X21227Y222950D01*
X21440Y222992D01*
X21653Y223200D01*
X21787Y223450D01*
X21813Y223700D01*
X21760Y223992D01*
X21573Y224200D01*
X21387Y224283D01*
X21147D01*
G01X21387D02*
X21547Y224408D01*
X21680Y224617D01*
X21733Y224867D01*
X21680Y225117D01*
X21547Y225325D01*
X21307Y225450D01*
X21067Y225408D01*
X20827Y225242D01*
G01X25960Y224200D02*
X26493D01*
Y223450D01*
X26333Y223200D01*
X26147Y223033D01*
X25880Y222950D01*
X25613Y223033D01*
X25427Y223200D01*
X25267Y223450D01*
X25160Y223742D01*
X25107Y224075D01*
Y224367D01*
X25160Y224617D01*
X25267Y224908D01*
X25427Y225158D01*
X25587Y225325D01*
X25800Y225450D01*
X25987D01*
X26200Y225367D01*
X26360Y225200D01*
G01X27440Y222950D02*
Y225450D01*
G01X28560D02*
Y222950D01*
G01Y224200D02*
X27440D01*
G01X30520Y222950D02*
Y225450D01*
X29533Y223658D01*
X30867D01*
G01X13772Y267533D02*
X14002Y267843D01*
X14270Y267998D01*
X14577Y268050D01*
X14960Y267947D01*
X15228Y267688D01*
X15305Y267378D01*
X15267Y267068D01*
X15113Y266810D01*
X14347Y266293D01*
X14002Y265932D01*
X13772Y265415D01*
X13695Y264950D01*
X15305D01*
G01X14460Y259500D02*
X14993D01*
Y258750D01*
X14833Y258500D01*
X14647Y258333D01*
X14380Y258250D01*
X14113Y258333D01*
X13927Y258500D01*
X13767Y258750D01*
X13660Y259042D01*
X13607Y259375D01*
Y259667D01*
X13660Y259917D01*
X13767Y260208D01*
X13927Y260458D01*
X14087Y260625D01*
X14300Y260750D01*
X14487D01*
X14700Y260667D01*
X14860Y260500D01*
G01X15940Y258250D02*
Y260750D01*
G01X17060D02*
Y258250D01*
G01Y259500D02*
X15940D01*
G01X18700Y258250D02*
Y260750D01*
X18380Y260250D01*
G01Y258250D02*
X19020D01*
G01X23960Y259500D02*
X24493D01*
Y258750D01*
X24333Y258500D01*
X24147Y258333D01*
X23880Y258250D01*
X23613Y258333D01*
X23427Y258500D01*
X23267Y258750D01*
X23160Y259042D01*
X23107Y259375D01*
Y259667D01*
X23160Y259917D01*
X23267Y260208D01*
X23427Y260458D01*
X23587Y260625D01*
X23800Y260750D01*
X23987D01*
X24200Y260667D01*
X24360Y260500D01*
G01X25440Y258250D02*
Y260750D01*
G01X26560D02*
Y258250D01*
G01Y259500D02*
X25440D01*
G01X27693Y260333D02*
X27853Y260583D01*
X28040Y260708D01*
X28253Y260750D01*
X28520Y260667D01*
X28707Y260458D01*
X28760Y260208D01*
X28733Y259958D01*
X28627Y259750D01*
X28093Y259333D01*
X27853Y259042D01*
X27693Y258625D01*
X27640Y258250D01*
X28760D01*
G01X24550Y277083D02*
X21450D01*
Y278042D01*
X21605Y278348D01*
X21812Y278540D01*
X22225Y278617D01*
X22638Y278540D01*
X22897Y278310D01*
X23052Y278042D01*
Y277083D01*
G01Y278042D02*
X24550Y278617D01*
G01X23930Y280107D02*
X24292Y280337D01*
X24498Y280643D01*
X24550Y280988D01*
X24498Y281295D01*
X24240Y281602D01*
X23930Y281793D01*
X23620Y281832D01*
X23258Y281755D01*
X23000Y281487D01*
X22897Y281218D01*
Y280873D01*
G01Y281218D02*
X22742Y281448D01*
X22483Y281640D01*
X22173Y281717D01*
X21863Y281640D01*
X21605Y281448D01*
X21450Y281103D01*
X21502Y280758D01*
X21708Y280413D01*
G01X24550Y283973D02*
X23878Y284050D01*
X23310Y284165D01*
X22793Y284318D01*
X22225Y284510D01*
X21450Y284817D01*
Y283283D01*
G01X24550Y287610D02*
X21450D01*
X23672Y286192D01*
Y288108D01*
G01X19050Y277083D02*
X15950D01*
Y278042D01*
X16105Y278348D01*
X16312Y278540D01*
X16725Y278617D01*
X17138Y278540D01*
X17397Y278310D01*
X17552Y278042D01*
Y277083D01*
G01Y278042D02*
X19050Y278617D01*
G01X18430Y280107D02*
X18792Y280337D01*
X18998Y280643D01*
X19050Y280988D01*
X18998Y281295D01*
X18740Y281602D01*
X18430Y281793D01*
X18120Y281832D01*
X17758Y281755D01*
X17500Y281487D01*
X17397Y281218D01*
Y280873D01*
G01Y281218D02*
X17242Y281448D01*
X16983Y281640D01*
X16673Y281717D01*
X16363Y281640D01*
X16105Y281448D01*
X15950Y281103D01*
X16002Y280758D01*
X16208Y280413D01*
G01X18688Y283398D02*
X18947Y283667D01*
X19050Y283973D01*
X18947Y284280D01*
X18637Y284548D01*
X18172Y284740D01*
X17707Y284817D01*
X17138D01*
X16673Y284740D01*
X16260Y284548D01*
X16053Y284318D01*
X15950Y284050D01*
X16053Y283743D01*
X16260Y283513D01*
X16570Y283360D01*
X16983Y283283D01*
X17345Y283360D01*
X17707Y283552D01*
X17913Y283782D01*
X17965Y284050D01*
X17862Y284357D01*
X17603Y284587D01*
X17138Y284817D01*
G01X19050Y287150D02*
X15950D01*
X16570Y286690D01*
G01X19050D02*
Y287610D01*
G01X28550Y277083D02*
X25450D01*
Y278042D01*
X25605Y278348D01*
X25812Y278540D01*
X26225Y278617D01*
X26638Y278540D01*
X26897Y278310D01*
X27052Y278042D01*
Y277083D01*
G01Y278042D02*
X28550Y278617D01*
G01X27930Y280107D02*
X28292Y280337D01*
X28498Y280643D01*
X28550Y280988D01*
X28498Y281295D01*
X28240Y281602D01*
X27930Y281793D01*
X27620Y281832D01*
X27258Y281755D01*
X27000Y281487D01*
X26897Y281218D01*
Y280873D01*
G01Y281218D02*
X26742Y281448D01*
X26483Y281640D01*
X26173Y281717D01*
X25863Y281640D01*
X25605Y281448D01*
X25450Y281103D01*
X25502Y280758D01*
X25708Y280413D01*
G01X28550Y283973D02*
X27878Y284050D01*
X27310Y284165D01*
X26793Y284318D01*
X26225Y284510D01*
X25450Y284817D01*
Y283283D01*
G01X27258Y286422D02*
X26897Y286690D01*
X26690Y286920D01*
X26587Y287227D01*
X26690Y287495D01*
X26897Y287687D01*
X27207Y287840D01*
X27568Y287878D01*
X27878Y287840D01*
X28188Y287687D01*
X28447Y287457D01*
X28550Y287188D01*
X28447Y286882D01*
X28137Y286613D01*
X27672Y286460D01*
X27155Y286422D01*
X26483Y286498D01*
X26122Y286613D01*
X25760Y286805D01*
X25502Y287073D01*
X25450Y287342D01*
X25553Y287610D01*
X25812Y287802D01*
G01X13550Y279007D02*
X10450D01*
Y279773D01*
X10605Y280080D01*
X10812Y280310D01*
X11122Y280502D01*
X11483Y280655D01*
X12000Y280693D01*
X12517Y280655D01*
X12878Y280502D01*
X13188Y280310D01*
X13395Y280080D01*
X13550Y279773D01*
Y279007D01*
G01X13137Y282145D02*
X13395Y282452D01*
X13550Y282797D01*
Y283103D01*
X13395Y283410D01*
X13137Y283640D01*
X12775Y283755D01*
X12413Y283678D01*
X12103Y283487D01*
X11897Y283142D01*
X11793Y282682D01*
X11587Y282413D01*
X11225Y282298D01*
X10863Y282375D01*
X10605Y282567D01*
X10450Y282835D01*
Y283103D01*
X10553Y283372D01*
X10812Y283602D01*
G01X13550Y286050D02*
X10450D01*
X11070Y285590D01*
G01X13550D02*
Y286510D01*
G01X12258Y288422D02*
X11897Y288690D01*
X11690Y288920D01*
X11587Y289227D01*
X11690Y289495D01*
X11897Y289687D01*
X12207Y289840D01*
X12568Y289878D01*
X12878Y289840D01*
X13188Y289687D01*
X13447Y289457D01*
X13550Y289188D01*
X13447Y288882D01*
X13137Y288613D01*
X12672Y288460D01*
X12155Y288422D01*
X11483Y288498D01*
X11122Y288613D01*
X10760Y288805D01*
X10502Y289073D01*
X10450Y289342D01*
X10553Y289610D01*
X10812Y289802D01*
G01X13157Y270070D02*
X13387Y269708D01*
X13693Y269502D01*
X14038Y269450D01*
X14345Y269502D01*
X14652Y269760D01*
X14843Y270070D01*
X14882Y270380D01*
X14805Y270742D01*
X14537Y271000D01*
X14268Y271103D01*
X13923D01*
G01X14268D02*
X14498Y271258D01*
X14690Y271517D01*
X14767Y271827D01*
X14690Y272137D01*
X14498Y272395D01*
X14153Y272550D01*
X13808Y272498D01*
X13463Y272292D01*
G01X15550Y305083D02*
X12450D01*
Y306042D01*
X12605Y306348D01*
X12812Y306540D01*
X13225Y306617D01*
X13638Y306540D01*
X13897Y306310D01*
X14052Y306042D01*
Y305083D01*
G01Y306042D02*
X15550Y306617D01*
G01X14930Y308107D02*
X15292Y308337D01*
X15498Y308643D01*
X15550Y308988D01*
X15498Y309295D01*
X15240Y309602D01*
X14930Y309793D01*
X14620Y309832D01*
X14258Y309755D01*
X14000Y309487D01*
X13897Y309218D01*
Y308873D01*
G01Y309218D02*
X13742Y309448D01*
X13483Y309640D01*
X13173Y309717D01*
X12863Y309640D01*
X12605Y309448D01*
X12450Y309103D01*
X12502Y308758D01*
X12708Y308413D01*
G01X15188Y311398D02*
X15447Y311667D01*
X15550Y311973D01*
X15447Y312280D01*
X15137Y312548D01*
X14672Y312740D01*
X14207Y312817D01*
X13638D01*
X13173Y312740D01*
X12760Y312548D01*
X12553Y312318D01*
X12450Y312050D01*
X12553Y311743D01*
X12760Y311513D01*
X13070Y311360D01*
X13483Y311283D01*
X13845Y311360D01*
X14207Y311552D01*
X14413Y311782D01*
X14465Y312050D01*
X14362Y312357D01*
X14103Y312587D01*
X13638Y312817D01*
G01X15550Y315073D02*
X14878Y315150D01*
X14310Y315265D01*
X13793Y315418D01*
X13225Y315610D01*
X12450Y315917D01*
Y314383D01*
G01X23050Y305083D02*
X19950D01*
Y306042D01*
X20105Y306348D01*
X20312Y306540D01*
X20725Y306617D01*
X21138Y306540D01*
X21397Y306310D01*
X21552Y306042D01*
Y305083D01*
G01Y306042D02*
X23050Y306617D01*
G01Y309410D02*
X19950D01*
X22172Y307992D01*
Y309908D01*
G01X20467Y311322D02*
X20157Y311552D01*
X20002Y311820D01*
X19950Y312127D01*
X20053Y312510D01*
X20312Y312778D01*
X20622Y312855D01*
X20932Y312817D01*
X21190Y312663D01*
X21707Y311897D01*
X22068Y311552D01*
X22585Y311322D01*
X23050Y311245D01*
Y312855D01*
G01X22585Y314307D02*
X22843Y314537D01*
X22998Y314805D01*
X23050Y315150D01*
X22947Y315495D01*
X22740Y315763D01*
X22378Y315955D01*
X21965Y315993D01*
X21552Y315917D01*
X21293Y315725D01*
X21087Y315457D01*
X21035Y315188D01*
X21087Y314920D01*
X21293Y314575D01*
X19950Y314690D01*
Y315725D01*
G01X28050Y305083D02*
X24950D01*
Y306042D01*
X25105Y306348D01*
X25312Y306540D01*
X25725Y306617D01*
X26138Y306540D01*
X26397Y306310D01*
X26552Y306042D01*
Y305083D01*
G01Y306042D02*
X28050Y306617D01*
G01Y309410D02*
X24950D01*
X27172Y307992D01*
Y309908D01*
G01X25467Y311322D02*
X25157Y311552D01*
X25002Y311820D01*
X24950Y312127D01*
X25053Y312510D01*
X25312Y312778D01*
X25622Y312855D01*
X25932Y312817D01*
X26190Y312663D01*
X26707Y311897D01*
X27068Y311552D01*
X27585Y311322D01*
X28050Y311245D01*
Y312855D01*
G01Y315073D02*
X27378Y315150D01*
X26810Y315265D01*
X26293Y315418D01*
X25725Y315610D01*
X24950Y315917D01*
Y314383D01*
G01X10993Y319533D02*
X11153Y319783D01*
X11340Y319908D01*
X11553Y319950D01*
X11820Y319867D01*
X12007Y319658D01*
X12060Y319408D01*
X12033Y319158D01*
X11927Y318950D01*
X11393Y318533D01*
X11153Y318242D01*
X10993Y317825D01*
X10940Y317450D01*
X12060D01*
G01X13913Y324450D02*
X14073Y324158D01*
X14287Y323992D01*
X14527Y323950D01*
X14740Y323992D01*
X14953Y324200D01*
X15087Y324450D01*
X15113Y324700D01*
X15060Y324992D01*
X14873Y325200D01*
X14687Y325283D01*
X14447D01*
G01X14687D02*
X14847Y325408D01*
X14980Y325617D01*
X15033Y325867D01*
X14980Y326117D01*
X14847Y326325D01*
X14607Y326450D01*
X14367Y326408D01*
X14127Y326242D01*
G01X11820Y325450D02*
Y327950D01*
X10833Y326158D01*
X12167D01*
G01X14133Y356570D02*
X14325Y356260D01*
X14555Y356053D01*
X14823Y355950D01*
X15130Y356053D01*
X15360Y356260D01*
X15590Y356570D01*
X15667Y356983D01*
Y359050D01*
G01X18000Y355950D02*
Y359050D01*
X17540Y358430D01*
G01Y355950D02*
X18460D01*
G01X20257Y356570D02*
X20487Y356208D01*
X20793Y356002D01*
X21138Y355950D01*
X21445Y356002D01*
X21752Y356260D01*
X21943Y356570D01*
X21982Y356880D01*
X21905Y357242D01*
X21637Y357500D01*
X21368Y357603D01*
X21023D01*
G01X21368D02*
X21598Y357758D01*
X21790Y358017D01*
X21867Y358327D01*
X21790Y358637D01*
X21598Y358895D01*
X21253Y359050D01*
X20908Y358998D01*
X20563Y358792D01*
G01X25933Y387480D02*
Y390580D01*
X26930Y387997D01*
X27927Y390580D01*
Y387480D01*
G01X30797D02*
X29263D01*
Y390580D01*
X30797D01*
G01X30183Y389082D02*
X29263D01*
G01X32478Y387842D02*
X32747Y387583D01*
X33053Y387480D01*
X33360Y387583D01*
X33628Y387893D01*
X33820Y388358D01*
X33897Y388823D01*
Y389392D01*
X33820Y389857D01*
X33628Y390270D01*
X33398Y390477D01*
X33130Y390580D01*
X32823Y390477D01*
X32593Y390270D01*
X32440Y389960D01*
X32363Y389547D01*
X32440Y389185D01*
X32632Y388823D01*
X32862Y388617D01*
X33130Y388565D01*
X33437Y388668D01*
X33667Y388927D01*
X33897Y389392D01*
G01X33183Y57070D02*
X33375Y56760D01*
X33605Y56553D01*
X33873Y56450D01*
X34180Y56553D01*
X34410Y56760D01*
X34640Y57070D01*
X34717Y57483D01*
Y59550D01*
G01X36322Y59033D02*
X36552Y59343D01*
X36820Y59498D01*
X37127Y59550D01*
X37510Y59447D01*
X37778Y59188D01*
X37855Y58878D01*
X37817Y58568D01*
X37663Y58310D01*
X36897Y57793D01*
X36552Y57432D01*
X36322Y56915D01*
X36245Y56450D01*
X37855D01*
G01X41550Y61583D02*
X38450D01*
Y62542D01*
X38605Y62848D01*
X38812Y63040D01*
X39225Y63117D01*
X39638Y63040D01*
X39897Y62810D01*
X40052Y62542D01*
Y61583D01*
G01Y62542D02*
X41550Y63117D01*
G01Y65910D02*
X38450D01*
X40672Y64492D01*
Y66408D01*
G01X41188Y67898D02*
X41447Y68167D01*
X41550Y68473D01*
X41447Y68780D01*
X41137Y69048D01*
X40672Y69240D01*
X40207Y69317D01*
X39638D01*
X39173Y69240D01*
X38760Y69048D01*
X38553Y68818D01*
X38450Y68550D01*
X38553Y68243D01*
X38760Y68013D01*
X39070Y67860D01*
X39483Y67783D01*
X39845Y67860D01*
X40207Y68052D01*
X40413Y68282D01*
X40465Y68550D01*
X40362Y68857D01*
X40103Y69087D01*
X39638Y69317D01*
G01X41550Y71573D02*
X40878Y71650D01*
X40310Y71765D01*
X39793Y71918D01*
X39225Y72110D01*
X38450Y72417D01*
Y70883D01*
G01X33689Y71260D02*
Y74360D01*
X33229Y73740D01*
G01Y71260D02*
X34149D01*
G01X30993Y91333D02*
X31153Y91583D01*
X31340Y91708D01*
X31553Y91750D01*
X31820Y91667D01*
X32007Y91458D01*
X32060Y91208D01*
X32033Y90958D01*
X31927Y90750D01*
X31393Y90333D01*
X31153Y90042D01*
X30993Y89625D01*
X30940Y89250D01*
X32060D01*
G01X31208Y95743D02*
X31053Y95513D01*
X30950Y95245D01*
Y94938D01*
X31105Y94593D01*
X31363Y94325D01*
X31673Y94133D01*
X32190Y93980D01*
X32655Y93942D01*
X33120Y94018D01*
X33430Y94133D01*
X33740Y94363D01*
X33947Y94632D01*
X34050Y94900D01*
Y95168D01*
X33947Y95437D01*
X33792Y95667D01*
X33585Y95858D01*
G01X34050Y97233D02*
X30950D01*
Y98192D01*
X31105Y98498D01*
X31312Y98690D01*
X31725Y98767D01*
X32138Y98690D01*
X32397Y98460D01*
X32552Y98192D01*
Y97233D01*
G01Y98192D02*
X34050Y98767D01*
G01X33585Y100257D02*
X33843Y100487D01*
X33998Y100755D01*
X34050Y101100D01*
X33947Y101445D01*
X33740Y101713D01*
X33378Y101905D01*
X32965Y101943D01*
X32552Y101867D01*
X32293Y101675D01*
X32087Y101407D01*
X32035Y101138D01*
X32087Y100870D01*
X32293Y100525D01*
X30950Y100640D01*
Y101675D01*
G01X45050Y82583D02*
X41950D01*
Y83542D01*
X42105Y83848D01*
X42312Y84040D01*
X42725Y84117D01*
X43138Y84040D01*
X43397Y83810D01*
X43552Y83542D01*
Y82583D01*
G01Y83542D02*
X45050Y84117D01*
G01X44430Y85607D02*
X44792Y85837D01*
X44998Y86143D01*
X45050Y86488D01*
X44998Y86795D01*
X44740Y87102D01*
X44430Y87293D01*
X44120Y87332D01*
X43758Y87255D01*
X43500Y86987D01*
X43397Y86718D01*
Y86373D01*
G01Y86718D02*
X43242Y86948D01*
X42983Y87140D01*
X42673Y87217D01*
X42363Y87140D01*
X42105Y86948D01*
X41950Y86603D01*
X42002Y86258D01*
X42208Y85913D01*
G01X43758Y88822D02*
X43397Y89090D01*
X43190Y89320D01*
X43087Y89627D01*
X43190Y89895D01*
X43397Y90087D01*
X43707Y90240D01*
X44068Y90278D01*
X44378Y90240D01*
X44688Y90087D01*
X44947Y89857D01*
X45050Y89588D01*
X44947Y89282D01*
X44637Y89013D01*
X44172Y88860D01*
X43655Y88822D01*
X42983Y88898D01*
X42622Y89013D01*
X42260Y89205D01*
X42002Y89473D01*
X41950Y89742D01*
X42053Y90010D01*
X42312Y90202D01*
G01X45050Y92650D02*
X44998Y92918D01*
X44843Y93225D01*
X44585Y93417D01*
X44223Y93493D01*
X43862Y93417D01*
X43552Y93187D01*
X43397Y92842D01*
Y92458D01*
X43293Y92228D01*
X43035Y92037D01*
X42673Y91960D01*
X42312Y92075D01*
X42053Y92343D01*
X41950Y92650D01*
X42053Y92957D01*
X42312Y93225D01*
X42673Y93340D01*
X43035Y93263D01*
X43293Y93072D01*
X43397Y92842D01*
Y92458D01*
X43552Y92113D01*
X43862Y91883D01*
X44223Y91807D01*
X44585Y91883D01*
X44843Y92075D01*
X44998Y92382D01*
X45050Y92650D01*
G01X37050Y82583D02*
X33950D01*
Y83542D01*
X34105Y83848D01*
X34312Y84040D01*
X34725Y84117D01*
X35138Y84040D01*
X35397Y83810D01*
X35552Y83542D01*
Y82583D01*
G01Y83542D02*
X37050Y84117D01*
G01X36430Y85607D02*
X36792Y85837D01*
X36998Y86143D01*
X37050Y86488D01*
X36998Y86795D01*
X36740Y87102D01*
X36430Y87293D01*
X36120Y87332D01*
X35758Y87255D01*
X35500Y86987D01*
X35397Y86718D01*
Y86373D01*
G01Y86718D02*
X35242Y86948D01*
X34983Y87140D01*
X34673Y87217D01*
X34363Y87140D01*
X34105Y86948D01*
X33950Y86603D01*
X34002Y86258D01*
X34208Y85913D01*
G01X37050Y89473D02*
X36378Y89550D01*
X35810Y89665D01*
X35293Y89818D01*
X34725Y90010D01*
X33950Y90317D01*
Y88783D01*
G01Y92650D02*
X34053Y92343D01*
X34312Y92113D01*
X34622Y91960D01*
X35035Y91845D01*
X35500Y91807D01*
X35965Y91845D01*
X36378Y91960D01*
X36688Y92113D01*
X36947Y92343D01*
X37050Y92650D01*
X36947Y92957D01*
X36688Y93187D01*
X36378Y93340D01*
X35965Y93455D01*
X35500Y93493D01*
X35035Y93455D01*
X34622Y93340D01*
X34312Y93187D01*
X34053Y92957D01*
X33950Y92650D01*
G01X41050Y82583D02*
X37950D01*
Y83542D01*
X38105Y83848D01*
X38312Y84040D01*
X38725Y84117D01*
X39138Y84040D01*
X39397Y83810D01*
X39552Y83542D01*
Y82583D01*
G01Y83542D02*
X41050Y84117D01*
G01Y86450D02*
X37950D01*
X38570Y85990D01*
G01X41050D02*
Y86910D01*
G01X40585Y88707D02*
X40843Y88937D01*
X40998Y89205D01*
X41050Y89550D01*
X40947Y89895D01*
X40740Y90163D01*
X40378Y90355D01*
X39965Y90393D01*
X39552Y90317D01*
X39293Y90125D01*
X39087Y89857D01*
X39035Y89588D01*
X39087Y89320D01*
X39293Y88975D01*
X37950Y89090D01*
Y90125D01*
G01X41050Y92573D02*
X40378Y92650D01*
X39810Y92765D01*
X39293Y92918D01*
X38725Y93110D01*
X37950Y93417D01*
Y91883D01*
G01X29413Y109250D02*
X29573Y108958D01*
X29787Y108792D01*
X30027Y108750D01*
X30240Y108792D01*
X30453Y109000D01*
X30587Y109250D01*
X30613Y109500D01*
X30560Y109792D01*
X30373Y110000D01*
X30187Y110083D01*
X29947D01*
G01X30187D02*
X30347Y110208D01*
X30480Y110417D01*
X30533Y110667D01*
X30480Y110917D01*
X30347Y111125D01*
X30107Y111250D01*
X29867Y111208D01*
X29627Y111042D01*
G01X37193Y101292D02*
X36963Y101447D01*
X36695Y101550D01*
X36388D01*
X36043Y101395D01*
X35775Y101137D01*
X35583Y100827D01*
X35430Y100310D01*
X35392Y99845D01*
X35468Y99380D01*
X35583Y99070D01*
X35813Y98760D01*
X36082Y98553D01*
X36350Y98450D01*
X36618D01*
X36887Y98553D01*
X37117Y98708D01*
X37308Y98915D01*
G01X38607Y99070D02*
X38837Y98708D01*
X39143Y98502D01*
X39488Y98450D01*
X39795Y98502D01*
X40102Y98760D01*
X40293Y99070D01*
X40332Y99380D01*
X40255Y99742D01*
X39987Y100000D01*
X39718Y100103D01*
X39373D01*
G01X39718D02*
X39948Y100258D01*
X40140Y100517D01*
X40217Y100827D01*
X40140Y101137D01*
X39948Y101395D01*
X39603Y101550D01*
X39258Y101498D01*
X38913Y101292D01*
G01X42550Y98450D02*
Y101550D01*
X42090Y100930D01*
G01Y98450D02*
X43010D01*
G01X45650D02*
Y101550D01*
X45190Y100930D01*
G01Y98450D02*
X46110D01*
G01X42550Y103083D02*
X39450D01*
Y104042D01*
X39605Y104348D01*
X39812Y104540D01*
X40225Y104617D01*
X40638Y104540D01*
X40897Y104310D01*
X41052Y104042D01*
Y103083D01*
G01Y104042D02*
X42550Y104617D01*
G01X41930Y106107D02*
X42292Y106337D01*
X42498Y106643D01*
X42550Y106988D01*
X42498Y107295D01*
X42240Y107602D01*
X41930Y107793D01*
X41620Y107832D01*
X41258Y107755D01*
X41000Y107487D01*
X40897Y107218D01*
Y106873D01*
G01Y107218D02*
X40742Y107448D01*
X40483Y107640D01*
X40173Y107717D01*
X39863Y107640D01*
X39605Y107448D01*
X39450Y107103D01*
X39502Y106758D01*
X39708Y106413D01*
G01X42550Y109973D02*
X41878Y110050D01*
X41310Y110165D01*
X40793Y110318D01*
X40225Y110510D01*
X39450Y110817D01*
Y109283D01*
G01X42550Y113073D02*
X41878Y113150D01*
X41310Y113265D01*
X40793Y113418D01*
X40225Y113610D01*
X39450Y113917D01*
Y112383D01*
G01X38550Y103083D02*
X35450D01*
Y104042D01*
X35605Y104348D01*
X35812Y104540D01*
X36225Y104617D01*
X36638Y104540D01*
X36897Y104310D01*
X37052Y104042D01*
Y103083D01*
G01Y104042D02*
X38550Y104617D01*
G01Y106950D02*
X35450D01*
X36070Y106490D01*
G01X38550D02*
Y107410D01*
G01X35967Y109322D02*
X35657Y109552D01*
X35502Y109820D01*
X35450Y110127D01*
X35553Y110510D01*
X35812Y110778D01*
X36122Y110855D01*
X36432Y110817D01*
X36690Y110663D01*
X37207Y109897D01*
X37568Y109552D01*
X38085Y109322D01*
X38550Y109245D01*
Y110855D01*
G01X35967Y112422D02*
X35657Y112652D01*
X35502Y112920D01*
X35450Y113227D01*
X35553Y113610D01*
X35812Y113878D01*
X36122Y113955D01*
X36432Y113917D01*
X36690Y113763D01*
X37207Y112997D01*
X37568Y112652D01*
X38085Y112422D01*
X38550Y112345D01*
Y113955D01*
G01Y115083D02*
X35450D01*
Y116042D01*
X35605Y116348D01*
X35812Y116540D01*
X36225Y116617D01*
X36638Y116540D01*
X36897Y116310D01*
X37052Y116042D01*
Y115083D01*
G01Y116042D02*
X38550Y116617D01*
G01Y119410D02*
X35450D01*
X37672Y117992D01*
Y119908D01*
G01X38188Y121398D02*
X38447Y121667D01*
X38550Y121973D01*
X38447Y122280D01*
X38137Y122548D01*
X37672Y122740D01*
X37207Y122817D01*
X36638D01*
X36173Y122740D01*
X35760Y122548D01*
X35553Y122318D01*
X35450Y122050D01*
X35553Y121743D01*
X35760Y121513D01*
X36070Y121360D01*
X36483Y121283D01*
X36845Y121360D01*
X37207Y121552D01*
X37413Y121782D01*
X37465Y122050D01*
X37362Y122357D01*
X37103Y122587D01*
X36638Y122817D01*
G01X37258Y124422D02*
X36897Y124690D01*
X36690Y124920D01*
X36587Y125227D01*
X36690Y125495D01*
X36897Y125687D01*
X37207Y125840D01*
X37568Y125878D01*
X37878Y125840D01*
X38188Y125687D01*
X38447Y125457D01*
X38550Y125188D01*
X38447Y124882D01*
X38137Y124613D01*
X37672Y124460D01*
X37155Y124422D01*
X36483Y124498D01*
X36122Y124613D01*
X35760Y124805D01*
X35502Y125073D01*
X35450Y125342D01*
X35553Y125610D01*
X35812Y125802D01*
G01X33000Y126950D02*
Y130050D01*
X32540Y129430D01*
G01Y126950D02*
X33460D01*
G01X44550Y136083D02*
X41450D01*
Y137042D01*
X41605Y137348D01*
X41812Y137540D01*
X42225Y137617D01*
X42638Y137540D01*
X42897Y137310D01*
X43052Y137042D01*
Y136083D01*
G01Y137042D02*
X44550Y137617D01*
G01X43930Y139107D02*
X44292Y139337D01*
X44498Y139643D01*
X44550Y139988D01*
X44498Y140295D01*
X44240Y140602D01*
X43930Y140793D01*
X43620Y140832D01*
X43258Y140755D01*
X43000Y140487D01*
X42897Y140218D01*
Y139873D01*
G01Y140218D02*
X42742Y140448D01*
X42483Y140640D01*
X42173Y140717D01*
X41863Y140640D01*
X41605Y140448D01*
X41450Y140103D01*
X41502Y139758D01*
X41708Y139413D01*
G01X43258Y142322D02*
X42897Y142590D01*
X42690Y142820D01*
X42587Y143127D01*
X42690Y143395D01*
X42897Y143587D01*
X43207Y143740D01*
X43568Y143778D01*
X43878Y143740D01*
X44188Y143587D01*
X44447Y143357D01*
X44550Y143088D01*
X44447Y142782D01*
X44137Y142513D01*
X43672Y142360D01*
X43155Y142322D01*
X42483Y142398D01*
X42122Y142513D01*
X41760Y142705D01*
X41502Y142973D01*
X41450Y143242D01*
X41553Y143510D01*
X41812Y143702D01*
G01X44085Y145307D02*
X44343Y145537D01*
X44498Y145805D01*
X44550Y146150D01*
X44447Y146495D01*
X44240Y146763D01*
X43878Y146955D01*
X43465Y146993D01*
X43052Y146917D01*
X42793Y146725D01*
X42587Y146457D01*
X42535Y146188D01*
X42587Y145920D01*
X42793Y145575D01*
X41450Y145690D01*
Y146725D01*
G01X36550Y136083D02*
X33450D01*
Y137042D01*
X33605Y137348D01*
X33812Y137540D01*
X34225Y137617D01*
X34638Y137540D01*
X34897Y137310D01*
X35052Y137042D01*
Y136083D01*
G01Y137042D02*
X36550Y137617D01*
G01X35930Y139107D02*
X36292Y139337D01*
X36498Y139643D01*
X36550Y139988D01*
X36498Y140295D01*
X36240Y140602D01*
X35930Y140793D01*
X35620Y140832D01*
X35258Y140755D01*
X35000Y140487D01*
X34897Y140218D01*
Y139873D01*
G01Y140218D02*
X34742Y140448D01*
X34483Y140640D01*
X34173Y140717D01*
X33863Y140640D01*
X33605Y140448D01*
X33450Y140103D01*
X33502Y139758D01*
X33708Y139413D01*
G01X35258Y142322D02*
X34897Y142590D01*
X34690Y142820D01*
X34587Y143127D01*
X34690Y143395D01*
X34897Y143587D01*
X35207Y143740D01*
X35568Y143778D01*
X35878Y143740D01*
X36188Y143587D01*
X36447Y143357D01*
X36550Y143088D01*
X36447Y142782D01*
X36137Y142513D01*
X35672Y142360D01*
X35155Y142322D01*
X34483Y142398D01*
X34122Y142513D01*
X33760Y142705D01*
X33502Y142973D01*
X33450Y143242D01*
X33553Y143510D01*
X33812Y143702D01*
G01X36550Y146073D02*
X35878Y146150D01*
X35310Y146265D01*
X34793Y146418D01*
X34225Y146610D01*
X33450Y146917D01*
Y145383D01*
G01X40550Y136083D02*
X37450D01*
Y137042D01*
X37605Y137348D01*
X37812Y137540D01*
X38225Y137617D01*
X38638Y137540D01*
X38897Y137310D01*
X39052Y137042D01*
Y136083D01*
G01Y137042D02*
X40550Y137617D01*
G01Y139950D02*
X37450D01*
X38070Y139490D01*
G01X40550D02*
Y140410D01*
G01X40085Y142207D02*
X40343Y142437D01*
X40498Y142705D01*
X40550Y143050D01*
X40447Y143395D01*
X40240Y143663D01*
X39878Y143855D01*
X39465Y143893D01*
X39052Y143817D01*
X38793Y143625D01*
X38587Y143357D01*
X38535Y143088D01*
X38587Y142820D01*
X38793Y142475D01*
X37450Y142590D01*
Y143625D01*
G01X39258Y145422D02*
X38897Y145690D01*
X38690Y145920D01*
X38587Y146227D01*
X38690Y146495D01*
X38897Y146687D01*
X39207Y146840D01*
X39568Y146878D01*
X39878Y146840D01*
X40188Y146687D01*
X40447Y146457D01*
X40550Y146188D01*
X40447Y145882D01*
X40137Y145613D01*
X39672Y145460D01*
X39155Y145422D01*
X38483Y145498D01*
X38122Y145613D01*
X37760Y145805D01*
X37502Y146073D01*
X37450Y146342D01*
X37553Y146610D01*
X37812Y146802D01*
G01X34683Y132070D02*
X34875Y131760D01*
X35105Y131553D01*
X35373Y131450D01*
X35680Y131553D01*
X35910Y131760D01*
X36140Y132070D01*
X36217Y132483D01*
Y134550D01*
G01X38550Y131450D02*
Y134550D01*
X38090Y133930D01*
G01Y131450D02*
X39010D01*
G01X33550Y160167D02*
X31050D01*
Y160833D01*
X31175Y161047D01*
X31342Y161180D01*
X31675Y161233D01*
X32008Y161180D01*
X32217Y161020D01*
X32342Y160833D01*
Y160167D01*
G01Y160833D02*
X33550Y161233D01*
G01X33050Y162313D02*
X33342Y162473D01*
X33508Y162687D01*
X33550Y162927D01*
X33508Y163140D01*
X33300Y163353D01*
X33050Y163487D01*
X32800Y163513D01*
X32508Y163460D01*
X32300Y163273D01*
X32217Y163087D01*
Y162847D01*
G01Y163087D02*
X32092Y163247D01*
X31883Y163380D01*
X31633Y163433D01*
X31383Y163380D01*
X31175Y163247D01*
X31050Y163007D01*
X31092Y162767D01*
X31258Y162527D01*
G01X33550Y165100D02*
X33508Y165287D01*
X33383Y165500D01*
X33175Y165633D01*
X32883Y165687D01*
X32592Y165633D01*
X32342Y165473D01*
X32217Y165233D01*
Y164967D01*
X32133Y164807D01*
X31925Y164673D01*
X31633Y164620D01*
X31342Y164700D01*
X31133Y164887D01*
X31050Y165100D01*
X31133Y165313D01*
X31342Y165500D01*
X31633Y165580D01*
X31925Y165527D01*
X32133Y165393D01*
X32217Y165233D01*
Y164967D01*
X32342Y164727D01*
X32592Y164567D01*
X32883Y164513D01*
X33175Y164567D01*
X33383Y164700D01*
X33508Y164913D01*
X33550Y165100D01*
G01Y167247D02*
X33008Y167300D01*
X32550Y167380D01*
X32133Y167487D01*
X31675Y167620D01*
X31050Y167833D01*
Y166767D01*
G01X37550Y160167D02*
X35050D01*
Y160833D01*
X35175Y161047D01*
X35342Y161180D01*
X35675Y161233D01*
X36008Y161180D01*
X36217Y161020D01*
X36342Y160833D01*
Y160167D01*
G01Y160833D02*
X37550Y161233D01*
G01Y162900D02*
X35050D01*
X35550Y162580D01*
G01X37550D02*
Y163220D01*
G01X35467Y164593D02*
X35217Y164753D01*
X35092Y164940D01*
X35050Y165153D01*
X35133Y165420D01*
X35342Y165607D01*
X35592Y165660D01*
X35842Y165633D01*
X36050Y165527D01*
X36467Y164993D01*
X36758Y164753D01*
X37175Y164593D01*
X37550Y164540D01*
Y165660D01*
G01X37175Y166713D02*
X37383Y166873D01*
X37508Y167060D01*
X37550Y167300D01*
X37467Y167540D01*
X37300Y167727D01*
X37008Y167860D01*
X36675Y167887D01*
X36342Y167833D01*
X36133Y167700D01*
X35967Y167513D01*
X35925Y167327D01*
X35967Y167140D01*
X36133Y166900D01*
X35050Y166980D01*
Y167700D01*
G01X46750Y151667D02*
X44250D01*
Y152333D01*
X44375Y152547D01*
X44542Y152680D01*
X44875Y152733D01*
X45208Y152680D01*
X45417Y152520D01*
X45542Y152333D01*
Y151667D01*
G01Y152333D02*
X46750Y152733D01*
G01X46250Y153813D02*
X46542Y153973D01*
X46708Y154187D01*
X46750Y154427D01*
X46708Y154640D01*
X46500Y154853D01*
X46250Y154987D01*
X46000Y155013D01*
X45708Y154960D01*
X45500Y154773D01*
X45417Y154587D01*
Y154347D01*
G01Y154587D02*
X45292Y154747D01*
X45083Y154880D01*
X44833Y154933D01*
X44583Y154880D01*
X44375Y154747D01*
X44250Y154507D01*
X44292Y154267D01*
X44458Y154027D01*
G01X46750Y156600D02*
X46708Y156787D01*
X46583Y157000D01*
X46375Y157133D01*
X46083Y157187D01*
X45792Y157133D01*
X45542Y156973D01*
X45417Y156733D01*
Y156467D01*
X45333Y156307D01*
X45125Y156173D01*
X44833Y156120D01*
X44542Y156200D01*
X44333Y156387D01*
X44250Y156600D01*
X44333Y156813D01*
X44542Y157000D01*
X44833Y157080D01*
X45125Y157027D01*
X45333Y156893D01*
X45417Y156733D01*
Y156467D01*
X45542Y156227D01*
X45792Y156067D01*
X46083Y156013D01*
X46375Y156067D01*
X46583Y156200D01*
X46708Y156413D01*
X46750Y156600D01*
G01X45708Y158293D02*
X45417Y158480D01*
X45250Y158640D01*
X45167Y158853D01*
X45250Y159040D01*
X45417Y159173D01*
X45667Y159280D01*
X45958Y159307D01*
X46208Y159280D01*
X46458Y159173D01*
X46667Y159013D01*
X46750Y158827D01*
X46667Y158613D01*
X46417Y158427D01*
X46042Y158320D01*
X45625Y158293D01*
X45083Y158347D01*
X44792Y158427D01*
X44500Y158560D01*
X44292Y158747D01*
X44250Y158933D01*
X44333Y159120D01*
X44542Y159253D01*
G01X42050Y162667D02*
X39550D01*
Y163333D01*
X39675Y163547D01*
X39842Y163680D01*
X40175Y163733D01*
X40508Y163680D01*
X40717Y163520D01*
X40842Y163333D01*
Y162667D01*
G01Y163333D02*
X42050Y163733D01*
G01Y165720D02*
X39550D01*
X41342Y164733D01*
Y166067D01*
G01X41758Y167147D02*
X41967Y167333D01*
X42050Y167547D01*
X41967Y167760D01*
X41717Y167947D01*
X41342Y168080D01*
X40967Y168133D01*
X40508D01*
X40133Y168080D01*
X39800Y167947D01*
X39633Y167787D01*
X39550Y167600D01*
X39633Y167387D01*
X39800Y167227D01*
X40050Y167120D01*
X40383Y167067D01*
X40675Y167120D01*
X40967Y167253D01*
X41133Y167413D01*
X41175Y167600D01*
X41092Y167813D01*
X40883Y167973D01*
X40508Y168133D01*
G01X41758Y169347D02*
X41967Y169533D01*
X42050Y169747D01*
X41967Y169960D01*
X41717Y170147D01*
X41342Y170280D01*
X40967Y170333D01*
X40508D01*
X40133Y170280D01*
X39800Y170147D01*
X39633Y169987D01*
X39550Y169800D01*
X39633Y169587D01*
X39800Y169427D01*
X40050Y169320D01*
X40383Y169267D01*
X40675Y169320D01*
X40967Y169453D01*
X41133Y169613D01*
X41175Y169800D01*
X41092Y170013D01*
X40883Y170173D01*
X40508Y170333D01*
G01X42050Y172583D02*
X38950D01*
Y173542D01*
X39105Y173848D01*
X39312Y174040D01*
X39725Y174117D01*
X40138Y174040D01*
X40397Y173810D01*
X40552Y173542D01*
Y172583D01*
G01Y173542D02*
X42050Y174117D01*
G01Y176450D02*
X38950D01*
X39570Y175990D01*
G01X42050D02*
Y176910D01*
G01X39467Y178822D02*
X39157Y179052D01*
X39002Y179320D01*
X38950Y179627D01*
X39053Y180010D01*
X39312Y180278D01*
X39622Y180355D01*
X39932Y180317D01*
X40190Y180163D01*
X40707Y179397D01*
X41068Y179052D01*
X41585Y178822D01*
X42050Y178745D01*
Y180355D01*
G01X40758Y181922D02*
X40397Y182190D01*
X40190Y182420D01*
X40087Y182727D01*
X40190Y182995D01*
X40397Y183187D01*
X40707Y183340D01*
X41068Y183378D01*
X41378Y183340D01*
X41688Y183187D01*
X41947Y182957D01*
X42050Y182688D01*
X41947Y182382D01*
X41637Y182113D01*
X41172Y181960D01*
X40655Y181922D01*
X39983Y181998D01*
X39622Y182113D01*
X39260Y182305D01*
X39002Y182573D01*
X38950Y182842D01*
X39053Y183110D01*
X39312Y183302D01*
G01X33500Y170460D02*
Y170993D01*
X34250D01*
X34500Y170833D01*
X34667Y170647D01*
X34750Y170380D01*
X34667Y170113D01*
X34500Y169927D01*
X34250Y169767D01*
X33958Y169660D01*
X33625Y169607D01*
X33333D01*
X33083Y169660D01*
X32792Y169767D01*
X32542Y169927D01*
X32375Y170087D01*
X32250Y170300D01*
Y170487D01*
X32333Y170700D01*
X32500Y170860D01*
G01X34750Y171940D02*
X32250D01*
G01Y173060D02*
X34750D01*
G01X33500D02*
Y171940D01*
G01X34750Y175020D02*
X32250D01*
X34042Y174033D01*
Y175367D01*
G01X44950Y185057D02*
X47172D01*
X47637Y185210D01*
X47947Y185517D01*
X48050Y185900D01*
X47947Y186283D01*
X47637Y186590D01*
X47172Y186743D01*
X44950D01*
G01X48050Y189000D02*
X44950D01*
X45570Y188540D01*
G01X48050D02*
Y189460D01*
G01X46758Y191372D02*
X46397Y191640D01*
X46190Y191870D01*
X46087Y192177D01*
X46190Y192445D01*
X46397Y192637D01*
X46707Y192790D01*
X47068Y192828D01*
X47378Y192790D01*
X47688Y192637D01*
X47947Y192407D01*
X48050Y192138D01*
X47947Y191832D01*
X47637Y191563D01*
X47172Y191410D01*
X46655Y191372D01*
X45983Y191448D01*
X45622Y191563D01*
X45260Y191755D01*
X45002Y192023D01*
X44950Y192292D01*
X45053Y192560D01*
X45312Y192752D01*
G01X33000Y184450D02*
Y187550D01*
X32540Y186930D01*
G01Y184450D02*
X33460D01*
G01X32683Y194070D02*
X32875Y193760D01*
X33105Y193553D01*
X33373Y193450D01*
X33680Y193553D01*
X33910Y193760D01*
X34140Y194070D01*
X34217Y194483D01*
Y196550D01*
G01X37010Y193450D02*
Y196550D01*
X35592Y194328D01*
X37508D01*
G01X32208Y213243D02*
X32053Y213013D01*
X31950Y212745D01*
Y212438D01*
X32105Y212093D01*
X32363Y211825D01*
X32673Y211633D01*
X33190Y211480D01*
X33655Y211442D01*
X34120Y211518D01*
X34430Y211633D01*
X34740Y211863D01*
X34947Y212132D01*
X35050Y212400D01*
Y212668D01*
X34947Y212937D01*
X34792Y213167D01*
X34585Y213358D01*
G01X35050Y214733D02*
X31950D01*
Y215692D01*
X32105Y215998D01*
X32312Y216190D01*
X32725Y216267D01*
X33138Y216190D01*
X33397Y215960D01*
X33552Y215692D01*
Y214733D01*
G01Y215692D02*
X35050Y216267D01*
G01Y219060D02*
X31950D01*
X34172Y217642D01*
Y219558D01*
G01X31993Y204833D02*
X32153Y205083D01*
X32340Y205208D01*
X32553Y205250D01*
X32820Y205167D01*
X33007Y204958D01*
X33060Y204708D01*
X33033Y204458D01*
X32927Y204250D01*
X32393Y203833D01*
X32153Y203542D01*
X31993Y203125D01*
X31940Y202750D01*
X33060D01*
G01X38193Y217292D02*
X37963Y217447D01*
X37695Y217550D01*
X37388D01*
X37043Y217395D01*
X36775Y217137D01*
X36583Y216827D01*
X36430Y216310D01*
X36392Y215845D01*
X36468Y215380D01*
X36583Y215070D01*
X36813Y214760D01*
X37082Y214553D01*
X37350Y214450D01*
X37618D01*
X37887Y214553D01*
X38117Y214708D01*
X38308Y214915D01*
G01X39607Y215070D02*
X39837Y214708D01*
X40143Y214502D01*
X40488Y214450D01*
X40795Y214502D01*
X41102Y214760D01*
X41293Y215070D01*
X41332Y215380D01*
X41255Y215742D01*
X40987Y216000D01*
X40718Y216103D01*
X40373D01*
G01X40718D02*
X40948Y216258D01*
X41140Y216517D01*
X41217Y216827D01*
X41140Y217137D01*
X40948Y217395D01*
X40603Y217550D01*
X40258Y217498D01*
X39913Y217292D01*
G01X43550Y214450D02*
Y217550D01*
X43090Y216930D01*
G01Y214450D02*
X44010D01*
G01X46650D02*
X46918Y214502D01*
X47225Y214657D01*
X47417Y214915D01*
X47493Y215277D01*
X47417Y215638D01*
X47187Y215948D01*
X46842Y216103D01*
X46458D01*
X46228Y216207D01*
X46037Y216465D01*
X45960Y216827D01*
X46075Y217188D01*
X46343Y217447D01*
X46650Y217550D01*
X46957Y217447D01*
X47225Y217188D01*
X47340Y216827D01*
X47263Y216465D01*
X47072Y216207D01*
X46842Y216103D01*
X46458D01*
X46113Y215948D01*
X45883Y215638D01*
X45807Y215277D01*
X45883Y214915D01*
X46075Y214657D01*
X46382Y214502D01*
X46650Y214450D01*
G01X45050Y199583D02*
X41950D01*
Y200542D01*
X42105Y200848D01*
X42312Y201040D01*
X42725Y201117D01*
X43138Y201040D01*
X43397Y200810D01*
X43552Y200542D01*
Y199583D01*
G01Y200542D02*
X45050Y201117D01*
G01X44430Y202607D02*
X44792Y202837D01*
X44998Y203143D01*
X45050Y203488D01*
X44998Y203795D01*
X44740Y204102D01*
X44430Y204293D01*
X44120Y204332D01*
X43758Y204255D01*
X43500Y203987D01*
X43397Y203718D01*
Y203373D01*
G01Y203718D02*
X43242Y203948D01*
X42983Y204140D01*
X42673Y204217D01*
X42363Y204140D01*
X42105Y203948D01*
X41950Y203603D01*
X42002Y203258D01*
X42208Y202913D01*
G01X44430Y205707D02*
X44792Y205937D01*
X44998Y206243D01*
X45050Y206588D01*
X44998Y206895D01*
X44740Y207202D01*
X44430Y207393D01*
X44120Y207432D01*
X43758Y207355D01*
X43500Y207087D01*
X43397Y206818D01*
Y206473D01*
G01Y206818D02*
X43242Y207048D01*
X42983Y207240D01*
X42673Y207317D01*
X42363Y207240D01*
X42105Y207048D01*
X41950Y206703D01*
X42002Y206358D01*
X42208Y206013D01*
G01X45050Y209650D02*
X41950D01*
X42570Y209190D01*
G01X45050D02*
Y210110D01*
G01X37050Y199583D02*
X33950D01*
Y200542D01*
X34105Y200848D01*
X34312Y201040D01*
X34725Y201117D01*
X35138Y201040D01*
X35397Y200810D01*
X35552Y200542D01*
Y199583D01*
G01Y200542D02*
X37050Y201117D01*
G01X36430Y202607D02*
X36792Y202837D01*
X36998Y203143D01*
X37050Y203488D01*
X36998Y203795D01*
X36740Y204102D01*
X36430Y204293D01*
X36120Y204332D01*
X35758Y204255D01*
X35500Y203987D01*
X35397Y203718D01*
Y203373D01*
G01Y203718D02*
X35242Y203948D01*
X34983Y204140D01*
X34673Y204217D01*
X34363Y204140D01*
X34105Y203948D01*
X33950Y203603D01*
X34002Y203258D01*
X34208Y202913D01*
G01X37050Y206473D02*
X36378Y206550D01*
X35810Y206665D01*
X35293Y206818D01*
X34725Y207010D01*
X33950Y207317D01*
Y205783D01*
G01X34467Y208922D02*
X34157Y209152D01*
X34002Y209420D01*
X33950Y209727D01*
X34053Y210110D01*
X34312Y210378D01*
X34622Y210455D01*
X34932Y210417D01*
X35190Y210263D01*
X35707Y209497D01*
X36068Y209152D01*
X36585Y208922D01*
X37050Y208845D01*
Y210455D01*
G01X41050Y199583D02*
X37950D01*
Y200542D01*
X38105Y200848D01*
X38312Y201040D01*
X38725Y201117D01*
X39138Y201040D01*
X39397Y200810D01*
X39552Y200542D01*
Y199583D01*
G01Y200542D02*
X41050Y201117D01*
G01Y203450D02*
X37950D01*
X38570Y202990D01*
G01X41050D02*
Y203910D01*
G01X38467Y205822D02*
X38157Y206052D01*
X38002Y206320D01*
X37950Y206627D01*
X38053Y207010D01*
X38312Y207278D01*
X38622Y207355D01*
X38932Y207317D01*
X39190Y207163D01*
X39707Y206397D01*
X40068Y206052D01*
X40585Y205822D01*
X41050Y205745D01*
Y207355D01*
G01Y209650D02*
X37950D01*
X38570Y209190D01*
G01X41050D02*
Y210110D01*
G01X32063Y220950D02*
X32223Y220658D01*
X32437Y220492D01*
X32677Y220450D01*
X32890Y220492D01*
X33103Y220700D01*
X33237Y220950D01*
X33263Y221200D01*
X33210Y221492D01*
X33023Y221700D01*
X32837Y221783D01*
X32597D01*
G01X32837D02*
X32997Y221908D01*
X33130Y222117D01*
X33183Y222367D01*
X33130Y222617D01*
X32997Y222825D01*
X32757Y222950D01*
X32517Y222908D01*
X32277Y222742D01*
G01X43550Y218583D02*
X40450D01*
Y219542D01*
X40605Y219848D01*
X40812Y220040D01*
X41225Y220117D01*
X41638Y220040D01*
X41897Y219810D01*
X42052Y219542D01*
Y218583D01*
G01Y219542D02*
X43550Y220117D01*
G01X42930Y221607D02*
X43292Y221837D01*
X43498Y222143D01*
X43550Y222488D01*
X43498Y222795D01*
X43240Y223102D01*
X42930Y223293D01*
X42620Y223332D01*
X42258Y223255D01*
X42000Y222987D01*
X41897Y222718D01*
Y222373D01*
G01Y222718D02*
X41742Y222948D01*
X41483Y223140D01*
X41173Y223217D01*
X40863Y223140D01*
X40605Y222948D01*
X40450Y222603D01*
X40502Y222258D01*
X40708Y221913D01*
G01X43550Y225550D02*
X43498Y225818D01*
X43343Y226125D01*
X43085Y226317D01*
X42723Y226393D01*
X42362Y226317D01*
X42052Y226087D01*
X41897Y225742D01*
Y225358D01*
X41793Y225128D01*
X41535Y224937D01*
X41173Y224860D01*
X40812Y224975D01*
X40553Y225243D01*
X40450Y225550D01*
X40553Y225857D01*
X40812Y226125D01*
X41173Y226240D01*
X41535Y226163D01*
X41793Y225972D01*
X41897Y225742D01*
Y225358D01*
X42052Y225013D01*
X42362Y224783D01*
X42723Y224707D01*
X43085Y224783D01*
X43343Y224975D01*
X43498Y225282D01*
X43550Y225550D01*
G01Y228650D02*
X40450D01*
X41070Y228190D01*
G01X43550D02*
Y229110D01*
G01X39550Y218583D02*
X36450D01*
Y219542D01*
X36605Y219848D01*
X36812Y220040D01*
X37225Y220117D01*
X37638Y220040D01*
X37897Y219810D01*
X38052Y219542D01*
Y218583D01*
G01Y219542D02*
X39550Y220117D01*
G01Y222450D02*
X36450D01*
X37070Y221990D01*
G01X39550D02*
Y222910D01*
G01X36967Y224822D02*
X36657Y225052D01*
X36502Y225320D01*
X36450Y225627D01*
X36553Y226010D01*
X36812Y226278D01*
X37122Y226355D01*
X37432Y226317D01*
X37690Y226163D01*
X38207Y225397D01*
X38568Y225052D01*
X39085Y224822D01*
X39550Y224745D01*
Y226355D01*
G01Y228573D02*
X38878Y228650D01*
X38310Y228765D01*
X37793Y228918D01*
X37225Y229110D01*
X36450Y229417D01*
Y227883D01*
G01X41050Y231583D02*
X37950D01*
Y232542D01*
X38105Y232848D01*
X38312Y233040D01*
X38725Y233117D01*
X39138Y233040D01*
X39397Y232810D01*
X39552Y232542D01*
Y231583D01*
G01Y232542D02*
X41050Y233117D01*
G01Y235910D02*
X37950D01*
X40172Y234492D01*
Y236408D01*
G01X40688Y237898D02*
X40947Y238167D01*
X41050Y238473D01*
X40947Y238780D01*
X40637Y239048D01*
X40172Y239240D01*
X39707Y239317D01*
X39138D01*
X38673Y239240D01*
X38260Y239048D01*
X38053Y238818D01*
X37950Y238550D01*
X38053Y238243D01*
X38260Y238013D01*
X38570Y237860D01*
X38983Y237783D01*
X39345Y237860D01*
X39707Y238052D01*
X39913Y238282D01*
X39965Y238550D01*
X39862Y238857D01*
X39603Y239087D01*
X39138Y239317D01*
G01X41050Y241650D02*
X40998Y241918D01*
X40843Y242225D01*
X40585Y242417D01*
X40223Y242493D01*
X39862Y242417D01*
X39552Y242187D01*
X39397Y241842D01*
Y241458D01*
X39293Y241228D01*
X39035Y241037D01*
X38673Y240960D01*
X38312Y241075D01*
X38053Y241343D01*
X37950Y241650D01*
X38053Y241957D01*
X38312Y242225D01*
X38673Y242340D01*
X39035Y242263D01*
X39293Y242072D01*
X39397Y241842D01*
Y241458D01*
X39552Y241113D01*
X39862Y240883D01*
X40223Y240807D01*
X40585Y240883D01*
X40843Y241075D01*
X40998Y241382D01*
X41050Y241650D01*
G01X43450Y242057D02*
X45672D01*
X46137Y242210D01*
X46447Y242517D01*
X46550Y242900D01*
X46447Y243283D01*
X46137Y243590D01*
X45672Y243743D01*
X43450D01*
G01X46550Y246000D02*
X43450D01*
X44070Y245540D01*
G01X46550D02*
Y246460D01*
G01X46085Y248257D02*
X46343Y248487D01*
X46498Y248755D01*
X46550Y249100D01*
X46447Y249445D01*
X46240Y249713D01*
X45878Y249905D01*
X45465Y249943D01*
X45052Y249867D01*
X44793Y249675D01*
X44587Y249407D01*
X44535Y249138D01*
X44587Y248870D01*
X44793Y248525D01*
X43450Y248640D01*
Y249675D01*
G01X33689Y242520D02*
Y245620D01*
X33229Y245000D01*
G01Y242520D02*
X34149D01*
G01X33183Y250570D02*
X33375Y250260D01*
X33605Y250053D01*
X33873Y249950D01*
X34180Y250053D01*
X34410Y250260D01*
X34640Y250570D01*
X34717Y250983D01*
Y253050D01*
G01X36207Y250570D02*
X36437Y250208D01*
X36743Y250002D01*
X37088Y249950D01*
X37395Y250002D01*
X37702Y250260D01*
X37893Y250570D01*
X37932Y250880D01*
X37855Y251242D01*
X37587Y251500D01*
X37318Y251603D01*
X36973D01*
G01X37318D02*
X37548Y251758D01*
X37740Y252017D01*
X37817Y252327D01*
X37740Y252637D01*
X37548Y252895D01*
X37203Y253050D01*
X36858Y252998D01*
X36513Y252792D01*
G01X36550Y277083D02*
X33450D01*
Y278042D01*
X33605Y278348D01*
X33812Y278540D01*
X34225Y278617D01*
X34638Y278540D01*
X34897Y278310D01*
X35052Y278042D01*
Y277083D01*
G01Y278042D02*
X36550Y278617D01*
G01X35930Y280107D02*
X36292Y280337D01*
X36498Y280643D01*
X36550Y280988D01*
X36498Y281295D01*
X36240Y281602D01*
X35930Y281793D01*
X35620Y281832D01*
X35258Y281755D01*
X35000Y281487D01*
X34897Y281218D01*
Y280873D01*
G01Y281218D02*
X34742Y281448D01*
X34483Y281640D01*
X34173Y281717D01*
X33863Y281640D01*
X33605Y281448D01*
X33450Y281103D01*
X33502Y280758D01*
X33708Y280413D01*
G01X36188Y283398D02*
X36447Y283667D01*
X36550Y283973D01*
X36447Y284280D01*
X36137Y284548D01*
X35672Y284740D01*
X35207Y284817D01*
X34638D01*
X34173Y284740D01*
X33760Y284548D01*
X33553Y284318D01*
X33450Y284050D01*
X33553Y283743D01*
X33760Y283513D01*
X34070Y283360D01*
X34483Y283283D01*
X34845Y283360D01*
X35207Y283552D01*
X35413Y283782D01*
X35465Y284050D01*
X35362Y284357D01*
X35103Y284587D01*
X34638Y284817D01*
G01X33967Y286422D02*
X33657Y286652D01*
X33502Y286920D01*
X33450Y287227D01*
X33553Y287610D01*
X33812Y287878D01*
X34122Y287955D01*
X34432Y287917D01*
X34690Y287763D01*
X35207Y286997D01*
X35568Y286652D01*
X36085Y286422D01*
X36550Y286345D01*
Y287955D01*
G01X42050Y276583D02*
X38950D01*
Y277542D01*
X39105Y277848D01*
X39312Y278040D01*
X39725Y278117D01*
X40138Y278040D01*
X40397Y277810D01*
X40552Y277542D01*
Y276583D01*
G01Y277542D02*
X42050Y278117D01*
G01X41430Y279607D02*
X41792Y279837D01*
X41998Y280143D01*
X42050Y280488D01*
X41998Y280795D01*
X41740Y281102D01*
X41430Y281293D01*
X41120Y281332D01*
X40758Y281255D01*
X40500Y280987D01*
X40397Y280718D01*
Y280373D01*
G01Y280718D02*
X40242Y280948D01*
X39983Y281140D01*
X39673Y281217D01*
X39363Y281140D01*
X39105Y280948D01*
X38950Y280603D01*
X39002Y280258D01*
X39208Y279913D01*
G01X42050Y283473D02*
X41378Y283550D01*
X40810Y283665D01*
X40293Y283818D01*
X39725Y284010D01*
X38950Y284317D01*
Y282783D01*
G01X41585Y285807D02*
X41843Y286037D01*
X41998Y286305D01*
X42050Y286650D01*
X41947Y286995D01*
X41740Y287263D01*
X41378Y287455D01*
X40965Y287493D01*
X40552Y287417D01*
X40293Y287225D01*
X40087Y286957D01*
X40035Y286688D01*
X40087Y286420D01*
X40293Y286075D01*
X38950Y286190D01*
Y287225D01*
G01X32550Y277083D02*
X29450D01*
Y278042D01*
X29605Y278348D01*
X29812Y278540D01*
X30225Y278617D01*
X30638Y278540D01*
X30897Y278310D01*
X31052Y278042D01*
Y277083D01*
G01Y278042D02*
X32550Y278617D01*
G01X31930Y280107D02*
X32292Y280337D01*
X32498Y280643D01*
X32550Y280988D01*
X32498Y281295D01*
X32240Y281602D01*
X31930Y281793D01*
X31620Y281832D01*
X31258Y281755D01*
X31000Y281487D01*
X30897Y281218D01*
Y280873D01*
G01Y281218D02*
X30742Y281448D01*
X30483Y281640D01*
X30173Y281717D01*
X29863Y281640D01*
X29605Y281448D01*
X29450Y281103D01*
X29502Y280758D01*
X29708Y280413D01*
G01X32188Y283398D02*
X32447Y283667D01*
X32550Y283973D01*
X32447Y284280D01*
X32137Y284548D01*
X31672Y284740D01*
X31207Y284817D01*
X30638D01*
X30173Y284740D01*
X29760Y284548D01*
X29553Y284318D01*
X29450Y284050D01*
X29553Y283743D01*
X29760Y283513D01*
X30070Y283360D01*
X30483Y283283D01*
X30845Y283360D01*
X31207Y283552D01*
X31413Y283782D01*
X31465Y284050D01*
X31362Y284357D01*
X31103Y284587D01*
X30638Y284817D01*
G01X31930Y286307D02*
X32292Y286537D01*
X32498Y286843D01*
X32550Y287188D01*
X32498Y287495D01*
X32240Y287802D01*
X31930Y287993D01*
X31620Y288032D01*
X31258Y287955D01*
X31000Y287687D01*
X30897Y287418D01*
Y287073D01*
G01Y287418D02*
X30742Y287648D01*
X30483Y287840D01*
X30173Y287917D01*
X29863Y287840D01*
X29605Y287648D01*
X29450Y287303D01*
X29502Y286958D01*
X29708Y286613D01*
G01X48050Y274583D02*
X44950D01*
Y275542D01*
X45105Y275848D01*
X45312Y276040D01*
X45725Y276117D01*
X46138Y276040D01*
X46397Y275810D01*
X46552Y275542D01*
Y274583D01*
G01Y275542D02*
X48050Y276117D01*
G01X47430Y277607D02*
X47792Y277837D01*
X47998Y278143D01*
X48050Y278488D01*
X47998Y278795D01*
X47740Y279102D01*
X47430Y279293D01*
X47120Y279332D01*
X46758Y279255D01*
X46500Y278987D01*
X46397Y278718D01*
Y278373D01*
G01Y278718D02*
X46242Y278948D01*
X45983Y279140D01*
X45673Y279217D01*
X45363Y279140D01*
X45105Y278948D01*
X44950Y278603D01*
X45002Y278258D01*
X45208Y277913D01*
G01X48050Y281473D02*
X47378Y281550D01*
X46810Y281665D01*
X46293Y281818D01*
X45725Y282010D01*
X44950Y282317D01*
Y280783D01*
G01X48050Y284650D02*
X44950D01*
X45570Y284190D01*
G01X48050D02*
Y285110D01*
G01X39050Y305083D02*
X35950D01*
Y306042D01*
X36105Y306348D01*
X36312Y306540D01*
X36725Y306617D01*
X37138Y306540D01*
X37397Y306310D01*
X37552Y306042D01*
Y305083D01*
G01Y306042D02*
X39050Y306617D01*
G01Y309410D02*
X35950D01*
X38172Y307992D01*
Y309908D01*
G01X36467Y311322D02*
X36157Y311552D01*
X36002Y311820D01*
X35950Y312127D01*
X36053Y312510D01*
X36312Y312778D01*
X36622Y312855D01*
X36932Y312817D01*
X37190Y312663D01*
X37707Y311897D01*
X38068Y311552D01*
X38585Y311322D01*
X39050Y311245D01*
Y312855D01*
G01X37758Y314422D02*
X37397Y314690D01*
X37190Y314920D01*
X37087Y315227D01*
X37190Y315495D01*
X37397Y315687D01*
X37707Y315840D01*
X38068Y315878D01*
X38378Y315840D01*
X38688Y315687D01*
X38947Y315457D01*
X39050Y315188D01*
X38947Y314882D01*
X38637Y314613D01*
X38172Y314460D01*
X37655Y314422D01*
X36983Y314498D01*
X36622Y314613D01*
X36260Y314805D01*
X36002Y315073D01*
X35950Y315342D01*
X36053Y315610D01*
X36312Y315802D01*
G01X32050Y305083D02*
X28950D01*
Y306042D01*
X29105Y306348D01*
X29312Y306540D01*
X29725Y306617D01*
X30138Y306540D01*
X30397Y306310D01*
X30552Y306042D01*
Y305083D01*
G01Y306042D02*
X32050Y306617D01*
G01X31430Y308107D02*
X31792Y308337D01*
X31998Y308643D01*
X32050Y308988D01*
X31998Y309295D01*
X31740Y309602D01*
X31430Y309793D01*
X31120Y309832D01*
X30758Y309755D01*
X30500Y309487D01*
X30397Y309218D01*
Y308873D01*
G01Y309218D02*
X30242Y309448D01*
X29983Y309640D01*
X29673Y309717D01*
X29363Y309640D01*
X29105Y309448D01*
X28950Y309103D01*
X29002Y308758D01*
X29208Y308413D01*
G01X31688Y311398D02*
X31947Y311667D01*
X32050Y311973D01*
X31947Y312280D01*
X31637Y312548D01*
X31172Y312740D01*
X30707Y312817D01*
X30138D01*
X29673Y312740D01*
X29260Y312548D01*
X29053Y312318D01*
X28950Y312050D01*
X29053Y311743D01*
X29260Y311513D01*
X29570Y311360D01*
X29983Y311283D01*
X30345Y311360D01*
X30707Y311552D01*
X30913Y311782D01*
X30965Y312050D01*
X30862Y312357D01*
X30603Y312587D01*
X30138Y312817D01*
G01X31688Y314498D02*
X31947Y314767D01*
X32050Y315073D01*
X31947Y315380D01*
X31637Y315648D01*
X31172Y315840D01*
X30707Y315917D01*
X30138D01*
X29673Y315840D01*
X29260Y315648D01*
X29053Y315418D01*
X28950Y315150D01*
X29053Y314843D01*
X29260Y314613D01*
X29570Y314460D01*
X29983Y314383D01*
X30345Y314460D01*
X30707Y314652D01*
X30913Y314882D01*
X30965Y315150D01*
X30862Y315457D01*
X30603Y315687D01*
X30138Y315917D01*
G01X47057Y57550D02*
Y55328D01*
X47210Y54863D01*
X47517Y54553D01*
X47900Y54450D01*
X48283Y54553D01*
X48590Y54863D01*
X48743Y55328D01*
Y57550D01*
G01X51000Y54450D02*
Y57550D01*
X50540Y56930D01*
G01Y54450D02*
X51460D01*
G01X54560D02*
Y57550D01*
X53142Y55328D01*
X55058D01*
G01X46913Y59825D02*
X47073Y59617D01*
X47260Y59492D01*
X47500Y59450D01*
X47740Y59533D01*
X47927Y59700D01*
X48060Y59992D01*
X48087Y60325D01*
X48033Y60658D01*
X47900Y60867D01*
X47713Y61033D01*
X47527Y61075D01*
X47340Y61033D01*
X47100Y60867D01*
X47180Y61950D01*
X47900D01*
G01X62500Y57828D02*
X62687Y57870D01*
X62900Y57995D01*
X63033Y58203D01*
X63087Y58495D01*
X63033Y58786D01*
X62873Y59036D01*
X62633Y59161D01*
X62367D01*
X62207Y59245D01*
X62073Y59453D01*
X62020Y59745D01*
X62100Y60036D01*
X62287Y60245D01*
X62500Y60328D01*
X62713Y60245D01*
X62900Y60036D01*
X62980Y59745D01*
X62927Y59453D01*
X62793Y59245D01*
X62633Y59161D01*
X62367D01*
X62127Y59036D01*
X61967Y58786D01*
X61913Y58495D01*
X61967Y58203D01*
X62100Y57995D01*
X62313Y57870D01*
X62500Y57828D01*
G01X47820Y78828D02*
Y81328D01*
X46833Y79536D01*
X48167D01*
G01X61450Y89350D02*
X64550D01*
G01X61450Y88468D02*
Y90232D01*
G01X64550Y91683D02*
X61450D01*
Y92603D01*
X61605Y92910D01*
X61967Y93140D01*
X62380Y93217D01*
X62793Y93140D01*
X63103Y92948D01*
X63258Y92603D01*
Y91683D01*
G01X63930Y94707D02*
X64292Y94937D01*
X64498Y95243D01*
X64550Y95588D01*
X64498Y95895D01*
X64240Y96202D01*
X63930Y96393D01*
X63620Y96432D01*
X63258Y96355D01*
X63000Y96087D01*
X62897Y95818D01*
Y95473D01*
G01Y95818D02*
X62742Y96048D01*
X62483Y96240D01*
X62173Y96317D01*
X61863Y96240D01*
X61605Y96048D01*
X61450Y95703D01*
X61502Y95358D01*
X61708Y95013D01*
G01X64085Y97807D02*
X64343Y98037D01*
X64498Y98305D01*
X64550Y98650D01*
X64447Y98995D01*
X64240Y99263D01*
X63878Y99455D01*
X63465Y99493D01*
X63052Y99417D01*
X62793Y99225D01*
X62587Y98957D01*
X62535Y98688D01*
X62587Y98420D01*
X62793Y98075D01*
X61450Y98190D01*
Y99225D01*
G01X54250Y103700D02*
X56750D01*
G01X54250Y103087D02*
Y104313D01*
G01X56750Y105367D02*
X54250D01*
Y106007D01*
X54375Y106220D01*
X54667Y106380D01*
X55000Y106433D01*
X55333Y106380D01*
X55583Y106247D01*
X55708Y106007D01*
Y105367D01*
G01X56250Y107513D02*
X56542Y107673D01*
X56708Y107887D01*
X56750Y108127D01*
X56708Y108340D01*
X56500Y108553D01*
X56250Y108687D01*
X56000Y108713D01*
X55708Y108660D01*
X55500Y108473D01*
X55417Y108287D01*
Y108047D01*
G01Y108287D02*
X55292Y108447D01*
X55083Y108580D01*
X54833Y108633D01*
X54583Y108580D01*
X54375Y108447D01*
X54250Y108207D01*
X54292Y107967D01*
X54458Y107727D01*
G01X54250Y110300D02*
X54333Y110087D01*
X54542Y109927D01*
X54792Y109820D01*
X55125Y109740D01*
X55500Y109713D01*
X55875Y109740D01*
X56208Y109820D01*
X56458Y109927D01*
X56667Y110087D01*
X56750Y110300D01*
X56667Y110513D01*
X56458Y110673D01*
X56208Y110780D01*
X55875Y110860D01*
X55500Y110887D01*
X55125Y110860D01*
X54792Y110780D01*
X54542Y110673D01*
X54333Y110513D01*
X54250Y110300D01*
G01X48413Y116125D02*
X48573Y115917D01*
X48760Y115792D01*
X49000Y115750D01*
X49240Y115833D01*
X49427Y116000D01*
X49560Y116292D01*
X49587Y116625D01*
X49533Y116958D01*
X49400Y117167D01*
X49213Y117333D01*
X49027Y117375D01*
X48840Y117333D01*
X48600Y117167D01*
X48680Y118250D01*
X49400D01*
G01X60000Y115750D02*
X60187Y115792D01*
X60400Y115917D01*
X60533Y116125D01*
X60587Y116417D01*
X60533Y116708D01*
X60373Y116958D01*
X60133Y117083D01*
X59867D01*
X59707Y117167D01*
X59573Y117375D01*
X59520Y117667D01*
X59600Y117958D01*
X59787Y118167D01*
X60000Y118250D01*
X60213Y118167D01*
X60400Y117958D01*
X60480Y117667D01*
X60427Y117375D01*
X60293Y117167D01*
X60133Y117083D01*
X59867D01*
X59627Y116958D01*
X59467Y116708D01*
X59413Y116417D01*
X59467Y116125D01*
X59600Y115917D01*
X59813Y115792D01*
X60000Y115750D01*
G01X47820Y134359D02*
Y136859D01*
X46833Y135067D01*
X48167D01*
G01X61958Y156887D02*
X61833Y156727D01*
X61750Y156540D01*
Y156327D01*
X61875Y156087D01*
X62083Y155900D01*
X62333Y155767D01*
X62750Y155660D01*
X63125Y155633D01*
X63500Y155687D01*
X63750Y155767D01*
X64000Y155927D01*
X64167Y156113D01*
X64250Y156300D01*
Y156487D01*
X64167Y156673D01*
X64042Y156833D01*
X63875Y156967D01*
G01X64250Y158500D02*
X64208Y158687D01*
X64083Y158900D01*
X63875Y159033D01*
X63583Y159087D01*
X63292Y159033D01*
X63042Y158873D01*
X62917Y158633D01*
Y158367D01*
X62833Y158207D01*
X62625Y158073D01*
X62333Y158020D01*
X62042Y158100D01*
X61833Y158287D01*
X61750Y158500D01*
X61833Y158713D01*
X62042Y158900D01*
X62333Y158980D01*
X62625Y158927D01*
X62833Y158793D01*
X62917Y158633D01*
Y158367D01*
X63042Y158127D01*
X63292Y157967D01*
X63583Y157913D01*
X63875Y157967D01*
X64083Y158100D01*
X64208Y158313D01*
X64250Y158500D01*
G01Y161020D02*
X61750D01*
X63542Y160033D01*
Y161367D01*
G01X51287Y154042D02*
X51127Y154167D01*
X50940Y154250D01*
X50727D01*
X50487Y154125D01*
X50300Y153917D01*
X50167Y153667D01*
X50060Y153250D01*
X50033Y152875D01*
X50087Y152500D01*
X50167Y152250D01*
X50327Y152000D01*
X50513Y151833D01*
X50700Y151750D01*
X50887D01*
X51073Y151833D01*
X51233Y151958D01*
X51367Y152125D01*
G01X52313Y152250D02*
X52473Y151958D01*
X52687Y151792D01*
X52927Y151750D01*
X53140Y151792D01*
X53353Y152000D01*
X53487Y152250D01*
X53513Y152500D01*
X53460Y152792D01*
X53273Y153000D01*
X53087Y153083D01*
X52847D01*
G01X53087D02*
X53247Y153208D01*
X53380Y153417D01*
X53433Y153667D01*
X53380Y153917D01*
X53247Y154125D01*
X53007Y154250D01*
X52767Y154208D01*
X52527Y154042D01*
G01X55100Y151750D02*
Y154250D01*
X54780Y153750D01*
G01Y151750D02*
X55420D01*
G01X57300Y154250D02*
X57087Y154167D01*
X56927Y153958D01*
X56820Y153708D01*
X56740Y153375D01*
X56713Y153000D01*
X56740Y152625D01*
X56820Y152292D01*
X56927Y152042D01*
X57087Y151833D01*
X57300Y151750D01*
X57513Y151833D01*
X57673Y152042D01*
X57780Y152292D01*
X57860Y152625D01*
X57887Y153000D01*
X57860Y153375D01*
X57780Y153708D01*
X57673Y153958D01*
X57513Y154167D01*
X57300Y154250D01*
G01X49667Y159250D02*
Y161750D01*
X50333D01*
X50547Y161625D01*
X50680Y161458D01*
X50733Y161125D01*
X50680Y160792D01*
X50520Y160583D01*
X50333Y160458D01*
X49667D01*
G01X50333D02*
X50733Y159250D01*
G01X51813Y159750D02*
X51973Y159458D01*
X52187Y159292D01*
X52427Y159250D01*
X52640Y159292D01*
X52853Y159500D01*
X52987Y159750D01*
X53013Y160000D01*
X52960Y160292D01*
X52773Y160500D01*
X52587Y160583D01*
X52347D01*
G01X52587D02*
X52747Y160708D01*
X52880Y160917D01*
X52933Y161167D01*
X52880Y161417D01*
X52747Y161625D01*
X52507Y161750D01*
X52267Y161708D01*
X52027Y161542D01*
G01X54600Y159250D02*
X54787Y159292D01*
X55000Y159417D01*
X55133Y159625D01*
X55187Y159917D01*
X55133Y160208D01*
X54973Y160458D01*
X54733Y160583D01*
X54467D01*
X54307Y160667D01*
X54173Y160875D01*
X54120Y161167D01*
X54200Y161458D01*
X54387Y161667D01*
X54600Y161750D01*
X54813Y161667D01*
X55000Y161458D01*
X55080Y161167D01*
X55027Y160875D01*
X54893Y160667D01*
X54733Y160583D01*
X54467D01*
X54227Y160458D01*
X54067Y160208D01*
X54013Y159917D01*
X54067Y159625D01*
X54200Y159417D01*
X54413Y159292D01*
X54600Y159250D01*
G01X56213Y159750D02*
X56373Y159458D01*
X56587Y159292D01*
X56827Y159250D01*
X57040Y159292D01*
X57253Y159500D01*
X57387Y159750D01*
X57413Y160000D01*
X57360Y160292D01*
X57173Y160500D01*
X56987Y160583D01*
X56747D01*
G01X56987D02*
X57147Y160708D01*
X57280Y160917D01*
X57333Y161167D01*
X57280Y161417D01*
X57147Y161625D01*
X56907Y161750D01*
X56667Y161708D01*
X56427Y161542D01*
G01X47913Y173325D02*
X48073Y173117D01*
X48260Y172992D01*
X48500Y172950D01*
X48740Y173033D01*
X48927Y173200D01*
X49060Y173492D01*
X49087Y173825D01*
X49033Y174158D01*
X48900Y174367D01*
X48713Y174533D01*
X48527Y174575D01*
X48340Y174533D01*
X48100Y174367D01*
X48180Y175450D01*
X48900D01*
G01X61500Y176750D02*
X61687Y176792D01*
X61900Y176917D01*
X62033Y177125D01*
X62087Y177417D01*
X62033Y177708D01*
X61873Y177958D01*
X61633Y178083D01*
X61367D01*
X61207Y178167D01*
X61073Y178375D01*
X61020Y178667D01*
X61100Y178958D01*
X61287Y179167D01*
X61500Y179250D01*
X61713Y179167D01*
X61900Y178958D01*
X61980Y178667D01*
X61927Y178375D01*
X61793Y178167D01*
X61633Y178083D01*
X61367D01*
X61127Y177958D01*
X60967Y177708D01*
X60913Y177417D01*
X60967Y177125D01*
X61100Y176917D01*
X61313Y176792D01*
X61500Y176750D01*
G01X58200Y174750D02*
Y172250D01*
G01X57587Y174750D02*
X58813D01*
G01X59867Y172250D02*
Y174750D01*
X60507D01*
X60720Y174625D01*
X60880Y174333D01*
X60933Y174000D01*
X60880Y173667D01*
X60747Y173417D01*
X60507Y173292D01*
X59867D01*
G01X62093Y174333D02*
X62253Y174583D01*
X62440Y174708D01*
X62653Y174750D01*
X62920Y174667D01*
X63107Y174458D01*
X63160Y174208D01*
X63133Y173958D01*
X63027Y173750D01*
X62493Y173333D01*
X62253Y173042D01*
X62093Y172625D01*
X62040Y172250D01*
X63160D01*
G01X64347Y172542D02*
X64533Y172333D01*
X64747Y172250D01*
X64960Y172333D01*
X65147Y172583D01*
X65280Y172958D01*
X65333Y173333D01*
Y173792D01*
X65280Y174167D01*
X65147Y174500D01*
X64987Y174667D01*
X64800Y174750D01*
X64587Y174667D01*
X64427Y174500D01*
X64320Y174250D01*
X64267Y173917D01*
X64320Y173625D01*
X64453Y173333D01*
X64613Y173167D01*
X64800Y173125D01*
X65013Y173208D01*
X65173Y173417D01*
X65333Y173792D01*
G01X49820Y195950D02*
Y198450D01*
X48833Y196658D01*
X50167D01*
G01X58750Y216200D02*
X61250D01*
G01X58750Y215587D02*
Y216813D01*
G01X61250Y217867D02*
X58750D01*
Y218507D01*
X58875Y218720D01*
X59167Y218880D01*
X59500Y218933D01*
X59833Y218880D01*
X60083Y218747D01*
X60208Y218507D01*
Y217867D01*
G01X59167Y220093D02*
X58917Y220253D01*
X58792Y220440D01*
X58750Y220653D01*
X58833Y220920D01*
X59042Y221107D01*
X59292Y221160D01*
X59542Y221133D01*
X59750Y221027D01*
X60167Y220493D01*
X60458Y220253D01*
X60875Y220093D01*
X61250Y220040D01*
Y221160D01*
G01Y222800D02*
X61208Y222987D01*
X61083Y223200D01*
X60875Y223333D01*
X60583Y223387D01*
X60292Y223333D01*
X60042Y223173D01*
X59917Y222933D01*
Y222667D01*
X59833Y222507D01*
X59625Y222373D01*
X59333Y222320D01*
X59042Y222400D01*
X58833Y222587D01*
X58750Y222800D01*
X58833Y223013D01*
X59042Y223200D01*
X59333Y223280D01*
X59625Y223227D01*
X59833Y223093D01*
X59917Y222933D01*
Y222667D01*
X60042Y222427D01*
X60292Y222267D01*
X60583Y222213D01*
X60875Y222267D01*
X61083Y222400D01*
X61208Y222613D01*
X61250Y222800D01*
G01X63287Y234542D02*
X63127Y234667D01*
X62940Y234750D01*
X62727D01*
X62487Y234625D01*
X62300Y234417D01*
X62167Y234167D01*
X62060Y233750D01*
X62033Y233375D01*
X62087Y233000D01*
X62167Y232750D01*
X62327Y232500D01*
X62513Y232333D01*
X62700Y232250D01*
X62887D01*
X63073Y232333D01*
X63233Y232458D01*
X63367Y232625D01*
G01X64313Y232750D02*
X64473Y232458D01*
X64687Y232292D01*
X64927Y232250D01*
X65140Y232292D01*
X65353Y232500D01*
X65487Y232750D01*
X65513Y233000D01*
X65460Y233292D01*
X65273Y233500D01*
X65087Y233583D01*
X64847D01*
G01X65087D02*
X65247Y233708D01*
X65380Y233917D01*
X65433Y234167D01*
X65380Y234417D01*
X65247Y234625D01*
X65007Y234750D01*
X64767Y234708D01*
X64527Y234542D01*
G01X67100Y232250D02*
Y234750D01*
X66780Y234250D01*
G01Y232250D02*
X67420D01*
G01X68713Y232750D02*
X68873Y232458D01*
X69087Y232292D01*
X69327Y232250D01*
X69540Y232292D01*
X69753Y232500D01*
X69887Y232750D01*
X69913Y233000D01*
X69860Y233292D01*
X69673Y233500D01*
X69487Y233583D01*
X69247D01*
G01X69487D02*
X69647Y233708D01*
X69780Y233917D01*
X69833Y234167D01*
X69780Y234417D01*
X69647Y234625D01*
X69407Y234750D01*
X69167Y234708D01*
X68927Y234542D01*
G01X47913Y230825D02*
X48073Y230617D01*
X48260Y230492D01*
X48500Y230450D01*
X48740Y230533D01*
X48927Y230700D01*
X49060Y230992D01*
X49087Y231325D01*
X49033Y231658D01*
X48900Y231867D01*
X48713Y232033D01*
X48527Y232075D01*
X48340Y232033D01*
X48100Y231867D01*
X48180Y232950D01*
X48900D01*
G01X61000Y230750D02*
X61187Y230792D01*
X61400Y230917D01*
X61533Y231125D01*
X61587Y231417D01*
X61533Y231708D01*
X61373Y231958D01*
X61133Y232083D01*
X60867D01*
X60707Y232167D01*
X60573Y232375D01*
X60520Y232667D01*
X60600Y232958D01*
X60787Y233167D01*
X61000Y233250D01*
X61213Y233167D01*
X61400Y232958D01*
X61480Y232667D01*
X61427Y232375D01*
X61293Y232167D01*
X61133Y232083D01*
X60867D01*
X60627Y231958D01*
X60467Y231708D01*
X60413Y231417D01*
X60467Y231125D01*
X60600Y230917D01*
X60813Y230792D01*
X61000Y230750D01*
G01X48320Y247450D02*
Y249950D01*
X47333Y248158D01*
X48667D01*
G01X61250Y240200D02*
X63750D01*
G01X61250Y239587D02*
Y240813D01*
G01X63750Y241867D02*
X61250D01*
Y242507D01*
X61375Y242720D01*
X61667Y242880D01*
X62000Y242933D01*
X62333Y242880D01*
X62583Y242747D01*
X62708Y242507D01*
Y241867D01*
G01X63250Y244013D02*
X63542Y244173D01*
X63708Y244387D01*
X63750Y244627D01*
X63708Y244840D01*
X63500Y245053D01*
X63250Y245187D01*
X63000Y245213D01*
X62708Y245160D01*
X62500Y244973D01*
X62417Y244787D01*
Y244547D01*
G01Y244787D02*
X62292Y244947D01*
X62083Y245080D01*
X61833Y245133D01*
X61583Y245080D01*
X61375Y244947D01*
X61250Y244707D01*
X61292Y244467D01*
X61458Y244227D01*
G01X61667Y246293D02*
X61417Y246453D01*
X61292Y246640D01*
X61250Y246853D01*
X61333Y247120D01*
X61542Y247307D01*
X61792Y247360D01*
X62042Y247333D01*
X62250Y247227D01*
X62667Y246693D01*
X62958Y246453D01*
X63375Y246293D01*
X63750Y246240D01*
Y247360D01*
G01X55767Y267250D02*
Y269750D01*
X56433D01*
X56647Y269625D01*
X56780Y269458D01*
X56833Y269125D01*
X56780Y268792D01*
X56620Y268583D01*
X56433Y268458D01*
X55767D01*
G01X56433D02*
X56833Y267250D01*
G01X58447D02*
X58500Y267792D01*
X58580Y268250D01*
X58687Y268667D01*
X58820Y269125D01*
X59033Y269750D01*
X57967D01*
G01X60193Y269333D02*
X60353Y269583D01*
X60540Y269708D01*
X60753Y269750D01*
X61020Y269667D01*
X61207Y269458D01*
X61260Y269208D01*
X61233Y268958D01*
X61127Y268750D01*
X60593Y268333D01*
X60353Y268042D01*
X60193Y267625D01*
X60140Y267250D01*
X61260D01*
G01X57550Y274583D02*
X54450D01*
Y275542D01*
X54605Y275848D01*
X54812Y276040D01*
X55225Y276117D01*
X55638Y276040D01*
X55897Y275810D01*
X56052Y275542D01*
Y274583D01*
G01Y275542D02*
X57550Y276117D01*
G01X56930Y277607D02*
X57292Y277837D01*
X57498Y278143D01*
X57550Y278488D01*
X57498Y278795D01*
X57240Y279102D01*
X56930Y279293D01*
X56620Y279332D01*
X56258Y279255D01*
X56000Y278987D01*
X55897Y278718D01*
Y278373D01*
G01Y278718D02*
X55742Y278948D01*
X55483Y279140D01*
X55173Y279217D01*
X54863Y279140D01*
X54605Y278948D01*
X54450Y278603D01*
X54502Y278258D01*
X54708Y277913D01*
G01X56258Y280822D02*
X55897Y281090D01*
X55690Y281320D01*
X55587Y281627D01*
X55690Y281895D01*
X55897Y282087D01*
X56207Y282240D01*
X56568Y282278D01*
X56878Y282240D01*
X57188Y282087D01*
X57447Y281857D01*
X57550Y281588D01*
X57447Y281282D01*
X57137Y281013D01*
X56672Y280860D01*
X56155Y280822D01*
X55483Y280898D01*
X55122Y281013D01*
X54760Y281205D01*
X54502Y281473D01*
X54450Y281742D01*
X54553Y282010D01*
X54812Y282202D01*
G01X57550Y284650D02*
X54450D01*
X55070Y284190D01*
G01X57550D02*
Y285110D01*
G01X55767Y270750D02*
Y273250D01*
X56433D01*
X56647Y273125D01*
X56780Y272958D01*
X56833Y272625D01*
X56780Y272292D01*
X56620Y272083D01*
X56433Y271958D01*
X55767D01*
G01X56433D02*
X56833Y270750D01*
G01X58447D02*
X58500Y271292D01*
X58580Y271750D01*
X58687Y272167D01*
X58820Y272625D01*
X59033Y273250D01*
X57967D01*
G01X60700D02*
X60487Y273167D01*
X60327Y272958D01*
X60220Y272708D01*
X60140Y272375D01*
X60113Y272000D01*
X60140Y271625D01*
X60220Y271292D01*
X60327Y271042D01*
X60487Y270833D01*
X60700Y270750D01*
X60913Y270833D01*
X61073Y271042D01*
X61180Y271292D01*
X61260Y271625D01*
X61287Y272000D01*
X61260Y272375D01*
X61180Y272708D01*
X61073Y272958D01*
X60913Y273167D01*
X60700Y273250D01*
G01X52050Y274583D02*
X48950D01*
Y275542D01*
X49105Y275848D01*
X49312Y276040D01*
X49725Y276117D01*
X50138Y276040D01*
X50397Y275810D01*
X50552Y275542D01*
Y274583D01*
G01Y275542D02*
X52050Y276117D01*
G01Y278450D02*
X48950D01*
X49570Y277990D01*
G01X52050D02*
Y278910D01*
G01X49467Y280822D02*
X49157Y281052D01*
X49002Y281320D01*
X48950Y281627D01*
X49053Y282010D01*
X49312Y282278D01*
X49622Y282355D01*
X49932Y282317D01*
X50190Y282163D01*
X50707Y281397D01*
X51068Y281052D01*
X51585Y280822D01*
X52050Y280745D01*
Y282355D01*
G01X48950Y284650D02*
X49053Y284343D01*
X49312Y284113D01*
X49622Y283960D01*
X50035Y283845D01*
X50500Y283807D01*
X50965Y283845D01*
X51378Y283960D01*
X51688Y284113D01*
X51947Y284343D01*
X52050Y284650D01*
X51947Y284957D01*
X51688Y285187D01*
X51378Y285340D01*
X50965Y285455D01*
X50500Y285493D01*
X50035Y285455D01*
X49622Y285340D01*
X49312Y285187D01*
X49053Y284957D01*
X48950Y284650D01*
G01X60083Y284450D02*
Y287550D01*
X61042D01*
X61348Y287395D01*
X61540Y287188D01*
X61617Y286775D01*
X61540Y286362D01*
X61310Y286103D01*
X61042Y285948D01*
X60083D01*
G01X61042D02*
X61617Y284450D01*
G01X63107Y285070D02*
X63337Y284708D01*
X63643Y284502D01*
X63988Y284450D01*
X64295Y284502D01*
X64602Y284760D01*
X64793Y285070D01*
X64832Y285380D01*
X64755Y285742D01*
X64487Y286000D01*
X64218Y286103D01*
X63873D01*
G01X64218D02*
X64448Y286258D01*
X64640Y286517D01*
X64717Y286827D01*
X64640Y287137D01*
X64448Y287395D01*
X64103Y287550D01*
X63758Y287498D01*
X63413Y287292D01*
G01X67510Y284450D02*
Y287550D01*
X66092Y285328D01*
X68008D01*
G01X69422Y285742D02*
X69690Y286103D01*
X69920Y286310D01*
X70227Y286413D01*
X70495Y286310D01*
X70687Y286103D01*
X70840Y285793D01*
X70878Y285432D01*
X70840Y285122D01*
X70687Y284812D01*
X70457Y284553D01*
X70188Y284450D01*
X69882Y284553D01*
X69613Y284863D01*
X69460Y285328D01*
X69422Y285845D01*
X69498Y286517D01*
X69613Y286878D01*
X69805Y287240D01*
X70073Y287498D01*
X70342Y287550D01*
X70610Y287447D01*
X70802Y287188D01*
G01X48193Y291792D02*
X47963Y291947D01*
X47695Y292050D01*
X47388D01*
X47043Y291895D01*
X46775Y291637D01*
X46583Y291327D01*
X46430Y290810D01*
X46392Y290345D01*
X46468Y289880D01*
X46583Y289570D01*
X46813Y289260D01*
X47082Y289053D01*
X47350Y288950D01*
X47618D01*
X47887Y289053D01*
X48117Y289208D01*
X48308Y289415D01*
G01X49607Y289570D02*
X49837Y289208D01*
X50143Y289002D01*
X50488Y288950D01*
X50795Y289002D01*
X51102Y289260D01*
X51293Y289570D01*
X51332Y289880D01*
X51255Y290242D01*
X50987Y290500D01*
X50718Y290603D01*
X50373D01*
G01X50718D02*
X50948Y290758D01*
X51140Y291017D01*
X51217Y291327D01*
X51140Y291637D01*
X50948Y291895D01*
X50603Y292050D01*
X50258Y291998D01*
X49913Y291792D01*
G01X53550Y288950D02*
Y292050D01*
X53090Y291430D01*
G01Y288950D02*
X54010D01*
G01X56573D02*
X56650Y289622D01*
X56765Y290190D01*
X56918Y290707D01*
X57110Y291275D01*
X57417Y292050D01*
X55883D01*
G01X55350Y302550D02*
Y299450D01*
G01X54468Y302550D02*
X56232D01*
G01X57683Y299450D02*
Y302550D01*
X58603D01*
X58910Y302395D01*
X59140Y302033D01*
X59217Y301620D01*
X59140Y301207D01*
X58948Y300897D01*
X58603Y300742D01*
X57683D01*
G01X60822Y302033D02*
X61052Y302343D01*
X61320Y302498D01*
X61627Y302550D01*
X62010Y302447D01*
X62278Y302188D01*
X62355Y301878D01*
X62317Y301568D01*
X62163Y301310D01*
X61397Y300793D01*
X61052Y300432D01*
X60822Y299915D01*
X60745Y299450D01*
X62355D01*
G01X65110D02*
Y302550D01*
X63692Y300328D01*
X65608D01*
G01X48550Y305083D02*
X45450D01*
Y306042D01*
X45605Y306348D01*
X45812Y306540D01*
X46225Y306617D01*
X46638Y306540D01*
X46897Y306310D01*
X47052Y306042D01*
Y305083D01*
G01Y306042D02*
X48550Y306617D01*
G01X47930Y308107D02*
X48292Y308337D01*
X48498Y308643D01*
X48550Y308988D01*
X48498Y309295D01*
X48240Y309602D01*
X47930Y309793D01*
X47620Y309832D01*
X47258Y309755D01*
X47000Y309487D01*
X46897Y309218D01*
Y308873D01*
G01Y309218D02*
X46742Y309448D01*
X46483Y309640D01*
X46173Y309717D01*
X45863Y309640D01*
X45605Y309448D01*
X45450Y309103D01*
X45502Y308758D01*
X45708Y308413D01*
G01X48188Y311398D02*
X48447Y311667D01*
X48550Y311973D01*
X48447Y312280D01*
X48137Y312548D01*
X47672Y312740D01*
X47207Y312817D01*
X46638D01*
X46173Y312740D01*
X45760Y312548D01*
X45553Y312318D01*
X45450Y312050D01*
X45553Y311743D01*
X45760Y311513D01*
X46070Y311360D01*
X46483Y311283D01*
X46845Y311360D01*
X47207Y311552D01*
X47413Y311782D01*
X47465Y312050D01*
X47362Y312357D01*
X47103Y312587D01*
X46638Y312817D01*
G01X48550Y315150D02*
X48498Y315418D01*
X48343Y315725D01*
X48085Y315917D01*
X47723Y315993D01*
X47362Y315917D01*
X47052Y315687D01*
X46897Y315342D01*
Y314958D01*
X46793Y314728D01*
X46535Y314537D01*
X46173Y314460D01*
X45812Y314575D01*
X45553Y314843D01*
X45450Y315150D01*
X45553Y315457D01*
X45812Y315725D01*
X46173Y315840D01*
X46535Y315763D01*
X46793Y315572D01*
X46897Y315342D01*
Y314958D01*
X47052Y314613D01*
X47362Y314383D01*
X47723Y314307D01*
X48085Y314383D01*
X48343Y314575D01*
X48498Y314882D01*
X48550Y315150D01*
G01X60450Y335057D02*
X62672D01*
X63137Y335210D01*
X63447Y335517D01*
X63550Y335900D01*
X63447Y336283D01*
X63137Y336590D01*
X62672Y336743D01*
X60450D01*
G01X63550Y339000D02*
X60450D01*
X61070Y338540D01*
G01X63550D02*
Y339460D01*
G01Y342023D02*
X62878Y342100D01*
X62310Y342215D01*
X61793Y342368D01*
X61225Y342560D01*
X60450Y342867D01*
Y341333D01*
G01X50083Y322950D02*
Y326050D01*
X51042D01*
X51348Y325895D01*
X51540Y325688D01*
X51617Y325275D01*
X51540Y324862D01*
X51310Y324603D01*
X51042Y324448D01*
X50083D01*
G01X51042D02*
X51617Y322950D01*
G01X54410D02*
Y326050D01*
X52992Y323828D01*
X54908D01*
G01X57510Y322950D02*
Y326050D01*
X56092Y323828D01*
X58008D01*
G01X59307Y323415D02*
X59537Y323157D01*
X59805Y323002D01*
X60150Y322950D01*
X60495Y323053D01*
X60763Y323260D01*
X60955Y323622D01*
X60993Y324035D01*
X60917Y324448D01*
X60725Y324707D01*
X60457Y324913D01*
X60188Y324965D01*
X59920Y324913D01*
X59575Y324707D01*
X59690Y326050D01*
X60725D01*
G01X56550Y357083D02*
X53450D01*
Y358042D01*
X53605Y358348D01*
X53812Y358540D01*
X54225Y358617D01*
X54638Y358540D01*
X54897Y358310D01*
X55052Y358042D01*
Y357083D01*
G01Y358042D02*
X56550Y358617D01*
G01Y361410D02*
X53450D01*
X55672Y359992D01*
Y361908D01*
G01X56550Y364510D02*
X53450D01*
X55672Y363092D01*
Y365008D01*
G01X53967Y366422D02*
X53657Y366652D01*
X53502Y366920D01*
X53450Y367227D01*
X53553Y367610D01*
X53812Y367878D01*
X54122Y367955D01*
X54432Y367917D01*
X54690Y367763D01*
X55207Y366997D01*
X55568Y366652D01*
X56085Y366422D01*
X56550Y366345D01*
Y367955D01*
G01X50450Y383133D02*
X53550D01*
Y384667D01*
G01X50967Y386272D02*
X50657Y386502D01*
X50502Y386770D01*
X50450Y387077D01*
X50553Y387460D01*
X50812Y387728D01*
X51122Y387805D01*
X51432Y387767D01*
X51690Y387613D01*
X52207Y386847D01*
X52568Y386502D01*
X53085Y386272D01*
X53550Y386195D01*
Y387805D01*
G01X50450Y390100D02*
X50553Y389793D01*
X50812Y389563D01*
X51122Y389410D01*
X51535Y389295D01*
X52000Y389257D01*
X52465Y389295D01*
X52878Y389410D01*
X53188Y389563D01*
X53447Y389793D01*
X53550Y390100D01*
X53447Y390407D01*
X53188Y390637D01*
X52878Y390790D01*
X52465Y390905D01*
X52000Y390943D01*
X51535Y390905D01*
X51122Y390790D01*
X50812Y390637D01*
X50553Y390407D01*
X50450Y390100D01*
G01X80000Y59950D02*
Y57450D01*
G01X79387Y59950D02*
X80613D01*
G01X81667Y57450D02*
Y59950D01*
X82307D01*
X82520Y59825D01*
X82680Y59533D01*
X82733Y59200D01*
X82680Y58867D01*
X82547Y58617D01*
X82307Y58492D01*
X81667D01*
G01X83893Y59533D02*
X84053Y59783D01*
X84240Y59908D01*
X84453Y59950D01*
X84720Y59867D01*
X84907Y59658D01*
X84960Y59408D01*
X84933Y59158D01*
X84827Y58950D01*
X84293Y58533D01*
X84053Y58242D01*
X83893Y57825D01*
X83840Y57450D01*
X84960D01*
G01X86600Y59950D02*
X86387Y59867D01*
X86227Y59658D01*
X86120Y59408D01*
X86040Y59075D01*
X86013Y58700D01*
X86040Y58325D01*
X86120Y57992D01*
X86227Y57742D01*
X86387Y57533D01*
X86600Y57450D01*
X86813Y57533D01*
X86973Y57742D01*
X87080Y57992D01*
X87160Y58325D01*
X87187Y58700D01*
X87160Y59075D01*
X87080Y59408D01*
X86973Y59658D01*
X86813Y59867D01*
X86600Y59950D01*
G01X64550Y56500D02*
X67050D01*
G01X64550Y55887D02*
Y57113D01*
G01X67050Y58167D02*
X64550D01*
Y58807D01*
X64675Y59020D01*
X64967Y59180D01*
X65300Y59233D01*
X65633Y59180D01*
X65883Y59047D01*
X66008Y58807D01*
Y58167D01*
G01X66550Y60313D02*
X66842Y60473D01*
X67008Y60687D01*
X67050Y60927D01*
X67008Y61140D01*
X66800Y61353D01*
X66550Y61487D01*
X66300Y61513D01*
X66008Y61460D01*
X65800Y61273D01*
X65717Y61087D01*
Y60847D01*
G01Y61087D02*
X65592Y61247D01*
X65383Y61380D01*
X65133Y61433D01*
X64883Y61380D01*
X64675Y61247D01*
X64550Y61007D01*
X64592Y60767D01*
X64758Y60527D01*
G01X67050Y63100D02*
X64550D01*
X65050Y62780D01*
G01X67050D02*
Y63420D01*
G01X70063Y62325D02*
X70223Y62117D01*
X70410Y61992D01*
X70650Y61950D01*
X70890Y62033D01*
X71077Y62200D01*
X71210Y62492D01*
X71237Y62825D01*
X71183Y63158D01*
X71050Y63367D01*
X70863Y63533D01*
X70677Y63575D01*
X70490Y63533D01*
X70250Y63367D01*
X70330Y64450D01*
X71050D01*
G01X68208Y107743D02*
X68053Y107513D01*
X67950Y107245D01*
Y106938D01*
X68105Y106593D01*
X68363Y106325D01*
X68673Y106133D01*
X69190Y105980D01*
X69655Y105942D01*
X70120Y106018D01*
X70430Y106133D01*
X70740Y106363D01*
X70947Y106632D01*
X71050Y106900D01*
Y107168D01*
X70947Y107437D01*
X70792Y107667D01*
X70585Y107858D01*
G01X71050Y110000D02*
X70998Y110268D01*
X70843Y110575D01*
X70585Y110767D01*
X70223Y110843D01*
X69862Y110767D01*
X69552Y110537D01*
X69397Y110192D01*
Y109808D01*
X69293Y109578D01*
X69035Y109387D01*
X68673Y109310D01*
X68312Y109425D01*
X68053Y109693D01*
X67950Y110000D01*
X68053Y110307D01*
X68312Y110575D01*
X68673Y110690D01*
X69035Y110613D01*
X69293Y110422D01*
X69397Y110192D01*
Y109808D01*
X69552Y109463D01*
X69862Y109233D01*
X70223Y109157D01*
X70585Y109233D01*
X70843Y109425D01*
X70998Y109732D01*
X71050Y110000D01*
G01X70430Y112257D02*
X70792Y112487D01*
X70998Y112793D01*
X71050Y113138D01*
X70998Y113445D01*
X70740Y113752D01*
X70430Y113943D01*
X70120Y113982D01*
X69758Y113905D01*
X69500Y113637D01*
X69397Y113368D01*
Y113023D01*
G01Y113368D02*
X69242Y113598D01*
X68983Y113790D01*
X68673Y113867D01*
X68363Y113790D01*
X68105Y113598D01*
X67950Y113253D01*
X68002Y112908D01*
X68208Y112563D01*
G01X71470Y100450D02*
Y102950D01*
X70483Y101158D01*
X71817D01*
G01X63450Y117557D02*
X65672D01*
X66137Y117710D01*
X66447Y118017D01*
X66550Y118400D01*
X66447Y118783D01*
X66137Y119090D01*
X65672Y119243D01*
X63450D01*
G01X66550Y121500D02*
X63450D01*
X64070Y121040D01*
G01X66550D02*
Y121960D01*
G01X65930Y123757D02*
X66292Y123987D01*
X66498Y124293D01*
X66550Y124638D01*
X66498Y124945D01*
X66240Y125252D01*
X65930Y125443D01*
X65620Y125482D01*
X65258Y125405D01*
X65000Y125137D01*
X64897Y124868D01*
Y124523D01*
G01Y124868D02*
X64742Y125098D01*
X64483Y125290D01*
X64173Y125367D01*
X63863Y125290D01*
X63605Y125098D01*
X63450Y124753D01*
X63502Y124408D01*
X63708Y124063D01*
G01X69450Y118850D02*
X72550D01*
G01X69450Y117968D02*
Y119732D01*
G01X72550Y121183D02*
X69450D01*
Y122103D01*
X69605Y122410D01*
X69967Y122640D01*
X70380Y122717D01*
X70793Y122640D01*
X71103Y122448D01*
X71258Y122103D01*
Y121183D01*
G01X71930Y124207D02*
X72292Y124437D01*
X72498Y124743D01*
X72550Y125088D01*
X72498Y125395D01*
X72240Y125702D01*
X71930Y125893D01*
X71620Y125932D01*
X71258Y125855D01*
X71000Y125587D01*
X70897Y125318D01*
Y124973D01*
G01Y125318D02*
X70742Y125548D01*
X70483Y125740D01*
X70173Y125817D01*
X69863Y125740D01*
X69605Y125548D01*
X69450Y125203D01*
X69502Y124858D01*
X69708Y124513D01*
G01X72550Y128610D02*
X69450D01*
X71672Y127192D01*
Y129108D01*
G01X71960Y130450D02*
Y133550D01*
X70542Y131328D01*
X72458D01*
G01X68657Y172570D02*
X68887Y172208D01*
X69193Y172002D01*
X69538Y171950D01*
X69845Y172002D01*
X70152Y172260D01*
X70343Y172570D01*
X70382Y172880D01*
X70305Y173242D01*
X70037Y173500D01*
X69768Y173603D01*
X69423D01*
G01X69768D02*
X69998Y173758D01*
X70190Y174017D01*
X70267Y174327D01*
X70190Y174637D01*
X69998Y174895D01*
X69653Y175050D01*
X69308Y174998D01*
X68963Y174792D01*
G01X64950Y187350D02*
X68050D01*
G01X64950Y186468D02*
Y188232D01*
G01X68050Y189683D02*
X64950D01*
Y190603D01*
X65105Y190910D01*
X65467Y191140D01*
X65880Y191217D01*
X66293Y191140D01*
X66603Y190948D01*
X66758Y190603D01*
Y189683D01*
G01X67430Y192707D02*
X67792Y192937D01*
X67998Y193243D01*
X68050Y193588D01*
X67998Y193895D01*
X67740Y194202D01*
X67430Y194393D01*
X67120Y194432D01*
X66758Y194355D01*
X66500Y194087D01*
X66397Y193818D01*
Y193473D01*
G01Y193818D02*
X66242Y194048D01*
X65983Y194240D01*
X65673Y194317D01*
X65363Y194240D01*
X65105Y194048D01*
X64950Y193703D01*
X65002Y193358D01*
X65208Y193013D01*
G01X67430Y195807D02*
X67792Y196037D01*
X67998Y196343D01*
X68050Y196688D01*
X67998Y196995D01*
X67740Y197302D01*
X67430Y197493D01*
X67120Y197532D01*
X66758Y197455D01*
X66500Y197187D01*
X66397Y196918D01*
Y196573D01*
G01Y196918D02*
X66242Y197148D01*
X65983Y197340D01*
X65673Y197417D01*
X65363Y197340D01*
X65105Y197148D01*
X64950Y196803D01*
X65002Y196458D01*
X65208Y196113D01*
G01X69413Y205750D02*
X69573Y205458D01*
X69787Y205292D01*
X70027Y205250D01*
X70240Y205292D01*
X70453Y205500D01*
X70587Y205750D01*
X70613Y206000D01*
X70560Y206292D01*
X70373Y206500D01*
X70187Y206583D01*
X69947D01*
G01X70187D02*
X70347Y206708D01*
X70480Y206917D01*
X70533Y207167D01*
X70480Y207417D01*
X70347Y207625D01*
X70107Y207750D01*
X69867Y207708D01*
X69627Y207542D01*
G01X64708Y213743D02*
X64553Y213513D01*
X64450Y213245D01*
Y212938D01*
X64605Y212593D01*
X64863Y212325D01*
X65173Y212133D01*
X65690Y211980D01*
X66155Y211942D01*
X66620Y212018D01*
X66930Y212133D01*
X67240Y212363D01*
X67447Y212632D01*
X67550Y212900D01*
Y213168D01*
X67447Y213437D01*
X67292Y213667D01*
X67085Y213858D01*
G01X67550Y216000D02*
X67498Y216268D01*
X67343Y216575D01*
X67085Y216767D01*
X66723Y216843D01*
X66362Y216767D01*
X66052Y216537D01*
X65897Y216192D01*
Y215808D01*
X65793Y215578D01*
X65535Y215387D01*
X65173Y215310D01*
X64812Y215425D01*
X64553Y215693D01*
X64450Y216000D01*
X64553Y216307D01*
X64812Y216575D01*
X65173Y216690D01*
X65535Y216613D01*
X65793Y216422D01*
X65897Y216192D01*
Y215808D01*
X66052Y215463D01*
X66362Y215233D01*
X66723Y215157D01*
X67085Y215233D01*
X67343Y215425D01*
X67498Y215732D01*
X67550Y216000D01*
G01X67085Y218257D02*
X67343Y218487D01*
X67498Y218755D01*
X67550Y219100D01*
X67447Y219445D01*
X67240Y219713D01*
X66878Y219905D01*
X66465Y219943D01*
X66052Y219867D01*
X65793Y219675D01*
X65587Y219407D01*
X65535Y219138D01*
X65587Y218870D01*
X65793Y218525D01*
X64450Y218640D01*
Y219675D01*
G01X66208Y239193D02*
X66053Y238963D01*
X65950Y238695D01*
Y238388D01*
X66105Y238043D01*
X66363Y237775D01*
X66673Y237583D01*
X67190Y237430D01*
X67655Y237392D01*
X68120Y237468D01*
X68430Y237583D01*
X68740Y237813D01*
X68947Y238082D01*
X69050Y238350D01*
Y238618D01*
X68947Y238887D01*
X68792Y239117D01*
X68585Y239308D01*
G01X68430Y240607D02*
X68792Y240837D01*
X68998Y241143D01*
X69050Y241488D01*
X68998Y241795D01*
X68740Y242102D01*
X68430Y242293D01*
X68120Y242332D01*
X67758Y242255D01*
X67500Y241987D01*
X67397Y241718D01*
Y241373D01*
G01Y241718D02*
X67242Y241948D01*
X66983Y242140D01*
X66673Y242217D01*
X66363Y242140D01*
X66105Y241948D01*
X65950Y241603D01*
X66002Y241258D01*
X66208Y240913D01*
G01X69050Y244550D02*
X65950D01*
X66570Y244090D01*
G01X69050D02*
Y245010D01*
G01X66467Y246922D02*
X66157Y247152D01*
X66002Y247420D01*
X65950Y247727D01*
X66053Y248110D01*
X66312Y248378D01*
X66622Y248455D01*
X66932Y248417D01*
X67190Y248263D01*
X67707Y247497D01*
X68068Y247152D01*
X68585Y246922D01*
X69050Y246845D01*
Y248455D01*
G01X74000Y247250D02*
X74187Y247292D01*
X74400Y247417D01*
X74533Y247625D01*
X74587Y247917D01*
X74533Y248208D01*
X74373Y248458D01*
X74133Y248583D01*
X73867D01*
X73707Y248667D01*
X73573Y248875D01*
X73520Y249167D01*
X73600Y249458D01*
X73787Y249667D01*
X74000Y249750D01*
X74213Y249667D01*
X74400Y249458D01*
X74480Y249167D01*
X74427Y248875D01*
X74293Y248667D01*
X74133Y248583D01*
X73867D01*
X73627Y248458D01*
X73467Y248208D01*
X73413Y247917D01*
X73467Y247625D01*
X73600Y247417D01*
X73813Y247292D01*
X74000Y247250D01*
G01X66167Y254250D02*
Y256750D01*
X66833D01*
X67047Y256625D01*
X67180Y256458D01*
X67233Y256125D01*
X67180Y255792D01*
X67020Y255583D01*
X66833Y255458D01*
X66167D01*
G01X66833D02*
X67233Y254250D01*
G01X68313Y254750D02*
X68473Y254458D01*
X68687Y254292D01*
X68927Y254250D01*
X69140Y254292D01*
X69353Y254500D01*
X69487Y254750D01*
X69513Y255000D01*
X69460Y255292D01*
X69273Y255500D01*
X69087Y255583D01*
X68847D01*
G01X69087D02*
X69247Y255708D01*
X69380Y255917D01*
X69433Y256167D01*
X69380Y256417D01*
X69247Y256625D01*
X69007Y256750D01*
X68767Y256708D01*
X68527Y256542D01*
G01X71420Y254250D02*
Y256750D01*
X70433Y254958D01*
X71767D01*
G01X73247Y254250D02*
X73300Y254792D01*
X73380Y255250D01*
X73487Y255667D01*
X73620Y256125D01*
X73833Y256750D01*
X72767D01*
G01X72493Y258792D02*
X72680Y259083D01*
X72840Y259250D01*
X73053Y259333D01*
X73240Y259250D01*
X73373Y259083D01*
X73480Y258833D01*
X73507Y258542D01*
X73480Y258292D01*
X73373Y258042D01*
X73213Y257833D01*
X73027Y257750D01*
X72813Y257833D01*
X72627Y258083D01*
X72520Y258458D01*
X72493Y258875D01*
X72547Y259417D01*
X72627Y259708D01*
X72760Y260000D01*
X72947Y260208D01*
X73133Y260250D01*
X73320Y260167D01*
X73453Y259958D01*
G01X71434Y261565D02*
X71594Y261357D01*
X71781Y261232D01*
X72021Y261190D01*
X72261Y261273D01*
X72448Y261440D01*
X72581Y261732D01*
X72608Y262065D01*
X72554Y262398D01*
X72421Y262607D01*
X72234Y262773D01*
X72048Y262815D01*
X71861Y262773D01*
X71621Y262607D01*
X71701Y263690D01*
X72421D01*
G01X71694Y266312D02*
X71854Y266020D01*
X72068Y265854D01*
X72308Y265812D01*
X72521Y265854D01*
X72734Y266062D01*
X72868Y266312D01*
X72894Y266562D01*
X72841Y266854D01*
X72654Y267062D01*
X72468Y267145D01*
X72228D01*
G01X72468D02*
X72628Y267270D01*
X72761Y267479D01*
X72814Y267729D01*
X72761Y267979D01*
X72628Y268187D01*
X72388Y268312D01*
X72148Y268270D01*
X71908Y268104D01*
G01X72133Y286450D02*
Y289550D01*
X73092D01*
X73398Y289395D01*
X73590Y289188D01*
X73667Y288775D01*
X73590Y288362D01*
X73360Y288103D01*
X73092Y287948D01*
X72133D01*
G01X73092D02*
X73667Y286450D01*
G01X75923D02*
X76000Y287122D01*
X76115Y287690D01*
X76268Y288207D01*
X76460Y288775D01*
X76767Y289550D01*
X75233D01*
G01X78257Y287070D02*
X78487Y286708D01*
X78793Y286502D01*
X79138Y286450D01*
X79445Y286502D01*
X79752Y286760D01*
X79943Y287070D01*
X79982Y287380D01*
X79905Y287742D01*
X79637Y288000D01*
X79368Y288103D01*
X79023D01*
G01X79368D02*
X79598Y288258D01*
X79790Y288517D01*
X79867Y288827D01*
X79790Y289137D01*
X79598Y289395D01*
X79253Y289550D01*
X78908Y289498D01*
X78563Y289292D01*
G01X70993Y275333D02*
X71153Y275583D01*
X71340Y275708D01*
X71553Y275750D01*
X71820Y275667D01*
X72007Y275458D01*
X72060Y275208D01*
X72033Y274958D01*
X71927Y274750D01*
X71393Y274333D01*
X71153Y274042D01*
X70993Y273625D01*
X70940Y273250D01*
X72060D01*
G01X73057Y276050D02*
Y273828D01*
X73210Y273363D01*
X73517Y273053D01*
X73900Y272950D01*
X74283Y273053D01*
X74590Y273363D01*
X74743Y273828D01*
Y276050D01*
G01X76272Y275533D02*
X76502Y275843D01*
X76770Y275998D01*
X77077Y276050D01*
X77460Y275947D01*
X77728Y275688D01*
X77805Y275378D01*
X77767Y275068D01*
X77613Y274810D01*
X76847Y274293D01*
X76502Y273932D01*
X76272Y273415D01*
X76195Y272950D01*
X77805D01*
G01X80100D02*
X80368Y273002D01*
X80675Y273157D01*
X80867Y273415D01*
X80943Y273777D01*
X80867Y274138D01*
X80637Y274448D01*
X80292Y274603D01*
X79908D01*
X79678Y274707D01*
X79487Y274965D01*
X79410Y275327D01*
X79525Y275688D01*
X79793Y275947D01*
X80100Y276050D01*
X80407Y275947D01*
X80675Y275688D01*
X80790Y275327D01*
X80713Y274965D01*
X80522Y274707D01*
X80292Y274603D01*
X79908D01*
X79563Y274448D01*
X79333Y274138D01*
X79257Y273777D01*
X79333Y273415D01*
X79525Y273157D01*
X79832Y273002D01*
X80100Y272950D01*
G01X78950Y296900D02*
X82050D01*
G01X78950Y296018D02*
Y297782D01*
G01X82050Y299233D02*
X78950D01*
Y300153D01*
X79105Y300460D01*
X79467Y300690D01*
X79880Y300767D01*
X80293Y300690D01*
X80603Y300498D01*
X80758Y300153D01*
Y299233D01*
G01Y302372D02*
X80397Y302640D01*
X80190Y302870D01*
X80087Y303177D01*
X80190Y303445D01*
X80397Y303637D01*
X80707Y303790D01*
X81068Y303828D01*
X81378Y303790D01*
X81688Y303637D01*
X81947Y303407D01*
X82050Y303138D01*
X81947Y302832D01*
X81637Y302563D01*
X81172Y302410D01*
X80655Y302372D01*
X79983Y302448D01*
X79622Y302563D01*
X79260Y302755D01*
X79002Y303023D01*
X78950Y303292D01*
X79053Y303560D01*
X79312Y303752D01*
G01X64583Y313950D02*
Y317050D01*
X65542D01*
X65848Y316895D01*
X66040Y316688D01*
X66117Y316275D01*
X66040Y315862D01*
X65810Y315603D01*
X65542Y315448D01*
X64583D01*
G01X65542D02*
X66117Y313950D01*
G01X68910D02*
Y317050D01*
X67492Y314828D01*
X69408D01*
G01X71473Y313950D02*
X71550Y314622D01*
X71665Y315190D01*
X71818Y315707D01*
X72010Y316275D01*
X72317Y317050D01*
X70783D01*
G01X74650Y313950D02*
Y317050D01*
X74190Y316430D01*
G01Y313950D02*
X75110D01*
G01X64583Y309450D02*
Y312550D01*
X65542D01*
X65848Y312395D01*
X66040Y312188D01*
X66117Y311775D01*
X66040Y311362D01*
X65810Y311103D01*
X65542Y310948D01*
X64583D01*
G01X65542D02*
X66117Y309450D01*
G01X68910D02*
Y312550D01*
X67492Y310328D01*
X69408D01*
G01X71473Y309450D02*
X71550Y310122D01*
X71665Y310690D01*
X71818Y311207D01*
X72010Y311775D01*
X72317Y312550D01*
X70783D01*
G01X73922Y312033D02*
X74152Y312343D01*
X74420Y312498D01*
X74727Y312550D01*
X75110Y312447D01*
X75378Y312188D01*
X75455Y311878D01*
X75417Y311568D01*
X75263Y311310D01*
X74497Y310793D01*
X74152Y310432D01*
X73922Y309915D01*
X73845Y309450D01*
X75455D01*
G01X79913Y336250D02*
X80073Y335958D01*
X80287Y335792D01*
X80527Y335750D01*
X80740Y335792D01*
X80953Y336000D01*
X81087Y336250D01*
X81113Y336500D01*
X81060Y336792D01*
X80873Y337000D01*
X80687Y337083D01*
X80447D01*
G01X80687D02*
X80847Y337208D01*
X80980Y337417D01*
X81033Y337667D01*
X80980Y337917D01*
X80847Y338125D01*
X80607Y338250D01*
X80367Y338208D01*
X80127Y338042D01*
G01X64544Y351099D02*
X64731Y351390D01*
X64891Y351557D01*
X65104Y351640D01*
X65291Y351557D01*
X65424Y351390D01*
X65531Y351140D01*
X65558Y350849D01*
X65531Y350599D01*
X65424Y350349D01*
X65264Y350140D01*
X65078Y350057D01*
X64864Y350140D01*
X64678Y350390D01*
X64571Y350765D01*
X64544Y351182D01*
X64598Y351724D01*
X64678Y352015D01*
X64811Y352307D01*
X64998Y352515D01*
X65184Y352557D01*
X65371Y352474D01*
X65504Y352265D01*
G01X80320Y354750D02*
Y357250D01*
X79333Y355458D01*
X80667D01*
G01X68000Y360450D02*
Y363550D01*
X67540Y362930D01*
G01Y360450D02*
X68460D01*
G01X72693Y363292D02*
X72463Y363447D01*
X72195Y363550D01*
X71888D01*
X71543Y363395D01*
X71275Y363137D01*
X71083Y362827D01*
X70930Y362310D01*
X70892Y361845D01*
X70968Y361380D01*
X71083Y361070D01*
X71313Y360760D01*
X71582Y360553D01*
X71850Y360450D01*
X72118D01*
X72387Y360553D01*
X72617Y360708D01*
X72808Y360915D01*
G01X74183Y360450D02*
Y363550D01*
X75142D01*
X75448Y363395D01*
X75640Y363188D01*
X75717Y362775D01*
X75640Y362362D01*
X75410Y362103D01*
X75142Y361948D01*
X74183D01*
G01X75142D02*
X75717Y360450D01*
G01X78050D02*
Y363550D01*
X77590Y362930D01*
G01Y360450D02*
X78510D01*
G01X80422Y363033D02*
X80652Y363343D01*
X80920Y363498D01*
X81227Y363550D01*
X81610Y363447D01*
X81878Y363188D01*
X81955Y362878D01*
X81917Y362568D01*
X81763Y362310D01*
X80997Y361793D01*
X80652Y361432D01*
X80422Y360915D01*
X80345Y360450D01*
X81955D01*
G01X76757Y416770D02*
X76987Y416408D01*
X77293Y416202D01*
X77638Y416150D01*
X77945Y416202D01*
X78252Y416460D01*
X78443Y416770D01*
X78482Y417080D01*
X78405Y417442D01*
X78137Y417700D01*
X77868Y417803D01*
X77523D01*
G01X77868D02*
X78098Y417958D01*
X78290Y418217D01*
X78367Y418527D01*
X78290Y418837D01*
X78098Y419095D01*
X77753Y419250D01*
X77408Y419198D01*
X77063Y418992D01*
G01X93787Y59770D02*
X94017Y59408D01*
X94323Y59202D01*
X94668Y59150D01*
X94975Y59202D01*
X95282Y59460D01*
X95473Y59770D01*
X95512Y60080D01*
X95435Y60442D01*
X95167Y60700D01*
X94898Y60803D01*
X94553D01*
G01X94898D02*
X95128Y60958D01*
X95320Y61217D01*
X95397Y61527D01*
X95320Y61837D01*
X95128Y62095D01*
X94783Y62250D01*
X94438Y62198D01*
X94093Y61992D01*
G01X86650Y67450D02*
X86837Y67492D01*
X87050Y67617D01*
X87183Y67825D01*
X87237Y68117D01*
X87183Y68408D01*
X87023Y68658D01*
X86783Y68783D01*
X86517D01*
X86357Y68867D01*
X86223Y69075D01*
X86170Y69367D01*
X86250Y69658D01*
X86437Y69867D01*
X86650Y69950D01*
X86863Y69867D01*
X87050Y69658D01*
X87130Y69367D01*
X87077Y69075D01*
X86943Y68867D01*
X86783Y68783D01*
X86517D01*
X86277Y68658D01*
X86117Y68408D01*
X86063Y68117D01*
X86117Y67825D01*
X86250Y67617D01*
X86463Y67492D01*
X86650Y67450D01*
G01X86450Y86557D02*
X88672D01*
X89137Y86710D01*
X89447Y87017D01*
X89550Y87400D01*
X89447Y87783D01*
X89137Y88090D01*
X88672Y88243D01*
X86450D01*
G01X89550Y90500D02*
X86450D01*
X87070Y90040D01*
G01X89550D02*
Y90960D01*
G01X89188Y92948D02*
X89447Y93217D01*
X89550Y93523D01*
X89447Y93830D01*
X89137Y94098D01*
X88672Y94290D01*
X88207Y94367D01*
X87638D01*
X87173Y94290D01*
X86760Y94098D01*
X86553Y93868D01*
X86450Y93600D01*
X86553Y93293D01*
X86760Y93063D01*
X87070Y92910D01*
X87483Y92833D01*
X87845Y92910D01*
X88207Y93102D01*
X88413Y93332D01*
X88465Y93600D01*
X88362Y93907D01*
X88103Y94137D01*
X87638Y94367D01*
G01X85583Y111450D02*
Y114550D01*
X86542D01*
X86848Y114395D01*
X87040Y114188D01*
X87117Y113775D01*
X87040Y113362D01*
X86810Y113103D01*
X86542Y112948D01*
X85583D01*
G01X86542D02*
X87117Y111450D01*
G01X88607Y112070D02*
X88837Y111708D01*
X89143Y111502D01*
X89488Y111450D01*
X89795Y111502D01*
X90102Y111760D01*
X90293Y112070D01*
X90332Y112380D01*
X90255Y112742D01*
X89987Y113000D01*
X89718Y113103D01*
X89373D01*
G01X89718D02*
X89948Y113258D01*
X90140Y113517D01*
X90217Y113827D01*
X90140Y114137D01*
X89948Y114395D01*
X89603Y114550D01*
X89258Y114498D01*
X88913Y114292D01*
G01X92473Y111450D02*
X92550Y112122D01*
X92665Y112690D01*
X92818Y113207D01*
X93010Y113775D01*
X93317Y114550D01*
X91783D01*
G01X94807Y112070D02*
X95037Y111708D01*
X95343Y111502D01*
X95688Y111450D01*
X95995Y111502D01*
X96302Y111760D01*
X96493Y112070D01*
X96532Y112380D01*
X96455Y112742D01*
X96187Y113000D01*
X95918Y113103D01*
X95573D01*
G01X95918D02*
X96148Y113258D01*
X96340Y113517D01*
X96417Y113827D01*
X96340Y114137D01*
X96148Y114395D01*
X95803Y114550D01*
X95458Y114498D01*
X95113Y114292D01*
G01X85583Y106450D02*
Y109550D01*
X86542D01*
X86848Y109395D01*
X87040Y109188D01*
X87117Y108775D01*
X87040Y108362D01*
X86810Y108103D01*
X86542Y107948D01*
X85583D01*
G01X86542D02*
X87117Y106450D01*
G01X88722Y109033D02*
X88952Y109343D01*
X89220Y109498D01*
X89527Y109550D01*
X89910Y109447D01*
X90178Y109188D01*
X90255Y108878D01*
X90217Y108568D01*
X90063Y108310D01*
X89297Y107793D01*
X88952Y107432D01*
X88722Y106915D01*
X88645Y106450D01*
X90255D01*
G01X92473D02*
X92550Y107122D01*
X92665Y107690D01*
X92818Y108207D01*
X93010Y108775D01*
X93317Y109550D01*
X91783D01*
G01X94807Y107070D02*
X95037Y106708D01*
X95343Y106502D01*
X95688Y106450D01*
X95995Y106502D01*
X96302Y106760D01*
X96493Y107070D01*
X96532Y107380D01*
X96455Y107742D01*
X96187Y108000D01*
X95918Y108103D01*
X95573D01*
G01X95918D02*
X96148Y108258D01*
X96340Y108517D01*
X96417Y108827D01*
X96340Y109137D01*
X96148Y109395D01*
X95803Y109550D01*
X95458Y109498D01*
X95113Y109292D01*
G01X88083Y100950D02*
Y104050D01*
X89042D01*
X89348Y103895D01*
X89540Y103688D01*
X89617Y103275D01*
X89540Y102862D01*
X89310Y102603D01*
X89042Y102448D01*
X88083D01*
G01X89042D02*
X89617Y100950D01*
G01X91107Y101570D02*
X91337Y101208D01*
X91643Y101002D01*
X91988Y100950D01*
X92295Y101002D01*
X92602Y101260D01*
X92793Y101570D01*
X92832Y101880D01*
X92755Y102242D01*
X92487Y102500D01*
X92218Y102603D01*
X91873D01*
G01X92218D02*
X92448Y102758D01*
X92640Y103017D01*
X92717Y103327D01*
X92640Y103637D01*
X92448Y103895D01*
X92103Y104050D01*
X91758Y103998D01*
X91413Y103792D01*
G01X95050Y100950D02*
X95318Y101002D01*
X95625Y101157D01*
X95817Y101415D01*
X95893Y101777D01*
X95817Y102138D01*
X95587Y102448D01*
X95242Y102603D01*
X94858D01*
X94628Y102707D01*
X94437Y102965D01*
X94360Y103327D01*
X94475Y103688D01*
X94743Y103947D01*
X95050Y104050D01*
X95357Y103947D01*
X95625Y103688D01*
X95740Y103327D01*
X95663Y102965D01*
X95472Y102707D01*
X95242Y102603D01*
X94858D01*
X94513Y102448D01*
X94283Y102138D01*
X94207Y101777D01*
X94283Y101415D01*
X94475Y101157D01*
X94782Y101002D01*
X95050Y100950D01*
G01X98150D02*
X98418Y101002D01*
X98725Y101157D01*
X98917Y101415D01*
X98993Y101777D01*
X98917Y102138D01*
X98687Y102448D01*
X98342Y102603D01*
X97958D01*
X97728Y102707D01*
X97537Y102965D01*
X97460Y103327D01*
X97575Y103688D01*
X97843Y103947D01*
X98150Y104050D01*
X98457Y103947D01*
X98725Y103688D01*
X98840Y103327D01*
X98763Y102965D01*
X98572Y102707D01*
X98342Y102603D01*
X97958D01*
X97613Y102448D01*
X97383Y102138D01*
X97307Y101777D01*
X97383Y101415D01*
X97575Y101157D01*
X97882Y101002D01*
X98150Y100950D01*
G01X85583Y115450D02*
Y118550D01*
X86542D01*
X86848Y118395D01*
X87040Y118188D01*
X87117Y117775D01*
X87040Y117362D01*
X86810Y117103D01*
X86542Y116948D01*
X85583D01*
G01X86542D02*
X87117Y115450D01*
G01X88607Y116070D02*
X88837Y115708D01*
X89143Y115502D01*
X89488Y115450D01*
X89795Y115502D01*
X90102Y115760D01*
X90293Y116070D01*
X90332Y116380D01*
X90255Y116742D01*
X89987Y117000D01*
X89718Y117103D01*
X89373D01*
G01X89718D02*
X89948Y117258D01*
X90140Y117517D01*
X90217Y117827D01*
X90140Y118137D01*
X89948Y118395D01*
X89603Y118550D01*
X89258Y118498D01*
X88913Y118292D01*
G01X91898Y115812D02*
X92167Y115553D01*
X92473Y115450D01*
X92780Y115553D01*
X93048Y115863D01*
X93240Y116328D01*
X93317Y116793D01*
Y117362D01*
X93240Y117827D01*
X93048Y118240D01*
X92818Y118447D01*
X92550Y118550D01*
X92243Y118447D01*
X92013Y118240D01*
X91860Y117930D01*
X91783Y117517D01*
X91860Y117155D01*
X92052Y116793D01*
X92282Y116587D01*
X92550Y116535D01*
X92857Y116638D01*
X93087Y116897D01*
X93317Y117362D01*
G01X95650Y118550D02*
X95343Y118447D01*
X95113Y118188D01*
X94960Y117878D01*
X94845Y117465D01*
X94807Y117000D01*
X94845Y116535D01*
X94960Y116122D01*
X95113Y115812D01*
X95343Y115553D01*
X95650Y115450D01*
X95957Y115553D01*
X96187Y115812D01*
X96340Y116122D01*
X96455Y116535D01*
X96493Y117000D01*
X96455Y117465D01*
X96340Y117878D01*
X96187Y118188D01*
X95957Y118447D01*
X95650Y118550D01*
G01X85583Y120950D02*
Y124050D01*
X86542D01*
X86848Y123895D01*
X87040Y123688D01*
X87117Y123275D01*
X87040Y122862D01*
X86810Y122603D01*
X86542Y122448D01*
X85583D01*
G01X86542D02*
X87117Y120950D01*
G01X88722Y123533D02*
X88952Y123843D01*
X89220Y123998D01*
X89527Y124050D01*
X89910Y123947D01*
X90178Y123688D01*
X90255Y123378D01*
X90217Y123068D01*
X90063Y122810D01*
X89297Y122293D01*
X88952Y121932D01*
X88722Y121415D01*
X88645Y120950D01*
X90255D01*
G01X92473D02*
X92550Y121622D01*
X92665Y122190D01*
X92818Y122707D01*
X93010Y123275D01*
X93317Y124050D01*
X91783D01*
G01X96110Y120950D02*
Y124050D01*
X94692Y121828D01*
X96608D01*
G01X85083Y125950D02*
Y129050D01*
X86042D01*
X86348Y128895D01*
X86540Y128688D01*
X86617Y128275D01*
X86540Y127862D01*
X86310Y127603D01*
X86042Y127448D01*
X85083D01*
G01X86042D02*
X86617Y125950D01*
G01X88107Y126570D02*
X88337Y126208D01*
X88643Y126002D01*
X88988Y125950D01*
X89295Y126002D01*
X89602Y126260D01*
X89793Y126570D01*
X89832Y126880D01*
X89755Y127242D01*
X89487Y127500D01*
X89218Y127603D01*
X88873D01*
G01X89218D02*
X89448Y127758D01*
X89640Y128017D01*
X89717Y128327D01*
X89640Y128637D01*
X89448Y128895D01*
X89103Y129050D01*
X88758Y128998D01*
X88413Y128792D01*
G01X92050Y125950D02*
X92318Y126002D01*
X92625Y126157D01*
X92817Y126415D01*
X92893Y126777D01*
X92817Y127138D01*
X92587Y127448D01*
X92242Y127603D01*
X91858D01*
X91628Y127707D01*
X91437Y127965D01*
X91360Y128327D01*
X91475Y128688D01*
X91743Y128947D01*
X92050Y129050D01*
X92357Y128947D01*
X92625Y128688D01*
X92740Y128327D01*
X92663Y127965D01*
X92472Y127707D01*
X92242Y127603D01*
X91858D01*
X91513Y127448D01*
X91283Y127138D01*
X91207Y126777D01*
X91283Y126415D01*
X91475Y126157D01*
X91782Y126002D01*
X92050Y125950D01*
G01X94498Y126312D02*
X94767Y126053D01*
X95073Y125950D01*
X95380Y126053D01*
X95648Y126363D01*
X95840Y126828D01*
X95917Y127293D01*
Y127862D01*
X95840Y128327D01*
X95648Y128740D01*
X95418Y128947D01*
X95150Y129050D01*
X94843Y128947D01*
X94613Y128740D01*
X94460Y128430D01*
X94383Y128017D01*
X94460Y127655D01*
X94652Y127293D01*
X94882Y127087D01*
X95150Y127035D01*
X95457Y127138D01*
X95687Y127397D01*
X95917Y127862D01*
G01X87272Y140533D02*
X87502Y140843D01*
X87770Y140998D01*
X88077Y141050D01*
X88460Y140947D01*
X88728Y140688D01*
X88805Y140378D01*
X88767Y140068D01*
X88613Y139810D01*
X87847Y139293D01*
X87502Y138932D01*
X87272Y138415D01*
X87195Y137950D01*
X88805D01*
G01X87183Y158070D02*
X87375Y157760D01*
X87605Y157553D01*
X87873Y157450D01*
X88180Y157553D01*
X88410Y157760D01*
X88640Y158070D01*
X88717Y158483D01*
Y160550D01*
G01X90398Y157812D02*
X90667Y157553D01*
X90973Y157450D01*
X91280Y157553D01*
X91548Y157863D01*
X91740Y158328D01*
X91817Y158793D01*
Y159362D01*
X91740Y159827D01*
X91548Y160240D01*
X91318Y160447D01*
X91050Y160550D01*
X90743Y160447D01*
X90513Y160240D01*
X90360Y159930D01*
X90283Y159517D01*
X90360Y159155D01*
X90552Y158793D01*
X90782Y158587D01*
X91050Y158535D01*
X91357Y158638D01*
X91587Y158897D01*
X91817Y159362D01*
G01X85083Y178450D02*
Y181550D01*
X86042D01*
X86348Y181395D01*
X86540Y181188D01*
X86617Y180775D01*
X86540Y180362D01*
X86310Y180103D01*
X86042Y179948D01*
X85083D01*
G01X86042D02*
X86617Y178450D01*
G01X89410D02*
Y181550D01*
X87992Y179328D01*
X89908D01*
G01X92050Y181550D02*
X91743Y181447D01*
X91513Y181188D01*
X91360Y180878D01*
X91245Y180465D01*
X91207Y180000D01*
X91245Y179535D01*
X91360Y179122D01*
X91513Y178812D01*
X91743Y178553D01*
X92050Y178450D01*
X92357Y178553D01*
X92587Y178812D01*
X92740Y179122D01*
X92855Y179535D01*
X92893Y180000D01*
X92855Y180465D01*
X92740Y180878D01*
X92587Y181188D01*
X92357Y181447D01*
X92050Y181550D01*
G01X95150D02*
X94843Y181447D01*
X94613Y181188D01*
X94460Y180878D01*
X94345Y180465D01*
X94307Y180000D01*
X94345Y179535D01*
X94460Y179122D01*
X94613Y178812D01*
X94843Y178553D01*
X95150Y178450D01*
X95457Y178553D01*
X95687Y178812D01*
X95840Y179122D01*
X95955Y179535D01*
X95993Y180000D01*
X95955Y180465D01*
X95840Y180878D01*
X95687Y181188D01*
X95457Y181447D01*
X95150Y181550D01*
G01X85083Y172950D02*
Y176050D01*
X86042D01*
X86348Y175895D01*
X86540Y175688D01*
X86617Y175275D01*
X86540Y174862D01*
X86310Y174603D01*
X86042Y174448D01*
X85083D01*
G01X86042D02*
X86617Y172950D01*
G01X88107Y173570D02*
X88337Y173208D01*
X88643Y173002D01*
X88988Y172950D01*
X89295Y173002D01*
X89602Y173260D01*
X89793Y173570D01*
X89832Y173880D01*
X89755Y174242D01*
X89487Y174500D01*
X89218Y174603D01*
X88873D01*
G01X89218D02*
X89448Y174758D01*
X89640Y175017D01*
X89717Y175327D01*
X89640Y175637D01*
X89448Y175895D01*
X89103Y176050D01*
X88758Y175998D01*
X88413Y175792D01*
G01X91398Y173312D02*
X91667Y173053D01*
X91973Y172950D01*
X92280Y173053D01*
X92548Y173363D01*
X92740Y173828D01*
X92817Y174293D01*
Y174862D01*
X92740Y175327D01*
X92548Y175740D01*
X92318Y175947D01*
X92050Y176050D01*
X91743Y175947D01*
X91513Y175740D01*
X91360Y175430D01*
X91283Y175017D01*
X91360Y174655D01*
X91552Y174293D01*
X91782Y174087D01*
X92050Y174035D01*
X92357Y174138D01*
X92587Y174397D01*
X92817Y174862D01*
G01X95610Y172950D02*
Y176050D01*
X94192Y173828D01*
X96108D01*
G01X87000Y167950D02*
Y171050D01*
X86540Y170430D01*
G01Y167950D02*
X87460D01*
G01X85083Y192450D02*
Y195550D01*
X86042D01*
X86348Y195395D01*
X86540Y195188D01*
X86617Y194775D01*
X86540Y194362D01*
X86310Y194103D01*
X86042Y193948D01*
X85083D01*
G01X86042D02*
X86617Y192450D01*
G01X88107Y193070D02*
X88337Y192708D01*
X88643Y192502D01*
X88988Y192450D01*
X89295Y192502D01*
X89602Y192760D01*
X89793Y193070D01*
X89832Y193380D01*
X89755Y193742D01*
X89487Y194000D01*
X89218Y194103D01*
X88873D01*
G01X89218D02*
X89448Y194258D01*
X89640Y194517D01*
X89717Y194827D01*
X89640Y195137D01*
X89448Y195395D01*
X89103Y195550D01*
X88758Y195498D01*
X88413Y195292D01*
G01X91398Y192812D02*
X91667Y192553D01*
X91973Y192450D01*
X92280Y192553D01*
X92548Y192863D01*
X92740Y193328D01*
X92817Y193793D01*
Y194362D01*
X92740Y194827D01*
X92548Y195240D01*
X92318Y195447D01*
X92050Y195550D01*
X91743Y195447D01*
X91513Y195240D01*
X91360Y194930D01*
X91283Y194517D01*
X91360Y194155D01*
X91552Y193793D01*
X91782Y193587D01*
X92050Y193535D01*
X92357Y193638D01*
X92587Y193897D01*
X92817Y194362D01*
G01X94307Y192915D02*
X94537Y192657D01*
X94805Y192502D01*
X95150Y192450D01*
X95495Y192553D01*
X95763Y192760D01*
X95955Y193122D01*
X95993Y193535D01*
X95917Y193948D01*
X95725Y194207D01*
X95457Y194413D01*
X95188Y194465D01*
X94920Y194413D01*
X94575Y194207D01*
X94690Y195550D01*
X95725D01*
G01X82583Y196950D02*
Y200050D01*
X83542D01*
X83848Y199895D01*
X84040Y199688D01*
X84117Y199275D01*
X84040Y198862D01*
X83810Y198603D01*
X83542Y198448D01*
X82583D01*
G01X83542D02*
X84117Y196950D01*
G01X86910D02*
Y200050D01*
X85492Y197828D01*
X87408D01*
G01X89550Y200050D02*
X89243Y199947D01*
X89013Y199688D01*
X88860Y199378D01*
X88745Y198965D01*
X88707Y198500D01*
X88745Y198035D01*
X88860Y197622D01*
X89013Y197312D01*
X89243Y197053D01*
X89550Y196950D01*
X89857Y197053D01*
X90087Y197312D01*
X90240Y197622D01*
X90355Y198035D01*
X90393Y198500D01*
X90355Y198965D01*
X90240Y199378D01*
X90087Y199688D01*
X89857Y199947D01*
X89550Y200050D01*
G01X92650Y196950D02*
Y200050D01*
X92190Y199430D01*
G01Y196950D02*
X93110D01*
G01X85083Y186950D02*
Y190050D01*
X86042D01*
X86348Y189895D01*
X86540Y189688D01*
X86617Y189275D01*
X86540Y188862D01*
X86310Y188603D01*
X86042Y188448D01*
X85083D01*
G01X86042D02*
X86617Y186950D01*
G01X88107Y187570D02*
X88337Y187208D01*
X88643Y187002D01*
X88988Y186950D01*
X89295Y187002D01*
X89602Y187260D01*
X89793Y187570D01*
X89832Y187880D01*
X89755Y188242D01*
X89487Y188500D01*
X89218Y188603D01*
X88873D01*
G01X89218D02*
X89448Y188758D01*
X89640Y189017D01*
X89717Y189327D01*
X89640Y189637D01*
X89448Y189895D01*
X89103Y190050D01*
X88758Y189998D01*
X88413Y189792D01*
G01X91398Y187312D02*
X91667Y187053D01*
X91973Y186950D01*
X92280Y187053D01*
X92548Y187363D01*
X92740Y187828D01*
X92817Y188293D01*
Y188862D01*
X92740Y189327D01*
X92548Y189740D01*
X92318Y189947D01*
X92050Y190050D01*
X91743Y189947D01*
X91513Y189740D01*
X91360Y189430D01*
X91283Y189017D01*
X91360Y188655D01*
X91552Y188293D01*
X91782Y188087D01*
X92050Y188035D01*
X92357Y188138D01*
X92587Y188397D01*
X92817Y188862D01*
G01X94422Y188242D02*
X94690Y188603D01*
X94920Y188810D01*
X95227Y188913D01*
X95495Y188810D01*
X95687Y188603D01*
X95840Y188293D01*
X95878Y187932D01*
X95840Y187622D01*
X95687Y187312D01*
X95457Y187053D01*
X95188Y186950D01*
X94882Y187053D01*
X94613Y187363D01*
X94460Y187828D01*
X94422Y188345D01*
X94498Y189017D01*
X94613Y189378D01*
X94805Y189740D01*
X95073Y189998D01*
X95342Y190050D01*
X95610Y189947D01*
X95802Y189688D01*
G01X85083Y182450D02*
Y185550D01*
X86042D01*
X86348Y185395D01*
X86540Y185188D01*
X86617Y184775D01*
X86540Y184362D01*
X86310Y184103D01*
X86042Y183948D01*
X85083D01*
G01X86042D02*
X86617Y182450D01*
G01X89410D02*
Y185550D01*
X87992Y183328D01*
X89908D01*
G01X91322Y185033D02*
X91552Y185343D01*
X91820Y185498D01*
X92127Y185550D01*
X92510Y185447D01*
X92778Y185188D01*
X92855Y184878D01*
X92817Y184568D01*
X92663Y184310D01*
X91897Y183793D01*
X91552Y183432D01*
X91322Y182915D01*
X91245Y182450D01*
X92855D01*
G01X95610D02*
Y185550D01*
X94192Y183328D01*
X96108D01*
G01X89993Y217833D02*
X90153Y218083D01*
X90340Y218208D01*
X90553Y218250D01*
X90820Y218167D01*
X91007Y217958D01*
X91060Y217708D01*
X91033Y217458D01*
X90927Y217250D01*
X90393Y216833D01*
X90153Y216542D01*
X89993Y216125D01*
X89940Y215750D01*
X91060D01*
G01X92000Y204450D02*
Y206950D01*
X91680Y206450D01*
G01Y204450D02*
X92320D01*
G01X90633Y209570D02*
X90825Y209260D01*
X91055Y209053D01*
X91323Y208950D01*
X91630Y209053D01*
X91860Y209260D01*
X92090Y209570D01*
X92167Y209983D01*
Y212050D01*
G01X94500Y208950D02*
Y212050D01*
X94040Y211430D01*
G01Y208950D02*
X94960D01*
G01X97600D02*
X97868Y209002D01*
X98175Y209157D01*
X98367Y209415D01*
X98443Y209777D01*
X98367Y210138D01*
X98137Y210448D01*
X97792Y210603D01*
X97408D01*
X97178Y210707D01*
X96987Y210965D01*
X96910Y211327D01*
X97025Y211688D01*
X97293Y211947D01*
X97600Y212050D01*
X97907Y211947D01*
X98175Y211688D01*
X98290Y211327D01*
X98213Y210965D01*
X98022Y210707D01*
X97792Y210603D01*
X97408D01*
X97063Y210448D01*
X96833Y210138D01*
X96757Y209777D01*
X96833Y209415D01*
X97025Y209157D01*
X97332Y209002D01*
X97600Y208950D01*
G01X90950Y230057D02*
X93172D01*
X93637Y230210D01*
X93947Y230517D01*
X94050Y230900D01*
X93947Y231283D01*
X93637Y231590D01*
X93172Y231743D01*
X90950D01*
G01X93430Y233157D02*
X93792Y233387D01*
X93998Y233693D01*
X94050Y234038D01*
X93998Y234345D01*
X93740Y234652D01*
X93430Y234843D01*
X93120Y234882D01*
X92758Y234805D01*
X92500Y234537D01*
X92397Y234268D01*
Y233923D01*
G01Y234268D02*
X92242Y234498D01*
X91983Y234690D01*
X91673Y234767D01*
X91363Y234690D01*
X91105Y234498D01*
X90950Y234153D01*
X91002Y233808D01*
X91208Y233463D01*
G01X91467Y236372D02*
X91157Y236602D01*
X91002Y236870D01*
X90950Y237177D01*
X91053Y237560D01*
X91312Y237828D01*
X91622Y237905D01*
X91932Y237867D01*
X92190Y237713D01*
X92707Y236947D01*
X93068Y236602D01*
X93585Y236372D01*
X94050Y236295D01*
Y237905D01*
G01X90820Y220950D02*
Y223450D01*
X89833Y221658D01*
X91167D01*
G01X97050Y244083D02*
X93950D01*
Y245042D01*
X94105Y245348D01*
X94312Y245540D01*
X94725Y245617D01*
X95138Y245540D01*
X95397Y245310D01*
X95552Y245042D01*
Y244083D01*
G01Y245042D02*
X97050Y245617D01*
G01X96430Y247107D02*
X96792Y247337D01*
X96998Y247643D01*
X97050Y247988D01*
X96998Y248295D01*
X96740Y248602D01*
X96430Y248793D01*
X96120Y248832D01*
X95758Y248755D01*
X95500Y248487D01*
X95397Y248218D01*
Y247873D01*
G01Y248218D02*
X95242Y248448D01*
X94983Y248640D01*
X94673Y248717D01*
X94363Y248640D01*
X94105Y248448D01*
X93950Y248103D01*
X94002Y247758D01*
X94208Y247413D01*
G01X96585Y250207D02*
X96843Y250437D01*
X96998Y250705D01*
X97050Y251050D01*
X96947Y251395D01*
X96740Y251663D01*
X96378Y251855D01*
X95965Y251893D01*
X95552Y251817D01*
X95293Y251625D01*
X95087Y251357D01*
X95035Y251088D01*
X95087Y250820D01*
X95293Y250475D01*
X93950Y250590D01*
Y251625D01*
G01Y254150D02*
X94053Y253843D01*
X94312Y253613D01*
X94622Y253460D01*
X95035Y253345D01*
X95500Y253307D01*
X95965Y253345D01*
X96378Y253460D01*
X96688Y253613D01*
X96947Y253843D01*
X97050Y254150D01*
X96947Y254457D01*
X96688Y254687D01*
X96378Y254840D01*
X95965Y254955D01*
X95500Y254993D01*
X95035Y254955D01*
X94622Y254840D01*
X94312Y254687D01*
X94053Y254457D01*
X93950Y254150D01*
G01X90413Y244625D02*
X90573Y244417D01*
X90760Y244292D01*
X91000Y244250D01*
X91240Y244333D01*
X91427Y244500D01*
X91560Y244792D01*
X91587Y245125D01*
X91533Y245458D01*
X91400Y245667D01*
X91213Y245833D01*
X91027Y245875D01*
X90840Y245833D01*
X90600Y245667D01*
X90680Y246750D01*
X91400D01*
G01X86500Y259250D02*
X86687Y259292D01*
X86900Y259417D01*
X87033Y259625D01*
X87087Y259917D01*
X87033Y260208D01*
X86873Y260458D01*
X86633Y260583D01*
X86367D01*
X86207Y260667D01*
X86073Y260875D01*
X86020Y261167D01*
X86100Y261458D01*
X86287Y261667D01*
X86500Y261750D01*
X86713Y261667D01*
X86900Y261458D01*
X86980Y261167D01*
X86927Y260875D01*
X86793Y260667D01*
X86633Y260583D01*
X86367D01*
X86127Y260458D01*
X85967Y260208D01*
X85913Y259917D01*
X85967Y259625D01*
X86100Y259417D01*
X86313Y259292D01*
X86500Y259250D01*
G01X86550Y278133D02*
X83450D01*
Y279092D01*
X83605Y279398D01*
X83812Y279590D01*
X84225Y279667D01*
X84638Y279590D01*
X84897Y279360D01*
X85052Y279092D01*
Y278133D01*
G01Y279092D02*
X86550Y279667D01*
G01Y281923D02*
X85878Y282000D01*
X85310Y282115D01*
X84793Y282268D01*
X84225Y282460D01*
X83450Y282767D01*
Y281233D01*
G01X86550Y285100D02*
X83450D01*
X84070Y284640D01*
G01X86550D02*
Y285560D01*
G01X81313Y318750D02*
X81473Y318458D01*
X81687Y318292D01*
X81927Y318250D01*
X82140Y318292D01*
X82353Y318500D01*
X82487Y318750D01*
X82513Y319000D01*
X82460Y319292D01*
X82273Y319500D01*
X82087Y319583D01*
X81847D01*
G01X82087D02*
X82247Y319708D01*
X82380Y319917D01*
X82433Y320167D01*
X82380Y320417D01*
X82247Y320625D01*
X82007Y320750D01*
X81767Y320708D01*
X81527Y320542D01*
G01X83593Y320333D02*
X83753Y320583D01*
X83940Y320708D01*
X84153Y320750D01*
X84420Y320667D01*
X84607Y320458D01*
X84660Y320208D01*
X84633Y319958D01*
X84527Y319750D01*
X83993Y319333D01*
X83753Y319042D01*
X83593Y318625D01*
X83540Y318250D01*
X84660D01*
G01X94813Y304750D02*
X94973Y304458D01*
X95187Y304292D01*
X95427Y304250D01*
X95640Y304292D01*
X95853Y304500D01*
X95987Y304750D01*
X96013Y305000D01*
X95960Y305292D01*
X95773Y305500D01*
X95587Y305583D01*
X95347D01*
G01X95587D02*
X95747Y305708D01*
X95880Y305917D01*
X95933Y306167D01*
X95880Y306417D01*
X95747Y306625D01*
X95507Y306750D01*
X95267Y306708D01*
X95027Y306542D01*
G01X97013Y304750D02*
X97173Y304458D01*
X97387Y304292D01*
X97627Y304250D01*
X97840Y304292D01*
X98053Y304500D01*
X98187Y304750D01*
X98213Y305000D01*
X98160Y305292D01*
X97973Y305500D01*
X97787Y305583D01*
X97547D01*
G01X97787D02*
X97947Y305708D01*
X98080Y305917D01*
X98133Y306167D01*
X98080Y306417D01*
X97947Y306625D01*
X97707Y306750D01*
X97467Y306708D01*
X97227Y306542D01*
G01X84550Y348400D02*
X82050D01*
X82550Y348080D01*
G01X84550D02*
Y348720D01*
G01Y350547D02*
X84008Y350600D01*
X83550Y350680D01*
X83133Y350787D01*
X82675Y350920D01*
X82050Y351133D01*
Y350067D01*
G01X91772Y365033D02*
X92002Y365343D01*
X92270Y365498D01*
X92577Y365550D01*
X92960Y365447D01*
X93228Y365188D01*
X93305Y364878D01*
X93267Y364568D01*
X93113Y364310D01*
X92347Y363793D01*
X92002Y363432D01*
X91772Y362915D01*
X91695Y362450D01*
X93305D01*
G01X96400Y362750D02*
Y365250D01*
X96080Y364750D01*
G01Y362750D02*
X96720D01*
G01X98093Y363792D02*
X98280Y364083D01*
X98440Y364250D01*
X98653Y364333D01*
X98840Y364250D01*
X98973Y364083D01*
X99080Y363833D01*
X99107Y363542D01*
X99080Y363292D01*
X98973Y363042D01*
X98813Y362833D01*
X98627Y362750D01*
X98413Y362833D01*
X98227Y363083D01*
X98120Y363458D01*
X98093Y363875D01*
X98147Y364417D01*
X98227Y364708D01*
X98360Y365000D01*
X98547Y365208D01*
X98733Y365250D01*
X98920Y365167D01*
X99053Y364958D01*
G01X113460Y61450D02*
Y64550D01*
X112042Y62328D01*
X113958D01*
G01X111157Y75415D02*
X111387Y75157D01*
X111655Y75002D01*
X112000Y74950D01*
X112345Y75053D01*
X112613Y75260D01*
X112805Y75622D01*
X112843Y76035D01*
X112767Y76448D01*
X112575Y76707D01*
X112307Y76913D01*
X112038Y76965D01*
X111770Y76913D01*
X111425Y76707D01*
X111540Y78050D01*
X112575D01*
G01X112163Y83652D02*
X111933Y83807D01*
X111665Y83910D01*
X111358D01*
X111013Y83755D01*
X110745Y83497D01*
X110553Y83187D01*
X110400Y82670D01*
X110362Y82205D01*
X110438Y81740D01*
X110553Y81430D01*
X110783Y81120D01*
X111052Y80913D01*
X111320Y80810D01*
X111588D01*
X111857Y80913D01*
X112087Y81068D01*
X112278Y81275D01*
G01X113692Y83393D02*
X113922Y83703D01*
X114190Y83858D01*
X114497Y83910D01*
X114880Y83807D01*
X115148Y83548D01*
X115225Y83238D01*
X115187Y82928D01*
X115033Y82670D01*
X114267Y82153D01*
X113922Y81792D01*
X113692Y81275D01*
X113615Y80810D01*
X115225D01*
G01X116792Y83393D02*
X117022Y83703D01*
X117290Y83858D01*
X117597Y83910D01*
X117980Y83807D01*
X118248Y83548D01*
X118325Y83238D01*
X118287Y82928D01*
X118133Y82670D01*
X117367Y82153D01*
X117022Y81792D01*
X116792Y81275D01*
X116715Y80810D01*
X118325D01*
G01X119777Y81275D02*
X120007Y81017D01*
X120275Y80862D01*
X120620Y80810D01*
X120965Y80913D01*
X121233Y81120D01*
X121425Y81482D01*
X121463Y81895D01*
X121387Y82308D01*
X121195Y82567D01*
X120927Y82773D01*
X120658Y82825D01*
X120390Y82773D01*
X120045Y82567D01*
X120160Y83910D01*
X121195D01*
G01X110553Y84810D02*
Y87910D01*
X111512D01*
X111818Y87755D01*
X112010Y87548D01*
X112087Y87135D01*
X112010Y86722D01*
X111780Y86463D01*
X111512Y86308D01*
X110553D01*
G01X111512D02*
X112087Y84810D01*
G01X113577Y85430D02*
X113807Y85068D01*
X114113Y84862D01*
X114458Y84810D01*
X114765Y84862D01*
X115072Y85120D01*
X115263Y85430D01*
X115302Y85740D01*
X115225Y86102D01*
X114957Y86360D01*
X114688Y86463D01*
X114343D01*
G01X114688D02*
X114918Y86618D01*
X115110Y86877D01*
X115187Y87187D01*
X115110Y87497D01*
X114918Y87755D01*
X114573Y87910D01*
X114228Y87858D01*
X113883Y87652D01*
G01X117980Y84810D02*
Y87910D01*
X116562Y85688D01*
X118478D01*
G01X119777Y85275D02*
X120007Y85017D01*
X120275Y84862D01*
X120620Y84810D01*
X120965Y84913D01*
X121233Y85120D01*
X121425Y85482D01*
X121463Y85895D01*
X121387Y86308D01*
X121195Y86567D01*
X120927Y86773D01*
X120658Y86825D01*
X120390Y86773D01*
X120045Y86567D01*
X120160Y87910D01*
X121195D01*
G01X110503Y93310D02*
Y96410D01*
X111462D01*
X111768Y96255D01*
X111960Y96048D01*
X112037Y95635D01*
X111960Y95222D01*
X111730Y94963D01*
X111462Y94808D01*
X110503D01*
G01X111462D02*
X112037Y93310D01*
G01X114370D02*
Y96410D01*
X113910Y95790D01*
G01Y93310D02*
X114830D01*
G01X116818Y93672D02*
X117087Y93413D01*
X117393Y93310D01*
X117700Y93413D01*
X117968Y93723D01*
X118160Y94188D01*
X118237Y94653D01*
Y95222D01*
X118160Y95687D01*
X117968Y96100D01*
X117738Y96307D01*
X117470Y96410D01*
X117163Y96307D01*
X116933Y96100D01*
X116780Y95790D01*
X116703Y95377D01*
X116780Y95015D01*
X116972Y94653D01*
X117202Y94447D01*
X117470Y94395D01*
X117777Y94498D01*
X118007Y94757D01*
X118237Y95222D01*
G01X119918Y93672D02*
X120187Y93413D01*
X120493Y93310D01*
X120800Y93413D01*
X121068Y93723D01*
X121260Y94188D01*
X121337Y94653D01*
Y95222D01*
X121260Y95687D01*
X121068Y96100D01*
X120838Y96307D01*
X120570Y96410D01*
X120263Y96307D01*
X120033Y96100D01*
X119880Y95790D01*
X119803Y95377D01*
X119880Y95015D01*
X120072Y94653D01*
X120302Y94447D01*
X120570Y94395D01*
X120877Y94498D01*
X121107Y94757D01*
X121337Y95222D01*
G01X122942Y95893D02*
X123172Y96203D01*
X123440Y96358D01*
X123747Y96410D01*
X124130Y96307D01*
X124398Y96048D01*
X124475Y95738D01*
X124437Y95428D01*
X124283Y95170D01*
X123517Y94653D01*
X123172Y94292D01*
X122942Y93775D01*
X122865Y93310D01*
X124475D01*
G01X110603Y89310D02*
Y92410D01*
X111562D01*
X111868Y92255D01*
X112060Y92048D01*
X112137Y91635D01*
X112060Y91222D01*
X111830Y90963D01*
X111562Y90808D01*
X110603D01*
G01X111562D02*
X112137Y89310D01*
G01X114470D02*
Y92410D01*
X114010Y91790D01*
G01Y89310D02*
X114930D01*
G01X116918Y89672D02*
X117187Y89413D01*
X117493Y89310D01*
X117800Y89413D01*
X118068Y89723D01*
X118260Y90188D01*
X118337Y90653D01*
Y91222D01*
X118260Y91687D01*
X118068Y92100D01*
X117838Y92307D01*
X117570Y92410D01*
X117263Y92307D01*
X117033Y92100D01*
X116880Y91790D01*
X116803Y91377D01*
X116880Y91015D01*
X117072Y90653D01*
X117302Y90447D01*
X117570Y90395D01*
X117877Y90498D01*
X118107Y90757D01*
X118337Y91222D01*
G01X102737Y80750D02*
Y78528D01*
X102890Y78063D01*
X103197Y77753D01*
X103580Y77650D01*
X103963Y77753D01*
X104270Y78063D01*
X104423Y78528D01*
Y80750D01*
G01X106603Y77650D02*
X106680Y78322D01*
X106795Y78890D01*
X106948Y79407D01*
X107140Y79975D01*
X107447Y80750D01*
X105913D01*
G01X105653Y112967D02*
Y116067D01*
X106650Y113484D01*
X107647Y116067D01*
Y112967D01*
G01X108792D02*
X109750Y116067D01*
X110708Y112967D01*
G01X110363Y114052D02*
X109137D01*
G01X113693Y115809D02*
X113463Y115964D01*
X113195Y116067D01*
X112888D01*
X112543Y115912D01*
X112275Y115654D01*
X112083Y115344D01*
X111930Y114827D01*
X111892Y114362D01*
X111968Y113897D01*
X112083Y113587D01*
X112313Y113277D01*
X112582Y113070D01*
X112850Y112967D01*
X113118D01*
X113387Y113070D01*
X113617Y113225D01*
X113808Y113432D01*
G01X114800Y111934D02*
X117100D01*
G01X118283Y112967D02*
Y116067D01*
X119203D01*
X119510Y115912D01*
X119740Y115550D01*
X119817Y115137D01*
X119740Y114724D01*
X119548Y114414D01*
X119203Y114259D01*
X118283D01*
G01X121690Y116067D02*
X122610D01*
G01X122150D02*
Y112967D01*
G01X121690D02*
X122610D01*
G01X124368D02*
Y116067D01*
X126132Y112967D01*
Y116067D01*
G01X127507Y113587D02*
X127737Y113225D01*
X128043Y113019D01*
X128388Y112967D01*
X128695Y113019D01*
X129002Y113277D01*
X129193Y113587D01*
X129232Y113897D01*
X129155Y114259D01*
X128887Y114517D01*
X128618Y114620D01*
X128273D01*
G01X128618D02*
X128848Y114775D01*
X129040Y115034D01*
X129117Y115344D01*
X129040Y115654D01*
X128848Y115912D01*
X128503Y116067D01*
X128158Y116015D01*
X127813Y115809D01*
G01X114723Y172490D02*
Y175590D01*
X115720Y173007D01*
X116717Y175590D01*
Y172490D01*
G01X117862D02*
X118820Y175590D01*
X119778Y172490D01*
G01X119433Y173575D02*
X118207D01*
G01X122763Y175332D02*
X122533Y175487D01*
X122265Y175590D01*
X121958D01*
X121613Y175435D01*
X121345Y175177D01*
X121153Y174867D01*
X121000Y174350D01*
X120962Y173885D01*
X121038Y173420D01*
X121153Y173110D01*
X121383Y172800D01*
X121652Y172593D01*
X121920Y172490D01*
X122188D01*
X122457Y172593D01*
X122687Y172748D01*
X122878Y172955D01*
G01X123870Y171457D02*
X126170D01*
G01X127353Y172490D02*
Y175590D01*
X128273D01*
X128580Y175435D01*
X128810Y175073D01*
X128887Y174660D01*
X128810Y174247D01*
X128618Y173937D01*
X128273Y173782D01*
X127353D01*
G01X130760Y175590D02*
X131680D01*
G01X131220D02*
Y172490D01*
G01X130760D02*
X131680D01*
G01X133438D02*
Y175590D01*
X135202Y172490D01*
Y175590D01*
G01X136692Y175073D02*
X136922Y175383D01*
X137190Y175538D01*
X137497Y175590D01*
X137880Y175487D01*
X138148Y175228D01*
X138225Y174918D01*
X138187Y174608D01*
X138033Y174350D01*
X137267Y173833D01*
X136922Y173472D01*
X136692Y172955D01*
X136615Y172490D01*
X138225D01*
G01X101050Y244083D02*
X97950D01*
Y245042D01*
X98105Y245348D01*
X98312Y245540D01*
X98725Y245617D01*
X99138Y245540D01*
X99397Y245310D01*
X99552Y245042D01*
Y244083D01*
G01Y245042D02*
X101050Y245617D01*
G01X100430Y247107D02*
X100792Y247337D01*
X100998Y247643D01*
X101050Y247988D01*
X100998Y248295D01*
X100740Y248602D01*
X100430Y248793D01*
X100120Y248832D01*
X99758Y248755D01*
X99500Y248487D01*
X99397Y248218D01*
Y247873D01*
G01Y248218D02*
X99242Y248448D01*
X98983Y248640D01*
X98673Y248717D01*
X98363Y248640D01*
X98105Y248448D01*
X97950Y248103D01*
X98002Y247758D01*
X98208Y247413D01*
G01X100585Y250207D02*
X100843Y250437D01*
X100998Y250705D01*
X101050Y251050D01*
X100947Y251395D01*
X100740Y251663D01*
X100378Y251855D01*
X99965Y251893D01*
X99552Y251817D01*
X99293Y251625D01*
X99087Y251357D01*
X99035Y251088D01*
X99087Y250820D01*
X99293Y250475D01*
X97950Y250590D01*
Y251625D01*
G01X101050Y254150D02*
X97950D01*
X98570Y253690D01*
G01X101050D02*
Y254610D01*
G01X114723Y251490D02*
Y254590D01*
X115720Y252007D01*
X116717Y254590D01*
Y251490D01*
G01X117862D02*
X118820Y254590D01*
X119778Y251490D01*
G01X119433Y252575D02*
X118207D01*
G01X122763Y254332D02*
X122533Y254487D01*
X122265Y254590D01*
X121958D01*
X121613Y254435D01*
X121345Y254177D01*
X121153Y253867D01*
X121000Y253350D01*
X120962Y252885D01*
X121038Y252420D01*
X121153Y252110D01*
X121383Y251800D01*
X121652Y251593D01*
X121920Y251490D01*
X122188D01*
X122457Y251593D01*
X122687Y251748D01*
X122878Y251955D01*
G01X123870Y250457D02*
X126170D01*
G01X127353Y251490D02*
Y254590D01*
X128273D01*
X128580Y254435D01*
X128810Y254073D01*
X128887Y253660D01*
X128810Y253247D01*
X128618Y252937D01*
X128273Y252782D01*
X127353D01*
G01X130760Y254590D02*
X131680D01*
G01X131220D02*
Y251490D01*
G01X130760D02*
X131680D01*
G01X133438D02*
Y254590D01*
X135202Y251490D01*
Y254590D01*
G01X137420Y251490D02*
Y254590D01*
X136960Y253970D01*
G01Y251490D02*
X137880D01*
G01X102693Y259292D02*
X102463Y259447D01*
X102195Y259550D01*
X101888D01*
X101543Y259395D01*
X101275Y259137D01*
X101083Y258827D01*
X100930Y258310D01*
X100892Y257845D01*
X100968Y257380D01*
X101083Y257070D01*
X101313Y256760D01*
X101582Y256553D01*
X101850Y256450D01*
X102118D01*
X102387Y256553D01*
X102617Y256708D01*
X102808Y256915D01*
G01X104222Y259033D02*
X104452Y259343D01*
X104720Y259498D01*
X105027Y259550D01*
X105410Y259447D01*
X105678Y259188D01*
X105755Y258878D01*
X105717Y258568D01*
X105563Y258310D01*
X104797Y257793D01*
X104452Y257432D01*
X104222Y256915D01*
X104145Y256450D01*
X105755D01*
G01X107973D02*
X108050Y257122D01*
X108165Y257690D01*
X108318Y258207D01*
X108510Y258775D01*
X108817Y259550D01*
X107283D01*
G01X110422Y257742D02*
X110690Y258103D01*
X110920Y258310D01*
X111227Y258413D01*
X111495Y258310D01*
X111687Y258103D01*
X111840Y257793D01*
X111878Y257432D01*
X111840Y257122D01*
X111687Y256812D01*
X111457Y256553D01*
X111188Y256450D01*
X110882Y256553D01*
X110613Y256863D01*
X110460Y257328D01*
X110422Y257845D01*
X110498Y258517D01*
X110613Y258878D01*
X110805Y259240D01*
X111073Y259498D01*
X111342Y259550D01*
X111610Y259447D01*
X111802Y259188D01*
G01X102193Y269792D02*
X101963Y269947D01*
X101695Y270050D01*
X101388D01*
X101043Y269895D01*
X100775Y269637D01*
X100583Y269327D01*
X100430Y268810D01*
X100392Y268345D01*
X100468Y267880D01*
X100583Y267570D01*
X100813Y267260D01*
X101082Y267053D01*
X101350Y266950D01*
X101618D01*
X101887Y267053D01*
X102117Y267208D01*
X102308Y267415D01*
G01X103722Y269533D02*
X103952Y269843D01*
X104220Y269998D01*
X104527Y270050D01*
X104910Y269947D01*
X105178Y269688D01*
X105255Y269378D01*
X105217Y269068D01*
X105063Y268810D01*
X104297Y268293D01*
X103952Y267932D01*
X103722Y267415D01*
X103645Y266950D01*
X105255D01*
G01X107473D02*
X107550Y267622D01*
X107665Y268190D01*
X107818Y268707D01*
X108010Y269275D01*
X108317Y270050D01*
X106783D01*
G01X110650Y266950D02*
X110918Y267002D01*
X111225Y267157D01*
X111417Y267415D01*
X111493Y267777D01*
X111417Y268138D01*
X111187Y268448D01*
X110842Y268603D01*
X110458D01*
X110228Y268707D01*
X110037Y268965D01*
X109960Y269327D01*
X110075Y269688D01*
X110343Y269947D01*
X110650Y270050D01*
X110957Y269947D01*
X111225Y269688D01*
X111340Y269327D01*
X111263Y268965D01*
X111072Y268707D01*
X110842Y268603D01*
X110458D01*
X110113Y268448D01*
X109883Y268138D01*
X109807Y267777D01*
X109883Y267415D01*
X110075Y267157D01*
X110382Y267002D01*
X110650Y266950D01*
G01X100633Y265050D02*
Y261950D01*
X102167D01*
G01X104500D02*
Y265050D01*
X104040Y264430D01*
G01Y261950D02*
X104960D01*
G01X107600D02*
X107868Y262002D01*
X108175Y262157D01*
X108367Y262415D01*
X108443Y262777D01*
X108367Y263138D01*
X108137Y263448D01*
X107792Y263603D01*
X107408D01*
X107178Y263707D01*
X106987Y263965D01*
X106910Y264327D01*
X107025Y264688D01*
X107293Y264947D01*
X107600Y265050D01*
X107907Y264947D01*
X108175Y264688D01*
X108290Y264327D01*
X108213Y263965D01*
X108022Y263707D01*
X107792Y263603D01*
X107408D01*
X107063Y263448D01*
X106833Y263138D01*
X106757Y262777D01*
X106833Y262415D01*
X107025Y262157D01*
X107332Y262002D01*
X107600Y261950D01*
G01X102193Y274792D02*
X101963Y274947D01*
X101695Y275050D01*
X101388D01*
X101043Y274895D01*
X100775Y274637D01*
X100583Y274327D01*
X100430Y273810D01*
X100392Y273345D01*
X100468Y272880D01*
X100583Y272570D01*
X100813Y272260D01*
X101082Y272053D01*
X101350Y271950D01*
X101618D01*
X101887Y272053D01*
X102117Y272208D01*
X102308Y272415D01*
G01X103722Y274533D02*
X103952Y274843D01*
X104220Y274998D01*
X104527Y275050D01*
X104910Y274947D01*
X105178Y274688D01*
X105255Y274378D01*
X105217Y274068D01*
X105063Y273810D01*
X104297Y273293D01*
X103952Y272932D01*
X103722Y272415D01*
X103645Y271950D01*
X105255D01*
G01X107473D02*
X107550Y272622D01*
X107665Y273190D01*
X107818Y273707D01*
X108010Y274275D01*
X108317Y275050D01*
X106783D01*
G01X110573Y271950D02*
X110650Y272622D01*
X110765Y273190D01*
X110918Y273707D01*
X111110Y274275D01*
X111417Y275050D01*
X109883D01*
G01X110050Y278083D02*
X106950D01*
Y279042D01*
X107105Y279348D01*
X107312Y279540D01*
X107725Y279617D01*
X108138Y279540D01*
X108397Y279310D01*
X108552Y279042D01*
Y278083D01*
G01Y279042D02*
X110050Y279617D01*
G01X109430Y281107D02*
X109792Y281337D01*
X109998Y281643D01*
X110050Y281988D01*
X109998Y282295D01*
X109740Y282602D01*
X109430Y282793D01*
X109120Y282832D01*
X108758Y282755D01*
X108500Y282487D01*
X108397Y282218D01*
Y281873D01*
G01Y282218D02*
X108242Y282448D01*
X107983Y282640D01*
X107673Y282717D01*
X107363Y282640D01*
X107105Y282448D01*
X106950Y282103D01*
X107002Y281758D01*
X107208Y281413D01*
G01X109585Y284207D02*
X109843Y284437D01*
X109998Y284705D01*
X110050Y285050D01*
X109947Y285395D01*
X109740Y285663D01*
X109378Y285855D01*
X108965Y285893D01*
X108552Y285817D01*
X108293Y285625D01*
X108087Y285357D01*
X108035Y285088D01*
X108087Y284820D01*
X108293Y284475D01*
X106950Y284590D01*
Y285625D01*
G01X109430Y287307D02*
X109792Y287537D01*
X109998Y287843D01*
X110050Y288188D01*
X109998Y288495D01*
X109740Y288802D01*
X109430Y288993D01*
X109120Y289032D01*
X108758Y288955D01*
X108500Y288687D01*
X108397Y288418D01*
Y288073D01*
G01Y288418D02*
X108242Y288648D01*
X107983Y288840D01*
X107673Y288917D01*
X107363Y288840D01*
X107105Y288648D01*
X106950Y288303D01*
X107002Y287958D01*
X107208Y287613D01*
G01X106050Y278083D02*
X102950D01*
Y279042D01*
X103105Y279348D01*
X103312Y279540D01*
X103725Y279617D01*
X104138Y279540D01*
X104397Y279310D01*
X104552Y279042D01*
Y278083D01*
G01Y279042D02*
X106050Y279617D01*
G01Y282410D02*
X102950D01*
X105172Y280992D01*
Y282908D01*
G01X106050Y285050D02*
X105998Y285318D01*
X105843Y285625D01*
X105585Y285817D01*
X105223Y285893D01*
X104862Y285817D01*
X104552Y285587D01*
X104397Y285242D01*
Y284858D01*
X104293Y284628D01*
X104035Y284437D01*
X103673Y284360D01*
X103312Y284475D01*
X103053Y284743D01*
X102950Y285050D01*
X103053Y285357D01*
X103312Y285625D01*
X103673Y285740D01*
X104035Y285663D01*
X104293Y285472D01*
X104397Y285242D01*
Y284858D01*
X104552Y284513D01*
X104862Y284283D01*
X105223Y284207D01*
X105585Y284283D01*
X105843Y284475D01*
X105998Y284782D01*
X106050Y285050D01*
G01X102950Y288150D02*
X103053Y287843D01*
X103312Y287613D01*
X103622Y287460D01*
X104035Y287345D01*
X104500Y287307D01*
X104965Y287345D01*
X105378Y287460D01*
X105688Y287613D01*
X105947Y287843D01*
X106050Y288150D01*
X105947Y288457D01*
X105688Y288687D01*
X105378Y288840D01*
X104965Y288955D01*
X104500Y288993D01*
X104035Y288955D01*
X103622Y288840D01*
X103312Y288687D01*
X103053Y288457D01*
X102950Y288150D01*
G01X114657Y379570D02*
X114887Y379208D01*
X115193Y379002D01*
X115538Y378950D01*
X115845Y379002D01*
X116152Y379260D01*
X116343Y379570D01*
X116382Y379880D01*
X116305Y380242D01*
X116037Y380500D01*
X115768Y380603D01*
X115423D01*
G01X115768D02*
X115998Y380758D01*
X116190Y381017D01*
X116267Y381327D01*
X116190Y381637D01*
X115998Y381895D01*
X115653Y382050D01*
X115308Y381998D01*
X114963Y381792D01*
G01X109550Y385083D02*
X106450D01*
Y386042D01*
X106605Y386348D01*
X106812Y386540D01*
X107225Y386617D01*
X107638Y386540D01*
X107897Y386310D01*
X108052Y386042D01*
Y385083D01*
G01Y386042D02*
X109550Y386617D01*
G01Y388950D02*
X106450D01*
X107070Y388490D01*
G01X109550D02*
Y389410D01*
G01X106967Y391322D02*
X106657Y391552D01*
X106502Y391820D01*
X106450Y392127D01*
X106553Y392510D01*
X106812Y392778D01*
X107122Y392855D01*
X107432Y392817D01*
X107690Y392663D01*
X108207Y391897D01*
X108568Y391552D01*
X109085Y391322D01*
X109550Y391245D01*
Y392855D01*
G01X109188Y394498D02*
X109447Y394767D01*
X109550Y395073D01*
X109447Y395380D01*
X109137Y395648D01*
X108672Y395840D01*
X108207Y395917D01*
X107638D01*
X107173Y395840D01*
X106760Y395648D01*
X106553Y395418D01*
X106450Y395150D01*
X106553Y394843D01*
X106760Y394613D01*
X107070Y394460D01*
X107483Y394383D01*
X107845Y394460D01*
X108207Y394652D01*
X108413Y394882D01*
X108465Y395150D01*
X108362Y395457D01*
X108103Y395687D01*
X107638Y395917D01*
G01X113550Y385083D02*
X110450D01*
Y386042D01*
X110605Y386348D01*
X110812Y386540D01*
X111225Y386617D01*
X111638Y386540D01*
X111897Y386310D01*
X112052Y386042D01*
Y385083D01*
G01Y386042D02*
X113550Y386617D01*
G01Y388950D02*
X110450D01*
X111070Y388490D01*
G01X113550D02*
Y389410D01*
G01X110967Y391322D02*
X110657Y391552D01*
X110502Y391820D01*
X110450Y392127D01*
X110553Y392510D01*
X110812Y392778D01*
X111122Y392855D01*
X111432Y392817D01*
X111690Y392663D01*
X112207Y391897D01*
X112568Y391552D01*
X113085Y391322D01*
X113550Y391245D01*
Y392855D01*
G01Y395150D02*
X113498Y395418D01*
X113343Y395725D01*
X113085Y395917D01*
X112723Y395993D01*
X112362Y395917D01*
X112052Y395687D01*
X111897Y395342D01*
Y394958D01*
X111793Y394728D01*
X111535Y394537D01*
X111173Y394460D01*
X110812Y394575D01*
X110553Y394843D01*
X110450Y395150D01*
X110553Y395457D01*
X110812Y395725D01*
X111173Y395840D01*
X111535Y395763D01*
X111793Y395572D01*
X111897Y395342D01*
Y394958D01*
X112052Y394613D01*
X112362Y394383D01*
X112723Y394307D01*
X113085Y394383D01*
X113343Y394575D01*
X113498Y394882D01*
X113550Y395150D01*
G01X105550Y385083D02*
X102450D01*
Y386042D01*
X102605Y386348D01*
X102812Y386540D01*
X103225Y386617D01*
X103638Y386540D01*
X103897Y386310D01*
X104052Y386042D01*
Y385083D01*
G01Y386042D02*
X105550Y386617D01*
G01Y389410D02*
X102450D01*
X104672Y387992D01*
Y389908D01*
G01X105085Y391207D02*
X105343Y391437D01*
X105498Y391705D01*
X105550Y392050D01*
X105447Y392395D01*
X105240Y392663D01*
X104878Y392855D01*
X104465Y392893D01*
X104052Y392817D01*
X103793Y392625D01*
X103587Y392357D01*
X103535Y392088D01*
X103587Y391820D01*
X103793Y391475D01*
X102450Y391590D01*
Y392625D01*
G01X104258Y394422D02*
X103897Y394690D01*
X103690Y394920D01*
X103587Y395227D01*
X103690Y395495D01*
X103897Y395687D01*
X104207Y395840D01*
X104568Y395878D01*
X104878Y395840D01*
X105188Y395687D01*
X105447Y395457D01*
X105550Y395188D01*
X105447Y394882D01*
X105137Y394613D01*
X104672Y394460D01*
X104155Y394422D01*
X103483Y394498D01*
X103122Y394613D01*
X102760Y394805D01*
X102502Y395073D01*
X102450Y395342D01*
X102553Y395610D01*
X102812Y395802D01*
G01X97450Y374350D02*
X100550D01*
G01X97450Y373468D02*
Y375232D01*
G01X100550Y376683D02*
X97450D01*
Y377603D01*
X97605Y377910D01*
X97967Y378140D01*
X98380Y378217D01*
X98793Y378140D01*
X99103Y377948D01*
X99258Y377603D01*
Y376683D01*
G01X100550Y380550D02*
X97450D01*
X98070Y380090D01*
G01X100550D02*
Y381010D01*
G01Y383650D02*
X97450D01*
X98070Y383190D01*
G01X100550D02*
Y384110D01*
G01X114272Y400033D02*
X114502Y400343D01*
X114770Y400498D01*
X115077Y400550D01*
X115460Y400447D01*
X115728Y400188D01*
X115805Y399878D01*
X115767Y399568D01*
X115613Y399310D01*
X114847Y398793D01*
X114502Y398432D01*
X114272Y397915D01*
X114195Y397450D01*
X115805D01*
G01X98950Y397850D02*
X102050D01*
G01X98950Y396968D02*
Y398732D01*
G01X102050Y400183D02*
X98950D01*
Y401103D01*
X99105Y401410D01*
X99467Y401640D01*
X99880Y401717D01*
X100293Y401640D01*
X100603Y401448D01*
X100758Y401103D01*
Y400183D01*
G01X102050Y404510D02*
X98950D01*
X101172Y403092D01*
Y405008D01*
G01X99467Y406422D02*
X99157Y406652D01*
X99002Y406920D01*
X98950Y407227D01*
X99053Y407610D01*
X99312Y407878D01*
X99622Y407955D01*
X99932Y407917D01*
X100190Y407763D01*
X100707Y406997D01*
X101068Y406652D01*
X101585Y406422D01*
X102050Y406345D01*
Y407955D01*
G01X123550Y292083D02*
X120450D01*
Y293042D01*
X120605Y293348D01*
X120812Y293540D01*
X121225Y293617D01*
X121638Y293540D01*
X121897Y293310D01*
X122052Y293042D01*
Y292083D01*
G01Y293042D02*
X123550Y293617D01*
G01X122930Y295107D02*
X123292Y295337D01*
X123498Y295643D01*
X123550Y295988D01*
X123498Y296295D01*
X123240Y296602D01*
X122930Y296793D01*
X122620Y296832D01*
X122258Y296755D01*
X122000Y296487D01*
X121897Y296218D01*
Y295873D01*
G01Y296218D02*
X121742Y296448D01*
X121483Y296640D01*
X121173Y296717D01*
X120863Y296640D01*
X120605Y296448D01*
X120450Y296103D01*
X120502Y295758D01*
X120708Y295413D01*
G01X123085Y298207D02*
X123343Y298437D01*
X123498Y298705D01*
X123550Y299050D01*
X123447Y299395D01*
X123240Y299663D01*
X122878Y299855D01*
X122465Y299893D01*
X122052Y299817D01*
X121793Y299625D01*
X121587Y299357D01*
X121535Y299088D01*
X121587Y298820D01*
X121793Y298475D01*
X120450Y298590D01*
Y299625D01*
G01X120967Y301422D02*
X120657Y301652D01*
X120502Y301920D01*
X120450Y302227D01*
X120553Y302610D01*
X120812Y302878D01*
X121122Y302955D01*
X121432Y302917D01*
X121690Y302763D01*
X122207Y301997D01*
X122568Y301652D01*
X123085Y301422D01*
X123550Y301345D01*
Y302955D01*
G01X127550Y292083D02*
X124450D01*
Y293042D01*
X124605Y293348D01*
X124812Y293540D01*
X125225Y293617D01*
X125638Y293540D01*
X125897Y293310D01*
X126052Y293042D01*
Y292083D01*
G01Y293042D02*
X127550Y293617D01*
G01Y296410D02*
X124450D01*
X126672Y294992D01*
Y296908D01*
G01X127550Y299050D02*
X127498Y299318D01*
X127343Y299625D01*
X127085Y299817D01*
X126723Y299893D01*
X126362Y299817D01*
X126052Y299587D01*
X125897Y299242D01*
Y298858D01*
X125793Y298628D01*
X125535Y298437D01*
X125173Y298360D01*
X124812Y298475D01*
X124553Y298743D01*
X124450Y299050D01*
X124553Y299357D01*
X124812Y299625D01*
X125173Y299740D01*
X125535Y299663D01*
X125793Y299472D01*
X125897Y299242D01*
Y298858D01*
X126052Y298513D01*
X126362Y298283D01*
X126723Y298207D01*
X127085Y298283D01*
X127343Y298475D01*
X127498Y298782D01*
X127550Y299050D01*
G01Y302150D02*
X124450D01*
X125070Y301690D01*
G01X127550D02*
Y302610D01*
G01X127720Y303750D02*
Y306250D01*
X126733Y304458D01*
X128067D01*
G01X129600Y303750D02*
X129787Y303792D01*
X130000Y303917D01*
X130133Y304125D01*
X130187Y304417D01*
X130133Y304708D01*
X129973Y304958D01*
X129733Y305083D01*
X129467D01*
X129307Y305167D01*
X129173Y305375D01*
X129120Y305667D01*
X129200Y305958D01*
X129387Y306167D01*
X129600Y306250D01*
X129813Y306167D01*
X130000Y305958D01*
X130080Y305667D01*
X130027Y305375D01*
X129893Y305167D01*
X129733Y305083D01*
X129467D01*
X129227Y304958D01*
X129067Y304708D01*
X129013Y304417D01*
X129067Y304125D01*
X129200Y303917D01*
X129413Y303792D01*
X129600Y303750D01*
G01X130083Y366950D02*
Y370050D01*
X131042D01*
X131348Y369895D01*
X131540Y369688D01*
X131617Y369275D01*
X131540Y368862D01*
X131310Y368603D01*
X131042Y368448D01*
X130083D01*
G01X131042D02*
X131617Y366950D01*
G01X134410D02*
Y370050D01*
X132992Y367828D01*
X134908D01*
G01X136207Y367415D02*
X136437Y367157D01*
X136705Y367002D01*
X137050Y366950D01*
X137395Y367053D01*
X137663Y367260D01*
X137855Y367622D01*
X137893Y368035D01*
X137817Y368448D01*
X137625Y368707D01*
X137357Y368913D01*
X137088Y368965D01*
X136820Y368913D01*
X136475Y368707D01*
X136590Y370050D01*
X137625D01*
G01X139307Y367415D02*
X139537Y367157D01*
X139805Y367002D01*
X140150Y366950D01*
X140495Y367053D01*
X140763Y367260D01*
X140955Y367622D01*
X140993Y368035D01*
X140917Y368448D01*
X140725Y368707D01*
X140457Y368913D01*
X140188Y368965D01*
X139920Y368913D01*
X139575Y368707D01*
X139690Y370050D01*
X140725D01*
G01X119450Y399450D02*
Y400845D01*
X118683Y402550D01*
G01X120217D02*
X119450Y400845D01*
G01X121822Y402033D02*
X122052Y402343D01*
X122320Y402498D01*
X122627Y402550D01*
X123010Y402447D01*
X123278Y402188D01*
X123355Y401878D01*
X123317Y401568D01*
X123163Y401310D01*
X122397Y400793D01*
X122052Y400432D01*
X121822Y399915D01*
X121745Y399450D01*
X123355D01*
G01X127343Y407392D02*
X127113Y407547D01*
X126845Y407650D01*
X126538D01*
X126193Y407495D01*
X125925Y407237D01*
X125733Y406927D01*
X125580Y406410D01*
X125542Y405945D01*
X125618Y405480D01*
X125733Y405170D01*
X125963Y404860D01*
X126232Y404653D01*
X126500Y404550D01*
X126768D01*
X127037Y404653D01*
X127267Y404808D01*
X127458Y405015D01*
G01X128757Y405170D02*
X128987Y404808D01*
X129293Y404602D01*
X129638Y404550D01*
X129945Y404602D01*
X130252Y404860D01*
X130443Y405170D01*
X130482Y405480D01*
X130405Y405842D01*
X130137Y406100D01*
X129868Y406203D01*
X129523D01*
G01X129868D02*
X130098Y406358D01*
X130290Y406617D01*
X130367Y406927D01*
X130290Y407237D01*
X130098Y407495D01*
X129753Y407650D01*
X129408Y407598D01*
X129063Y407392D01*
G01X132700Y404550D02*
Y407650D01*
X132240Y407030D01*
G01Y404550D02*
X133160D01*
G01X127343Y403392D02*
X127113Y403547D01*
X126845Y403650D01*
X126538D01*
X126193Y403495D01*
X125925Y403237D01*
X125733Y402927D01*
X125580Y402410D01*
X125542Y401945D01*
X125618Y401480D01*
X125733Y401170D01*
X125963Y400860D01*
X126232Y400653D01*
X126500Y400550D01*
X126768D01*
X127037Y400653D01*
X127267Y400808D01*
X127458Y401015D01*
G01X128872Y403133D02*
X129102Y403443D01*
X129370Y403598D01*
X129677Y403650D01*
X130060Y403547D01*
X130328Y403288D01*
X130405Y402978D01*
X130367Y402668D01*
X130213Y402410D01*
X129447Y401893D01*
X129102Y401532D01*
X128872Y401015D01*
X128795Y400550D01*
X130405D01*
G01X132048Y400912D02*
X132317Y400653D01*
X132623Y400550D01*
X132930Y400653D01*
X133198Y400963D01*
X133390Y401428D01*
X133467Y401893D01*
Y402462D01*
X133390Y402927D01*
X133198Y403340D01*
X132968Y403547D01*
X132700Y403650D01*
X132393Y403547D01*
X132163Y403340D01*
X132010Y403030D01*
X131933Y402617D01*
X132010Y402255D01*
X132202Y401893D01*
X132432Y401687D01*
X132700Y401635D01*
X133007Y401738D01*
X133237Y401997D01*
X133467Y402462D01*
G01X127243Y411292D02*
X127013Y411447D01*
X126745Y411550D01*
X126438D01*
X126093Y411395D01*
X125825Y411137D01*
X125633Y410827D01*
X125480Y410310D01*
X125442Y409845D01*
X125518Y409380D01*
X125633Y409070D01*
X125863Y408760D01*
X126132Y408553D01*
X126400Y408450D01*
X126668D01*
X126937Y408553D01*
X127167Y408708D01*
X127358Y408915D01*
G01X129960Y408450D02*
Y411550D01*
X128542Y409328D01*
X130458D01*
G01X131757Y409070D02*
X131987Y408708D01*
X132293Y408502D01*
X132638Y408450D01*
X132945Y408502D01*
X133252Y408760D01*
X133443Y409070D01*
X133482Y409380D01*
X133405Y409742D01*
X133137Y410000D01*
X132868Y410103D01*
X132523D01*
G01X132868D02*
X133098Y410258D01*
X133290Y410517D01*
X133367Y410827D01*
X133290Y411137D01*
X133098Y411395D01*
X132753Y411550D01*
X132408Y411498D01*
X132063Y411292D01*
G01X127243Y415292D02*
X127013Y415447D01*
X126745Y415550D01*
X126438D01*
X126093Y415395D01*
X125825Y415137D01*
X125633Y414827D01*
X125480Y414310D01*
X125442Y413845D01*
X125518Y413380D01*
X125633Y413070D01*
X125863Y412760D01*
X126132Y412553D01*
X126400Y412450D01*
X126668D01*
X126937Y412553D01*
X127167Y412708D01*
X127358Y412915D01*
G01X129500Y412450D02*
Y415550D01*
X129040Y414930D01*
G01Y412450D02*
X129960D01*
G01X132600D02*
Y415550D01*
X132140Y414930D01*
G01Y412450D02*
X133060D01*
G01X124050Y413683D02*
X120950D01*
Y414642D01*
X121105Y414948D01*
X121312Y415140D01*
X121725Y415217D01*
X122138Y415140D01*
X122397Y414910D01*
X122552Y414642D01*
Y413683D01*
G01Y414642D02*
X124050Y415217D01*
G01X122758Y416822D02*
X122397Y417090D01*
X122190Y417320D01*
X122087Y417627D01*
X122190Y417895D01*
X122397Y418087D01*
X122707Y418240D01*
X123068Y418278D01*
X123378Y418240D01*
X123688Y418087D01*
X123947Y417857D01*
X124050Y417588D01*
X123947Y417282D01*
X123637Y417013D01*
X123172Y416860D01*
X122655Y416822D01*
X121983Y416898D01*
X121622Y417013D01*
X121260Y417205D01*
X121002Y417473D01*
X120950Y417742D01*
X121053Y418010D01*
X121312Y418202D01*
G01X125633Y416450D02*
Y419550D01*
X126592D01*
X126898Y419395D01*
X127090Y419188D01*
X127167Y418775D01*
X127090Y418362D01*
X126860Y418103D01*
X126592Y417948D01*
X125633D01*
G01X126592D02*
X127167Y416450D01*
G01X128657Y417070D02*
X128887Y416708D01*
X129193Y416502D01*
X129538Y416450D01*
X129845Y416502D01*
X130152Y416760D01*
X130343Y417070D01*
X130382Y417380D01*
X130305Y417742D01*
X130037Y418000D01*
X129768Y418103D01*
X129423D01*
G01X129768D02*
X129998Y418258D01*
X130190Y418517D01*
X130267Y418827D01*
X130190Y419137D01*
X129998Y419395D01*
X129653Y419550D01*
X129308Y419498D01*
X128963Y419292D01*
G01X133060Y416450D02*
Y419550D01*
X131642Y417328D01*
X133558D01*
G01X137983Y56250D02*
Y59350D01*
X138942D01*
X139248Y59195D01*
X139440Y58988D01*
X139517Y58575D01*
X139440Y58162D01*
X139210Y57903D01*
X138942Y57748D01*
X137983D01*
G01X138942D02*
X139517Y56250D01*
G01X141007Y56870D02*
X141237Y56508D01*
X141543Y56302D01*
X141888Y56250D01*
X142195Y56302D01*
X142502Y56560D01*
X142693Y56870D01*
X142732Y57180D01*
X142655Y57542D01*
X142387Y57800D01*
X142118Y57903D01*
X141773D01*
G01X142118D02*
X142348Y58058D01*
X142540Y58317D01*
X142617Y58627D01*
X142540Y58937D01*
X142348Y59195D01*
X142003Y59350D01*
X141658Y59298D01*
X141313Y59092D01*
G01X144950Y56250D02*
Y59350D01*
X144490Y58730D01*
G01Y56250D02*
X145410D01*
G01X147322Y58833D02*
X147552Y59143D01*
X147820Y59298D01*
X148127Y59350D01*
X148510Y59247D01*
X148778Y58988D01*
X148855Y58678D01*
X148817Y58368D01*
X148663Y58110D01*
X147897Y57593D01*
X147552Y57232D01*
X147322Y56715D01*
X147245Y56250D01*
X148855D01*
G01X137983Y51750D02*
Y54850D01*
X138942D01*
X139248Y54695D01*
X139440Y54488D01*
X139517Y54075D01*
X139440Y53662D01*
X139210Y53403D01*
X138942Y53248D01*
X137983D01*
G01X138942D02*
X139517Y51750D01*
G01X141850D02*
Y54850D01*
X141390Y54230D01*
G01Y51750D02*
X142310D01*
G01X144950D02*
X145218Y51802D01*
X145525Y51957D01*
X145717Y52215D01*
X145793Y52577D01*
X145717Y52938D01*
X145487Y53248D01*
X145142Y53403D01*
X144758D01*
X144528Y53507D01*
X144337Y53765D01*
X144260Y54127D01*
X144375Y54488D01*
X144643Y54747D01*
X144950Y54850D01*
X145257Y54747D01*
X145525Y54488D01*
X145640Y54127D01*
X145563Y53765D01*
X145372Y53507D01*
X145142Y53403D01*
X144758D01*
X144413Y53248D01*
X144183Y52938D01*
X144107Y52577D01*
X144183Y52215D01*
X144375Y51957D01*
X144682Y51802D01*
X144950Y51750D01*
G01X147207Y52370D02*
X147437Y52008D01*
X147743Y51802D01*
X148088Y51750D01*
X148395Y51802D01*
X148702Y52060D01*
X148893Y52370D01*
X148932Y52680D01*
X148855Y53042D01*
X148587Y53300D01*
X148318Y53403D01*
X147973D01*
G01X148318D02*
X148548Y53558D01*
X148740Y53817D01*
X148817Y54127D01*
X148740Y54437D01*
X148548Y54695D01*
X148203Y54850D01*
X147858Y54798D01*
X147513Y54592D01*
G01X138583Y63950D02*
Y67050D01*
X139542D01*
X139848Y66895D01*
X140040Y66688D01*
X140117Y66275D01*
X140040Y65862D01*
X139810Y65603D01*
X139542Y65448D01*
X138583D01*
G01X139542D02*
X140117Y63950D01*
G01X142450D02*
Y67050D01*
X141990Y66430D01*
G01Y63950D02*
X142910D01*
G01X145550D02*
X145818Y64002D01*
X146125Y64157D01*
X146317Y64415D01*
X146393Y64777D01*
X146317Y65138D01*
X146087Y65448D01*
X145742Y65603D01*
X145358D01*
X145128Y65707D01*
X144937Y65965D01*
X144860Y66327D01*
X144975Y66688D01*
X145243Y66947D01*
X145550Y67050D01*
X145857Y66947D01*
X146125Y66688D01*
X146240Y66327D01*
X146163Y65965D01*
X145972Y65707D01*
X145742Y65603D01*
X145358D01*
X145013Y65448D01*
X144783Y65138D01*
X144707Y64777D01*
X144783Y64415D01*
X144975Y64157D01*
X145282Y64002D01*
X145550Y63950D01*
G01X149110D02*
Y67050D01*
X147692Y64828D01*
X149608D01*
G01X139583Y70950D02*
Y74050D01*
X140542D01*
X140848Y73895D01*
X141040Y73688D01*
X141117Y73275D01*
X141040Y72862D01*
X140810Y72603D01*
X140542Y72448D01*
X139583D01*
G01X140542D02*
X141117Y70950D01*
G01X142607Y71570D02*
X142837Y71208D01*
X143143Y71002D01*
X143488Y70950D01*
X143795Y71002D01*
X144102Y71260D01*
X144293Y71570D01*
X144332Y71880D01*
X144255Y72242D01*
X143987Y72500D01*
X143718Y72603D01*
X143373D01*
G01X143718D02*
X143948Y72758D01*
X144140Y73017D01*
X144217Y73327D01*
X144140Y73637D01*
X143948Y73895D01*
X143603Y74050D01*
X143258Y73998D01*
X142913Y73792D01*
G01X146550Y70950D02*
Y74050D01*
X146090Y73430D01*
G01Y70950D02*
X147010D01*
G01X148807Y71570D02*
X149037Y71208D01*
X149343Y71002D01*
X149688Y70950D01*
X149995Y71002D01*
X150302Y71260D01*
X150493Y71570D01*
X150532Y71880D01*
X150455Y72242D01*
X150187Y72500D01*
X149918Y72603D01*
X149573D01*
G01X149918D02*
X150148Y72758D01*
X150340Y73017D01*
X150417Y73327D01*
X150340Y73637D01*
X150148Y73895D01*
X149803Y74050D01*
X149458Y73998D01*
X149113Y73792D01*
G01X137903Y122050D02*
Y125150D01*
X138900Y122567D01*
X139897Y125150D01*
Y122050D01*
G01X142767D02*
X141233D01*
Y125150D01*
X142767D01*
G01X142153Y123652D02*
X141233D01*
G01X145023Y122050D02*
X145100Y122722D01*
X145215Y123290D01*
X145368Y123807D01*
X145560Y124375D01*
X145867Y125150D01*
X144333D01*
G01X134903Y282950D02*
Y286050D01*
X135900Y283467D01*
X136897Y286050D01*
Y282950D01*
G01X139767D02*
X138233D01*
Y286050D01*
X139767D01*
G01X139153Y284552D02*
X138233D01*
G01X141257Y283415D02*
X141487Y283157D01*
X141755Y283002D01*
X142100Y282950D01*
X142445Y283053D01*
X142713Y283260D01*
X142905Y283622D01*
X142943Y284035D01*
X142867Y284448D01*
X142675Y284707D01*
X142407Y284913D01*
X142138Y284965D01*
X141870Y284913D01*
X141525Y284707D01*
X141640Y286050D01*
X142675D01*
G01X132708Y295193D02*
X132553Y294963D01*
X132450Y294695D01*
Y294388D01*
X132605Y294043D01*
X132863Y293775D01*
X133173Y293583D01*
X133690Y293430D01*
X134155Y293392D01*
X134620Y293468D01*
X134930Y293583D01*
X135240Y293813D01*
X135447Y294082D01*
X135550Y294350D01*
Y294618D01*
X135447Y294887D01*
X135292Y295117D01*
X135085Y295308D01*
G01X134930Y296607D02*
X135292Y296837D01*
X135498Y297143D01*
X135550Y297488D01*
X135498Y297795D01*
X135240Y298102D01*
X134930Y298293D01*
X134620Y298332D01*
X134258Y298255D01*
X134000Y297987D01*
X133897Y297718D01*
Y297373D01*
G01Y297718D02*
X133742Y297948D01*
X133483Y298140D01*
X133173Y298217D01*
X132863Y298140D01*
X132605Y297948D01*
X132450Y297603D01*
X132502Y297258D01*
X132708Y296913D01*
G01X132450Y300550D02*
X132553Y300243D01*
X132812Y300013D01*
X133122Y299860D01*
X133535Y299745D01*
X134000Y299707D01*
X134465Y299745D01*
X134878Y299860D01*
X135188Y300013D01*
X135447Y300243D01*
X135550Y300550D01*
X135447Y300857D01*
X135188Y301087D01*
X134878Y301240D01*
X134465Y301355D01*
X134000Y301393D01*
X133535Y301355D01*
X133122Y301240D01*
X132812Y301087D01*
X132553Y300857D01*
X132450Y300550D01*
G01X135550Y303650D02*
X135498Y303918D01*
X135343Y304225D01*
X135085Y304417D01*
X134723Y304493D01*
X134362Y304417D01*
X134052Y304187D01*
X133897Y303842D01*
Y303458D01*
X133793Y303228D01*
X133535Y303037D01*
X133173Y302960D01*
X132812Y303075D01*
X132553Y303343D01*
X132450Y303650D01*
X132553Y303957D01*
X132812Y304225D01*
X133173Y304340D01*
X133535Y304263D01*
X133793Y304072D01*
X133897Y303842D01*
Y303458D01*
X134052Y303113D01*
X134362Y302883D01*
X134723Y302807D01*
X135085Y302883D01*
X135343Y303075D01*
X135498Y303382D01*
X135550Y303650D01*
G01X147083Y288450D02*
Y291550D01*
X148042D01*
X148348Y291395D01*
X148540Y291188D01*
X148617Y290775D01*
X148540Y290362D01*
X148310Y290103D01*
X148042Y289948D01*
X147083D01*
G01X148042D02*
X148617Y288450D01*
G01X151410D02*
Y291550D01*
X149992Y289328D01*
X151908D01*
G01X154050Y288450D02*
X154318Y288502D01*
X154625Y288657D01*
X154817Y288915D01*
X154893Y289277D01*
X154817Y289638D01*
X154587Y289948D01*
X154242Y290103D01*
X153858D01*
X153628Y290207D01*
X153437Y290465D01*
X153360Y290827D01*
X153475Y291188D01*
X153743Y291447D01*
X154050Y291550D01*
X154357Y291447D01*
X154625Y291188D01*
X154740Y290827D01*
X154663Y290465D01*
X154472Y290207D01*
X154242Y290103D01*
X153858D01*
X153513Y289948D01*
X153283Y289638D01*
X153207Y289277D01*
X153283Y288915D01*
X153475Y288657D01*
X153782Y288502D01*
X154050Y288450D01*
G01X156498Y288812D02*
X156767Y288553D01*
X157073Y288450D01*
X157380Y288553D01*
X157648Y288863D01*
X157840Y289328D01*
X157917Y289793D01*
Y290362D01*
X157840Y290827D01*
X157648Y291240D01*
X157418Y291447D01*
X157150Y291550D01*
X156843Y291447D01*
X156613Y291240D01*
X156460Y290930D01*
X156383Y290517D01*
X156460Y290155D01*
X156652Y289793D01*
X156882Y289587D01*
X157150Y289535D01*
X157457Y289638D01*
X157687Y289897D01*
X157917Y290362D01*
G01X139550Y293583D02*
X136450D01*
Y294542D01*
X136605Y294848D01*
X136812Y295040D01*
X137225Y295117D01*
X137638Y295040D01*
X137897Y294810D01*
X138052Y294542D01*
Y293583D01*
G01Y294542D02*
X139550Y295117D01*
G01Y297910D02*
X136450D01*
X138672Y296492D01*
Y298408D01*
G01X139188Y299898D02*
X139447Y300167D01*
X139550Y300473D01*
X139447Y300780D01*
X139137Y301048D01*
X138672Y301240D01*
X138207Y301317D01*
X137638D01*
X137173Y301240D01*
X136760Y301048D01*
X136553Y300818D01*
X136450Y300550D01*
X136553Y300243D01*
X136760Y300013D01*
X137070Y299860D01*
X137483Y299783D01*
X137845Y299860D01*
X138207Y300052D01*
X138413Y300282D01*
X138465Y300550D01*
X138362Y300857D01*
X138103Y301087D01*
X137638Y301317D01*
G01X136450Y303650D02*
X136553Y303343D01*
X136812Y303113D01*
X137122Y302960D01*
X137535Y302845D01*
X138000Y302807D01*
X138465Y302845D01*
X138878Y302960D01*
X139188Y303113D01*
X139447Y303343D01*
X139550Y303650D01*
X139447Y303957D01*
X139188Y304187D01*
X138878Y304340D01*
X138465Y304455D01*
X138000Y304493D01*
X137535Y304455D01*
X137122Y304340D01*
X136812Y304187D01*
X136553Y303957D01*
X136450Y303650D01*
G01X142250Y316220D02*
X139750D01*
X141542Y315233D01*
Y316567D01*
G01X141958Y317647D02*
X142167Y317833D01*
X142250Y318047D01*
X142167Y318260D01*
X141917Y318447D01*
X141542Y318580D01*
X141167Y318633D01*
X140708D01*
X140333Y318580D01*
X140000Y318447D01*
X139833Y318287D01*
X139750Y318100D01*
X139833Y317887D01*
X140000Y317727D01*
X140250Y317620D01*
X140583Y317567D01*
X140875Y317620D01*
X141167Y317753D01*
X141333Y317913D01*
X141375Y318100D01*
X141292Y318313D01*
X141083Y318473D01*
X140708Y318633D01*
G01X149208Y328693D02*
X149053Y328463D01*
X148950Y328195D01*
Y327888D01*
X149105Y327543D01*
X149363Y327275D01*
X149673Y327083D01*
X150190Y326930D01*
X150655Y326892D01*
X151120Y326968D01*
X151430Y327083D01*
X151740Y327313D01*
X151947Y327582D01*
X152050Y327850D01*
Y328118D01*
X151947Y328387D01*
X151792Y328617D01*
X151585Y328808D01*
G01X151430Y330107D02*
X151792Y330337D01*
X151998Y330643D01*
X152050Y330988D01*
X151998Y331295D01*
X151740Y331602D01*
X151430Y331793D01*
X151120Y331832D01*
X150758Y331755D01*
X150500Y331487D01*
X150397Y331218D01*
Y330873D01*
G01Y331218D02*
X150242Y331448D01*
X149983Y331640D01*
X149673Y331717D01*
X149363Y331640D01*
X149105Y331448D01*
X148950Y331103D01*
X149002Y330758D01*
X149208Y330413D01*
G01X148950Y334050D02*
X149053Y333743D01*
X149312Y333513D01*
X149622Y333360D01*
X150035Y333245D01*
X150500Y333207D01*
X150965Y333245D01*
X151378Y333360D01*
X151688Y333513D01*
X151947Y333743D01*
X152050Y334050D01*
X151947Y334357D01*
X151688Y334587D01*
X151378Y334740D01*
X150965Y334855D01*
X150500Y334893D01*
X150035Y334855D01*
X149622Y334740D01*
X149312Y334587D01*
X149053Y334357D01*
X148950Y334050D01*
G01X151688Y336498D02*
X151947Y336767D01*
X152050Y337073D01*
X151947Y337380D01*
X151637Y337648D01*
X151172Y337840D01*
X150707Y337917D01*
X150138D01*
X149673Y337840D01*
X149260Y337648D01*
X149053Y337418D01*
X148950Y337150D01*
X149053Y336843D01*
X149260Y336613D01*
X149570Y336460D01*
X149983Y336383D01*
X150345Y336460D01*
X150707Y336652D01*
X150913Y336882D01*
X150965Y337150D01*
X150862Y337457D01*
X150603Y337687D01*
X150138Y337917D01*
G01X143950Y323133D02*
X147050D01*
Y324667D01*
G01X144467Y326272D02*
X144157Y326502D01*
X144002Y326770D01*
X143950Y327077D01*
X144053Y327460D01*
X144312Y327728D01*
X144622Y327805D01*
X144932Y327767D01*
X145190Y327613D01*
X145707Y326847D01*
X146068Y326502D01*
X146585Y326272D01*
X147050Y326195D01*
Y327805D01*
G01Y330560D02*
X143950D01*
X146172Y329142D01*
Y331058D01*
G01X142450Y336557D02*
X144672D01*
X145137Y336710D01*
X145447Y337017D01*
X145550Y337400D01*
X145447Y337783D01*
X145137Y338090D01*
X144672Y338243D01*
X142450D01*
G01X145550Y340500D02*
X142450D01*
X143070Y340040D01*
G01X145550D02*
Y340960D01*
G01Y343600D02*
X145498Y343868D01*
X145343Y344175D01*
X145085Y344367D01*
X144723Y344443D01*
X144362Y344367D01*
X144052Y344137D01*
X143897Y343792D01*
Y343408D01*
X143793Y343178D01*
X143535Y342987D01*
X143173Y342910D01*
X142812Y343025D01*
X142553Y343293D01*
X142450Y343600D01*
X142553Y343907D01*
X142812Y344175D01*
X143173Y344290D01*
X143535Y344213D01*
X143793Y344022D01*
X143897Y343792D01*
Y343408D01*
X144052Y343063D01*
X144362Y342833D01*
X144723Y342757D01*
X145085Y342833D01*
X145343Y343025D01*
X145498Y343332D01*
X145550Y343600D01*
G01X150243Y359292D02*
X150013Y359447D01*
X149745Y359550D01*
X149438D01*
X149093Y359395D01*
X148825Y359137D01*
X148633Y358827D01*
X148480Y358310D01*
X148442Y357845D01*
X148518Y357380D01*
X148633Y357070D01*
X148863Y356760D01*
X149132Y356553D01*
X149400Y356450D01*
X149668D01*
X149937Y356553D01*
X150167Y356708D01*
X150358Y356915D01*
G01X152423Y356450D02*
X152500Y357122D01*
X152615Y357690D01*
X152768Y358207D01*
X152960Y358775D01*
X153267Y359550D01*
X151733D01*
G01X156060Y356450D02*
Y359550D01*
X154642Y357328D01*
X156558D01*
G01X142393Y352492D02*
X142580Y352783D01*
X142740Y352950D01*
X142953Y353033D01*
X143140Y352950D01*
X143273Y352783D01*
X143380Y352533D01*
X143407Y352242D01*
X143380Y351992D01*
X143273Y351742D01*
X143113Y351533D01*
X142927Y351450D01*
X142713Y351533D01*
X142527Y351783D01*
X142420Y352158D01*
X142393Y352575D01*
X142447Y353117D01*
X142527Y353408D01*
X142660Y353700D01*
X142847Y353908D01*
X143033Y353950D01*
X143220Y353867D01*
X143353Y353658D01*
G01X145420Y351450D02*
Y353950D01*
X144433Y352158D01*
X145767D01*
G01X133208Y372743D02*
X133053Y372513D01*
X132950Y372245D01*
Y371938D01*
X133105Y371593D01*
X133363Y371325D01*
X133673Y371133D01*
X134190Y370980D01*
X134655Y370942D01*
X135120Y371018D01*
X135430Y371133D01*
X135740Y371363D01*
X135947Y371632D01*
X136050Y371900D01*
Y372168D01*
X135947Y372437D01*
X135792Y372667D01*
X135585Y372858D01*
G01X136050Y375000D02*
X135998Y375268D01*
X135843Y375575D01*
X135585Y375767D01*
X135223Y375843D01*
X134862Y375767D01*
X134552Y375537D01*
X134397Y375192D01*
Y374808D01*
X134293Y374578D01*
X134035Y374387D01*
X133673Y374310D01*
X133312Y374425D01*
X133053Y374693D01*
X132950Y375000D01*
X133053Y375307D01*
X133312Y375575D01*
X133673Y375690D01*
X134035Y375613D01*
X134293Y375422D01*
X134397Y375192D01*
Y374808D01*
X134552Y374463D01*
X134862Y374233D01*
X135223Y374157D01*
X135585Y374233D01*
X135843Y374425D01*
X135998Y374732D01*
X136050Y375000D01*
G01Y378023D02*
X135378Y378100D01*
X134810Y378215D01*
X134293Y378368D01*
X133725Y378560D01*
X132950Y378867D01*
Y377333D01*
G01X137208Y372743D02*
X137053Y372513D01*
X136950Y372245D01*
Y371938D01*
X137105Y371593D01*
X137363Y371325D01*
X137673Y371133D01*
X138190Y370980D01*
X138655Y370942D01*
X139120Y371018D01*
X139430Y371133D01*
X139740Y371363D01*
X139947Y371632D01*
X140050Y371900D01*
Y372168D01*
X139947Y372437D01*
X139792Y372667D01*
X139585Y372858D01*
G01X140050Y375000D02*
X139998Y375268D01*
X139843Y375575D01*
X139585Y375767D01*
X139223Y375843D01*
X138862Y375767D01*
X138552Y375537D01*
X138397Y375192D01*
Y374808D01*
X138293Y374578D01*
X138035Y374387D01*
X137673Y374310D01*
X137312Y374425D01*
X137053Y374693D01*
X136950Y375000D01*
X137053Y375307D01*
X137312Y375575D01*
X137673Y375690D01*
X138035Y375613D01*
X138293Y375422D01*
X138397Y375192D01*
Y374808D01*
X138552Y374463D01*
X138862Y374233D01*
X139223Y374157D01*
X139585Y374233D01*
X139843Y374425D01*
X139998Y374732D01*
X140050Y375000D01*
G01X138758Y377372D02*
X138397Y377640D01*
X138190Y377870D01*
X138087Y378177D01*
X138190Y378445D01*
X138397Y378637D01*
X138707Y378790D01*
X139068Y378828D01*
X139378Y378790D01*
X139688Y378637D01*
X139947Y378407D01*
X140050Y378138D01*
X139947Y377832D01*
X139637Y377563D01*
X139172Y377410D01*
X138655Y377372D01*
X137983Y377448D01*
X137622Y377563D01*
X137260Y377755D01*
X137002Y378023D01*
X136950Y378292D01*
X137053Y378560D01*
X137312Y378752D01*
G01X150243Y366792D02*
X150013Y366947D01*
X149745Y367050D01*
X149438D01*
X149093Y366895D01*
X148825Y366637D01*
X148633Y366327D01*
X148480Y365810D01*
X148442Y365345D01*
X148518Y364880D01*
X148633Y364570D01*
X148863Y364260D01*
X149132Y364053D01*
X149400Y363950D01*
X149668D01*
X149937Y364053D01*
X150167Y364208D01*
X150358Y364415D01*
G01X152423Y363950D02*
X152500Y364622D01*
X152615Y365190D01*
X152768Y365707D01*
X152960Y366275D01*
X153267Y367050D01*
X151733D01*
G01X154757Y364415D02*
X154987Y364157D01*
X155255Y364002D01*
X155600Y363950D01*
X155945Y364053D01*
X156213Y364260D01*
X156405Y364622D01*
X156443Y365035D01*
X156367Y365448D01*
X156175Y365707D01*
X155907Y365913D01*
X155638Y365965D01*
X155370Y365913D01*
X155025Y365707D01*
X155140Y367050D01*
X156175D01*
G01X148773Y360330D02*
Y363430D01*
X149732D01*
X150038Y363275D01*
X150230Y363068D01*
X150307Y362655D01*
X150230Y362242D01*
X150000Y361983D01*
X149732Y361828D01*
X148773D01*
G01X149732D02*
X150307Y360330D01*
G01X151912Y362913D02*
X152142Y363223D01*
X152410Y363378D01*
X152717Y363430D01*
X153100Y363327D01*
X153368Y363068D01*
X153445Y362758D01*
X153407Y362448D01*
X153253Y362190D01*
X152487Y361673D01*
X152142Y361312D01*
X151912Y360795D01*
X151835Y360330D01*
X153445D01*
G01X155088Y360692D02*
X155357Y360433D01*
X155663Y360330D01*
X155970Y360433D01*
X156238Y360743D01*
X156430Y361208D01*
X156507Y361673D01*
Y362242D01*
X156430Y362707D01*
X156238Y363120D01*
X156008Y363327D01*
X155740Y363430D01*
X155433Y363327D01*
X155203Y363120D01*
X155050Y362810D01*
X154973Y362397D01*
X155050Y362035D01*
X155242Y361673D01*
X155472Y361467D01*
X155740Y361415D01*
X156047Y361518D01*
X156277Y361777D01*
X156507Y362242D01*
G01X159300Y360330D02*
Y363430D01*
X157882Y361208D01*
X159798D01*
G01X136460Y378950D02*
Y382050D01*
X135042Y379828D01*
X136958D01*
G01X145633Y418950D02*
Y422050D01*
X146592D01*
X146898Y421895D01*
X147090Y421688D01*
X147167Y421275D01*
X147090Y420862D01*
X146860Y420603D01*
X146592Y420448D01*
X145633D01*
G01X146592D02*
X147167Y418950D01*
G01X148772Y421533D02*
X149002Y421843D01*
X149270Y421998D01*
X149577Y422050D01*
X149960Y421947D01*
X150228Y421688D01*
X150305Y421378D01*
X150267Y421068D01*
X150113Y420810D01*
X149347Y420293D01*
X149002Y419932D01*
X148772Y419415D01*
X148695Y418950D01*
X150305D01*
G01X151948Y419312D02*
X152217Y419053D01*
X152523Y418950D01*
X152830Y419053D01*
X153098Y419363D01*
X153290Y419828D01*
X153367Y420293D01*
Y420862D01*
X153290Y421327D01*
X153098Y421740D01*
X152868Y421947D01*
X152600Y422050D01*
X152293Y421947D01*
X152063Y421740D01*
X151910Y421430D01*
X151833Y421017D01*
X151910Y420655D01*
X152102Y420293D01*
X152332Y420087D01*
X152600Y420035D01*
X152907Y420138D01*
X153137Y420397D01*
X153367Y420862D01*
G01X154208Y49743D02*
X154053Y49513D01*
X153950Y49245D01*
Y48938D01*
X154105Y48593D01*
X154363Y48325D01*
X154673Y48133D01*
X155190Y47980D01*
X155655Y47942D01*
X156120Y48018D01*
X156430Y48133D01*
X156740Y48363D01*
X156947Y48632D01*
X157050Y48900D01*
Y49168D01*
X156947Y49437D01*
X156792Y49667D01*
X156585Y49858D01*
G01X157050Y52000D02*
X153950D01*
X154570Y51540D01*
G01X157050D02*
Y52460D01*
G01Y55023D02*
X156378Y55100D01*
X155810Y55215D01*
X155293Y55368D01*
X154725Y55560D01*
X153950Y55867D01*
Y54333D01*
G01X160070Y57400D02*
X160338Y57452D01*
X160645Y57607D01*
X160837Y57865D01*
X160913Y58227D01*
X160837Y58588D01*
X160607Y58898D01*
X160262Y59053D01*
X159878D01*
X159648Y59157D01*
X159457Y59415D01*
X159380Y59777D01*
X159495Y60138D01*
X159763Y60397D01*
X160070Y60500D01*
X160377Y60397D01*
X160645Y60138D01*
X160760Y59777D01*
X160683Y59415D01*
X160492Y59157D01*
X160262Y59053D01*
X159878D01*
X159533Y58898D01*
X159303Y58588D01*
X159227Y58227D01*
X159303Y57865D01*
X159495Y57607D01*
X159802Y57452D01*
X160070Y57400D01*
G01X159657Y77415D02*
X159887Y77157D01*
X160155Y77002D01*
X160500Y76950D01*
X160845Y77053D01*
X161113Y77260D01*
X161305Y77622D01*
X161343Y78035D01*
X161267Y78448D01*
X161075Y78707D01*
X160807Y78913D01*
X160538Y78965D01*
X160270Y78913D01*
X159925Y78707D01*
X160040Y80050D01*
X161075D01*
G01X160557Y292050D02*
Y289828D01*
X160710Y289363D01*
X161017Y289053D01*
X161400Y288950D01*
X161783Y289053D01*
X162090Y289363D01*
X162243Y289828D01*
Y292050D01*
G01X164960Y288950D02*
Y292050D01*
X163542Y289828D01*
X165458D01*
G01X167600Y288950D02*
Y292050D01*
X167140Y291430D01*
G01Y288950D02*
X168060D01*
G01X156289Y296087D02*
X156449Y295879D01*
X156636Y295754D01*
X156876Y295712D01*
X157116Y295795D01*
X157303Y295962D01*
X157436Y296254D01*
X157463Y296587D01*
X157409Y296920D01*
X157276Y297129D01*
X157089Y297295D01*
X156903Y297337D01*
X156716Y297295D01*
X156476Y297129D01*
X156556Y298212D01*
X157276D01*
G01X153542Y317950D02*
X154500Y321050D01*
X155458Y317950D01*
G01X155113Y319035D02*
X153887D01*
G01X153042Y329950D02*
X154000Y333050D01*
X154958Y329950D01*
G01X154613Y331035D02*
X153387D01*
G01X159243Y340292D02*
X159013Y340447D01*
X158745Y340550D01*
X158438D01*
X158093Y340395D01*
X157825Y340137D01*
X157633Y339827D01*
X157480Y339310D01*
X157442Y338845D01*
X157518Y338380D01*
X157633Y338070D01*
X157863Y337760D01*
X158132Y337553D01*
X158400Y337450D01*
X158668D01*
X158937Y337553D01*
X159167Y337708D01*
X159358Y337915D01*
G01X160733Y337450D02*
Y340550D01*
X161692D01*
X161998Y340395D01*
X162190Y340188D01*
X162267Y339775D01*
X162190Y339362D01*
X161960Y339103D01*
X161692Y338948D01*
X160733D01*
G01X161692D02*
X162267Y337450D01*
G01X164600D02*
Y340550D01*
X164140Y339930D01*
G01Y337450D02*
X165060D01*
G01X159243Y335792D02*
X159013Y335947D01*
X158745Y336050D01*
X158438D01*
X158093Y335895D01*
X157825Y335637D01*
X157633Y335327D01*
X157480Y334810D01*
X157442Y334345D01*
X157518Y333880D01*
X157633Y333570D01*
X157863Y333260D01*
X158132Y333053D01*
X158400Y332950D01*
X158668D01*
X158937Y333053D01*
X159167Y333208D01*
X159358Y333415D01*
G01X160733Y332950D02*
Y336050D01*
X161692D01*
X161998Y335895D01*
X162190Y335688D01*
X162267Y335275D01*
X162190Y334862D01*
X161960Y334603D01*
X161692Y334448D01*
X160733D01*
G01X161692D02*
X162267Y332950D01*
G01X163872Y335533D02*
X164102Y335843D01*
X164370Y335998D01*
X164677Y336050D01*
X165060Y335947D01*
X165328Y335688D01*
X165405Y335378D01*
X165367Y335068D01*
X165213Y334810D01*
X164447Y334293D01*
X164102Y333932D01*
X163872Y333415D01*
X163795Y332950D01*
X165405D01*
G01X155683Y373550D02*
Y370450D01*
X157217D01*
G01X159473D02*
X159550Y371122D01*
X159665Y371690D01*
X159818Y372207D01*
X160010Y372775D01*
X160317Y373550D01*
X158783D01*
G01X155250Y386400D02*
X152750D01*
X153250Y386080D01*
G01X155250D02*
Y386720D01*
G01Y388600D02*
X155208Y388787D01*
X155083Y389000D01*
X154875Y389133D01*
X154583Y389187D01*
X154292Y389133D01*
X154042Y388973D01*
X153917Y388733D01*
Y388467D01*
X153833Y388307D01*
X153625Y388173D01*
X153333Y388120D01*
X153042Y388200D01*
X152833Y388387D01*
X152750Y388600D01*
X152833Y388813D01*
X153042Y389000D01*
X153333Y389080D01*
X153625Y389027D01*
X153833Y388893D01*
X153917Y388733D01*
Y388467D01*
X154042Y388227D01*
X154292Y388067D01*
X154583Y388013D01*
X154875Y388067D01*
X155083Y388200D01*
X155208Y388413D01*
X155250Y388600D01*
G01X154750Y401900D02*
X152250D01*
X152750Y401580D01*
G01X154750D02*
Y402220D01*
G01X154250Y403513D02*
X154542Y403673D01*
X154708Y403887D01*
X154750Y404127D01*
X154708Y404340D01*
X154500Y404553D01*
X154250Y404687D01*
X154000Y404713D01*
X153708Y404660D01*
X153500Y404473D01*
X153417Y404287D01*
Y404047D01*
G01Y404287D02*
X153292Y404447D01*
X153083Y404580D01*
X152833Y404633D01*
X152583Y404580D01*
X152375Y404447D01*
X152250Y404207D01*
X152292Y403967D01*
X152458Y403727D01*
G01X159400Y406250D02*
Y408750D01*
X159080Y408250D01*
G01Y406250D02*
X159720D01*
G01X161093Y408333D02*
X161253Y408583D01*
X161440Y408708D01*
X161653Y408750D01*
X161920Y408667D01*
X162107Y408458D01*
X162160Y408208D01*
X162133Y407958D01*
X162027Y407750D01*
X161493Y407333D01*
X161253Y407042D01*
X161093Y406625D01*
X161040Y406250D01*
X162160D01*
G01X177507Y82550D02*
Y80328D01*
X177660Y79863D01*
X177967Y79553D01*
X178350Y79450D01*
X178733Y79553D01*
X179040Y79863D01*
X179193Y80328D01*
Y82550D01*
G01X180722Y82033D02*
X180952Y82343D01*
X181220Y82498D01*
X181527Y82550D01*
X181910Y82447D01*
X182178Y82188D01*
X182255Y81878D01*
X182217Y81568D01*
X182063Y81310D01*
X181297Y80793D01*
X180952Y80432D01*
X180722Y79915D01*
X180645Y79450D01*
X182255D01*
G01X171193Y286792D02*
X170963Y286947D01*
X170695Y287050D01*
X170388D01*
X170043Y286895D01*
X169775Y286637D01*
X169583Y286327D01*
X169430Y285810D01*
X169392Y285345D01*
X169468Y284880D01*
X169583Y284570D01*
X169813Y284260D01*
X170082Y284053D01*
X170350Y283950D01*
X170618D01*
X170887Y284053D01*
X171117Y284208D01*
X171308Y284415D01*
G01X172607Y284570D02*
X172837Y284208D01*
X173143Y284002D01*
X173488Y283950D01*
X173795Y284002D01*
X174102Y284260D01*
X174293Y284570D01*
X174332Y284880D01*
X174255Y285242D01*
X173987Y285500D01*
X173718Y285603D01*
X173373D01*
G01X173718D02*
X173948Y285758D01*
X174140Y286017D01*
X174217Y286327D01*
X174140Y286637D01*
X173948Y286895D01*
X173603Y287050D01*
X173258Y286998D01*
X172913Y286792D01*
G01X176550Y287050D02*
X176243Y286947D01*
X176013Y286688D01*
X175860Y286378D01*
X175745Y285965D01*
X175707Y285500D01*
X175745Y285035D01*
X175860Y284622D01*
X176013Y284312D01*
X176243Y284053D01*
X176550Y283950D01*
X176857Y284053D01*
X177087Y284312D01*
X177240Y284622D01*
X177355Y285035D01*
X177393Y285500D01*
X177355Y285965D01*
X177240Y286378D01*
X177087Y286688D01*
X176857Y286947D01*
X176550Y287050D01*
G01X179573Y283950D02*
X179650Y284622D01*
X179765Y285190D01*
X179918Y285707D01*
X180110Y286275D01*
X180417Y287050D01*
X178883D01*
G01X177993Y297292D02*
X178180Y297583D01*
X178340Y297750D01*
X178553Y297833D01*
X178740Y297750D01*
X178873Y297583D01*
X178980Y297333D01*
X179007Y297042D01*
X178980Y296792D01*
X178873Y296542D01*
X178713Y296333D01*
X178527Y296250D01*
X178313Y296333D01*
X178127Y296583D01*
X178020Y296958D01*
X177993Y297375D01*
X178047Y297917D01*
X178127Y298208D01*
X178260Y298500D01*
X178447Y298708D01*
X178633Y298750D01*
X178820Y298667D01*
X178953Y298458D01*
G01X179750Y303400D02*
X177250D01*
X177750Y303080D01*
G01X179750D02*
Y303720D01*
G01X177250Y305600D02*
X177333Y305387D01*
X177542Y305227D01*
X177792Y305120D01*
X178125Y305040D01*
X178500Y305013D01*
X178875Y305040D01*
X179208Y305120D01*
X179458Y305227D01*
X179667Y305387D01*
X179750Y305600D01*
X179667Y305813D01*
X179458Y305973D01*
X179208Y306080D01*
X178875Y306160D01*
X178500Y306187D01*
X178125Y306160D01*
X177792Y306080D01*
X177542Y305973D01*
X177333Y305813D01*
X177250Y305600D01*
G01X172587Y311542D02*
X172427Y311667D01*
X172240Y311750D01*
X172027D01*
X171787Y311625D01*
X171600Y311417D01*
X171467Y311167D01*
X171360Y310750D01*
X171333Y310375D01*
X171387Y310000D01*
X171467Y309750D01*
X171627Y309500D01*
X171813Y309333D01*
X172000Y309250D01*
X172187D01*
X172373Y309333D01*
X172533Y309458D01*
X172667Y309625D01*
G01X178193Y336292D02*
X177963Y336447D01*
X177695Y336550D01*
X177388D01*
X177043Y336395D01*
X176775Y336137D01*
X176583Y335827D01*
X176430Y335310D01*
X176392Y334845D01*
X176468Y334380D01*
X176583Y334070D01*
X176813Y333760D01*
X177082Y333553D01*
X177350Y333450D01*
X177618D01*
X177887Y333553D01*
X178117Y333708D01*
X178308Y333915D01*
G01X179722Y336033D02*
X179952Y336343D01*
X180220Y336498D01*
X180527Y336550D01*
X180910Y336447D01*
X181178Y336188D01*
X181255Y335878D01*
X181217Y335568D01*
X181063Y335310D01*
X180297Y334793D01*
X179952Y334432D01*
X179722Y333915D01*
X179645Y333450D01*
X181255D01*
G01X183550D02*
X183818Y333502D01*
X184125Y333657D01*
X184317Y333915D01*
X184393Y334277D01*
X184317Y334638D01*
X184087Y334948D01*
X183742Y335103D01*
X183358D01*
X183128Y335207D01*
X182937Y335465D01*
X182860Y335827D01*
X182975Y336188D01*
X183243Y336447D01*
X183550Y336550D01*
X183857Y336447D01*
X184125Y336188D01*
X184240Y335827D01*
X184163Y335465D01*
X183972Y335207D01*
X183742Y335103D01*
X183358D01*
X183013Y334948D01*
X182783Y334638D01*
X182707Y334277D01*
X182783Y333915D01*
X182975Y333657D01*
X183282Y333502D01*
X183550Y333450D01*
G01X187110D02*
Y336550D01*
X185692Y334328D01*
X187608D01*
G01X174087Y331242D02*
X173927Y331367D01*
X173740Y331450D01*
X173527D01*
X173287Y331325D01*
X173100Y331117D01*
X172967Y330867D01*
X172860Y330450D01*
X172833Y330075D01*
X172887Y329700D01*
X172967Y329450D01*
X173127Y329200D01*
X173313Y329033D01*
X173500Y328950D01*
X173687D01*
X173873Y329033D01*
X174033Y329158D01*
X174167Y329325D01*
G01X169343Y367492D02*
X169113Y367647D01*
X168845Y367750D01*
X168538D01*
X168193Y367595D01*
X167925Y367337D01*
X167733Y367027D01*
X167580Y366510D01*
X167542Y366045D01*
X167618Y365580D01*
X167733Y365270D01*
X167963Y364960D01*
X168232Y364753D01*
X168500Y364650D01*
X168768D01*
X169037Y364753D01*
X169267Y364908D01*
X169458Y365115D01*
G01X172060Y364650D02*
Y367750D01*
X170642Y365528D01*
X172558D01*
G01X174700Y364650D02*
Y367750D01*
X174240Y367130D01*
G01Y364650D02*
X175160D01*
G01X169343Y363092D02*
X169113Y363247D01*
X168845Y363350D01*
X168538D01*
X168193Y363195D01*
X167925Y362937D01*
X167733Y362627D01*
X167580Y362110D01*
X167542Y361645D01*
X167618Y361180D01*
X167733Y360870D01*
X167963Y360560D01*
X168232Y360353D01*
X168500Y360250D01*
X168768D01*
X169037Y360353D01*
X169267Y360508D01*
X169458Y360715D01*
G01X170757Y360870D02*
X170987Y360508D01*
X171293Y360302D01*
X171638Y360250D01*
X171945Y360302D01*
X172252Y360560D01*
X172443Y360870D01*
X172482Y361180D01*
X172405Y361542D01*
X172137Y361800D01*
X171868Y361903D01*
X171523D01*
G01X171868D02*
X172098Y362058D01*
X172290Y362317D01*
X172367Y362627D01*
X172290Y362937D01*
X172098Y363195D01*
X171753Y363350D01*
X171408Y363298D01*
X171063Y363092D01*
G01X173972Y362833D02*
X174202Y363143D01*
X174470Y363298D01*
X174777Y363350D01*
X175160Y363247D01*
X175428Y362988D01*
X175505Y362678D01*
X175467Y362368D01*
X175313Y362110D01*
X174547Y361593D01*
X174202Y361232D01*
X173972Y360715D01*
X173895Y360250D01*
X175505D01*
G01X168107Y372050D02*
Y369828D01*
X168260Y369363D01*
X168567Y369053D01*
X168950Y368950D01*
X169333Y369053D01*
X169640Y369363D01*
X169793Y369828D01*
Y372050D01*
G01X171207Y369415D02*
X171437Y369157D01*
X171705Y369002D01*
X172050Y368950D01*
X172395Y369053D01*
X172663Y369260D01*
X172855Y369622D01*
X172893Y370035D01*
X172817Y370448D01*
X172625Y370707D01*
X172357Y370913D01*
X172088Y370965D01*
X171820Y370913D01*
X171475Y370707D01*
X171590Y372050D01*
X172625D01*
G01X181500Y378450D02*
Y381550D01*
X181040Y380930D01*
G01Y378450D02*
X181960D01*
G01X174613Y389325D02*
X174773Y389117D01*
X174960Y388992D01*
X175200Y388950D01*
X175440Y389033D01*
X175627Y389200D01*
X175760Y389492D01*
X175787Y389825D01*
X175733Y390158D01*
X175600Y390367D01*
X175413Y390533D01*
X175227Y390575D01*
X175040Y390533D01*
X174800Y390367D01*
X174880Y391450D01*
X175600D01*
G01X173000Y405750D02*
X173187Y405792D01*
X173400Y405917D01*
X173533Y406125D01*
X173587Y406417D01*
X173533Y406708D01*
X173373Y406958D01*
X173133Y407083D01*
X172867D01*
X172707Y407167D01*
X172573Y407375D01*
X172520Y407667D01*
X172600Y407958D01*
X172787Y408167D01*
X173000Y408250D01*
X173213Y408167D01*
X173400Y407958D01*
X173480Y407667D01*
X173427Y407375D01*
X173293Y407167D01*
X173133Y407083D01*
X172867D01*
X172627Y406958D01*
X172467Y406708D01*
X172413Y406417D01*
X172467Y406125D01*
X172600Y405917D01*
X172813Y405792D01*
X173000Y405750D01*
G01X176493Y393292D02*
X176680Y393583D01*
X176840Y393750D01*
X177053Y393833D01*
X177240Y393750D01*
X177373Y393583D01*
X177480Y393333D01*
X177507Y393042D01*
X177480Y392792D01*
X177373Y392542D01*
X177213Y392333D01*
X177027Y392250D01*
X176813Y392333D01*
X176627Y392583D01*
X176520Y392958D01*
X176493Y393375D01*
X176547Y393917D01*
X176627Y394208D01*
X176760Y394500D01*
X176947Y394708D01*
X177133Y394750D01*
X177320Y394667D01*
X177453Y394458D01*
G01X175947Y401950D02*
X176000Y402492D01*
X176080Y402950D01*
X176187Y403367D01*
X176320Y403825D01*
X176533Y404450D01*
X175467D01*
G01X180243Y416842D02*
X180013Y416997D01*
X179745Y417100D01*
X179438D01*
X179093Y416945D01*
X178825Y416687D01*
X178633Y416377D01*
X178480Y415860D01*
X178442Y415395D01*
X178518Y414930D01*
X178633Y414620D01*
X178863Y414310D01*
X179132Y414103D01*
X179400Y414000D01*
X179668D01*
X179937Y414103D01*
X180167Y414258D01*
X180358Y414465D01*
G01X181657Y414620D02*
X181887Y414258D01*
X182193Y414052D01*
X182538Y414000D01*
X182845Y414052D01*
X183152Y414310D01*
X183343Y414620D01*
X183382Y414930D01*
X183305Y415292D01*
X183037Y415550D01*
X182768Y415653D01*
X182423D01*
G01X182768D02*
X182998Y415808D01*
X183190Y416067D01*
X183267Y416377D01*
X183190Y416687D01*
X182998Y416945D01*
X182653Y417100D01*
X182308Y417048D01*
X181963Y416842D01*
G01X184757Y414620D02*
X184987Y414258D01*
X185293Y414052D01*
X185638Y414000D01*
X185945Y414052D01*
X186252Y414310D01*
X186443Y414620D01*
X186482Y414930D01*
X186405Y415292D01*
X186137Y415550D01*
X185868Y415653D01*
X185523D01*
G01X185868D02*
X186098Y415808D01*
X186290Y416067D01*
X186367Y416377D01*
X186290Y416687D01*
X186098Y416945D01*
X185753Y417100D01*
X185408Y417048D01*
X185063Y416842D01*
G01X180243Y421342D02*
X180013Y421497D01*
X179745Y421600D01*
X179438D01*
X179093Y421445D01*
X178825Y421187D01*
X178633Y420877D01*
X178480Y420360D01*
X178442Y419895D01*
X178518Y419430D01*
X178633Y419120D01*
X178863Y418810D01*
X179132Y418603D01*
X179400Y418500D01*
X179668D01*
X179937Y418603D01*
X180167Y418758D01*
X180358Y418965D01*
G01X181657Y419120D02*
X181887Y418758D01*
X182193Y418552D01*
X182538Y418500D01*
X182845Y418552D01*
X183152Y418810D01*
X183343Y419120D01*
X183382Y419430D01*
X183305Y419792D01*
X183037Y420050D01*
X182768Y420153D01*
X182423D01*
G01X182768D02*
X182998Y420308D01*
X183190Y420567D01*
X183267Y420877D01*
X183190Y421187D01*
X182998Y421445D01*
X182653Y421600D01*
X182308Y421548D01*
X181963Y421342D01*
G01X185600Y421600D02*
X185293Y421497D01*
X185063Y421238D01*
X184910Y420928D01*
X184795Y420515D01*
X184757Y420050D01*
X184795Y419585D01*
X184910Y419172D01*
X185063Y418862D01*
X185293Y418603D01*
X185600Y418500D01*
X185907Y418603D01*
X186137Y418862D01*
X186290Y419172D01*
X186405Y419585D01*
X186443Y420050D01*
X186405Y420515D01*
X186290Y420928D01*
X186137Y421238D01*
X185907Y421497D01*
X185600Y421600D01*
G01X190257Y40103D02*
X190410Y40258D01*
X190525Y40517D01*
X190602Y40878D01*
X190525Y41188D01*
X190372Y41395D01*
X190103Y41550D01*
X189068D01*
Y38450D01*
X190333D01*
X190602Y38657D01*
X190755Y38967D01*
X190832Y39328D01*
X190755Y39690D01*
X190525Y40000D01*
X190257Y40103D01*
X189068D01*
G01X193050Y38450D02*
Y41550D01*
X192590Y40930D01*
G01Y38450D02*
X193510D01*
G01X201550Y69083D02*
X198450D01*
Y70042D01*
X198605Y70348D01*
X198812Y70540D01*
X199225Y70617D01*
X199638Y70540D01*
X199897Y70310D01*
X200052Y70042D01*
Y69083D01*
G01Y70042D02*
X201550Y70617D01*
G01X200930Y72107D02*
X201292Y72337D01*
X201498Y72643D01*
X201550Y72988D01*
X201498Y73295D01*
X201240Y73602D01*
X200930Y73793D01*
X200620Y73832D01*
X200258Y73755D01*
X200000Y73487D01*
X199897Y73218D01*
Y72873D01*
G01Y73218D02*
X199742Y73448D01*
X199483Y73640D01*
X199173Y73717D01*
X198863Y73640D01*
X198605Y73448D01*
X198450Y73103D01*
X198502Y72758D01*
X198708Y72413D01*
G01X201085Y75207D02*
X201343Y75437D01*
X201498Y75705D01*
X201550Y76050D01*
X201447Y76395D01*
X201240Y76663D01*
X200878Y76855D01*
X200465Y76893D01*
X200052Y76817D01*
X199793Y76625D01*
X199587Y76357D01*
X199535Y76088D01*
X199587Y75820D01*
X199793Y75475D01*
X198450Y75590D01*
Y76625D01*
G01X201550Y79610D02*
X198450D01*
X200672Y78192D01*
Y80108D01*
G01X194960Y72950D02*
Y76050D01*
X193542Y73828D01*
X195458D01*
G01X193193Y304792D02*
X192963Y304947D01*
X192695Y305050D01*
X192388D01*
X192043Y304895D01*
X191775Y304637D01*
X191583Y304327D01*
X191430Y303810D01*
X191392Y303345D01*
X191468Y302880D01*
X191583Y302570D01*
X191813Y302260D01*
X192082Y302053D01*
X192350Y301950D01*
X192618D01*
X192887Y302053D01*
X193117Y302208D01*
X193308Y302415D01*
G01X194607Y302570D02*
X194837Y302208D01*
X195143Y302002D01*
X195488Y301950D01*
X195795Y302002D01*
X196102Y302260D01*
X196293Y302570D01*
X196332Y302880D01*
X196255Y303242D01*
X195987Y303500D01*
X195718Y303603D01*
X195373D01*
G01X195718D02*
X195948Y303758D01*
X196140Y304017D01*
X196217Y304327D01*
X196140Y304637D01*
X195948Y304895D01*
X195603Y305050D01*
X195258Y304998D01*
X194913Y304792D01*
G01X198550Y305050D02*
X198243Y304947D01*
X198013Y304688D01*
X197860Y304378D01*
X197745Y303965D01*
X197707Y303500D01*
X197745Y303035D01*
X197860Y302622D01*
X198013Y302312D01*
X198243Y302053D01*
X198550Y301950D01*
X198857Y302053D01*
X199087Y302312D01*
X199240Y302622D01*
X199355Y303035D01*
X199393Y303500D01*
X199355Y303965D01*
X199240Y304378D01*
X199087Y304688D01*
X198857Y304947D01*
X198550Y305050D01*
G01X202110Y301950D02*
Y305050D01*
X200692Y302828D01*
X202608D01*
G01X195708Y290693D02*
X195553Y290463D01*
X195450Y290195D01*
Y289888D01*
X195605Y289543D01*
X195863Y289275D01*
X196173Y289083D01*
X196690Y288930D01*
X197155Y288892D01*
X197620Y288968D01*
X197930Y289083D01*
X198240Y289313D01*
X198447Y289582D01*
X198550Y289850D01*
Y290118D01*
X198447Y290387D01*
X198292Y290617D01*
X198085Y290808D01*
G01X197930Y292107D02*
X198292Y292337D01*
X198498Y292643D01*
X198550Y292988D01*
X198498Y293295D01*
X198240Y293602D01*
X197930Y293793D01*
X197620Y293832D01*
X197258Y293755D01*
X197000Y293487D01*
X196897Y293218D01*
Y292873D01*
G01Y293218D02*
X196742Y293448D01*
X196483Y293640D01*
X196173Y293717D01*
X195863Y293640D01*
X195605Y293448D01*
X195450Y293103D01*
X195502Y292758D01*
X195708Y292413D01*
G01X195450Y296050D02*
X195553Y295743D01*
X195812Y295513D01*
X196122Y295360D01*
X196535Y295245D01*
X197000Y295207D01*
X197465Y295245D01*
X197878Y295360D01*
X198188Y295513D01*
X198447Y295743D01*
X198550Y296050D01*
X198447Y296357D01*
X198188Y296587D01*
X197878Y296740D01*
X197465Y296855D01*
X197000Y296893D01*
X196535Y296855D01*
X196122Y296740D01*
X195812Y296587D01*
X195553Y296357D01*
X195450Y296050D01*
G01X195967Y298422D02*
X195657Y298652D01*
X195502Y298920D01*
X195450Y299227D01*
X195553Y299610D01*
X195812Y299878D01*
X196122Y299955D01*
X196432Y299917D01*
X196690Y299763D01*
X197207Y298997D01*
X197568Y298652D01*
X198085Y298422D01*
X198550Y298345D01*
Y299955D01*
G01X194550Y289083D02*
X191450D01*
Y290042D01*
X191605Y290348D01*
X191812Y290540D01*
X192225Y290617D01*
X192638Y290540D01*
X192897Y290310D01*
X193052Y290042D01*
Y289083D01*
G01Y290042D02*
X194550Y290617D01*
G01Y293410D02*
X191450D01*
X193672Y291992D01*
Y293908D01*
G01X194550Y296050D02*
X194498Y296318D01*
X194343Y296625D01*
X194085Y296817D01*
X193723Y296893D01*
X193362Y296817D01*
X193052Y296587D01*
X192897Y296242D01*
Y295858D01*
X192793Y295628D01*
X192535Y295437D01*
X192173Y295360D01*
X191812Y295475D01*
X191553Y295743D01*
X191450Y296050D01*
X191553Y296357D01*
X191812Y296625D01*
X192173Y296740D01*
X192535Y296663D01*
X192793Y296472D01*
X192897Y296242D01*
Y295858D01*
X193052Y295513D01*
X193362Y295283D01*
X193723Y295207D01*
X194085Y295283D01*
X194343Y295475D01*
X194498Y295782D01*
X194550Y296050D01*
G01Y299073D02*
X193878Y299150D01*
X193310Y299265D01*
X192793Y299418D01*
X192225Y299610D01*
X191450Y299917D01*
Y298383D01*
G01X195193Y319792D02*
X194963Y319947D01*
X194695Y320050D01*
X194388D01*
X194043Y319895D01*
X193775Y319637D01*
X193583Y319327D01*
X193430Y318810D01*
X193392Y318345D01*
X193468Y317880D01*
X193583Y317570D01*
X193813Y317260D01*
X194082Y317053D01*
X194350Y316950D01*
X194618D01*
X194887Y317053D01*
X195117Y317208D01*
X195308Y317415D01*
G01X196722Y319533D02*
X196952Y319843D01*
X197220Y319998D01*
X197527Y320050D01*
X197910Y319947D01*
X198178Y319688D01*
X198255Y319378D01*
X198217Y319068D01*
X198063Y318810D01*
X197297Y318293D01*
X196952Y317932D01*
X196722Y317415D01*
X196645Y316950D01*
X198255D01*
G01X199898Y317312D02*
X200167Y317053D01*
X200473Y316950D01*
X200780Y317053D01*
X201048Y317363D01*
X201240Y317828D01*
X201317Y318293D01*
Y318862D01*
X201240Y319327D01*
X201048Y319740D01*
X200818Y319947D01*
X200550Y320050D01*
X200243Y319947D01*
X200013Y319740D01*
X199860Y319430D01*
X199783Y319017D01*
X199860Y318655D01*
X200052Y318293D01*
X200282Y318087D01*
X200550Y318035D01*
X200857Y318138D01*
X201087Y318397D01*
X201317Y318862D01*
G01X203650Y316950D02*
X203918Y317002D01*
X204225Y317157D01*
X204417Y317415D01*
X204493Y317777D01*
X204417Y318138D01*
X204187Y318448D01*
X203842Y318603D01*
X203458D01*
X203228Y318707D01*
X203037Y318965D01*
X202960Y319327D01*
X203075Y319688D01*
X203343Y319947D01*
X203650Y320050D01*
X203957Y319947D01*
X204225Y319688D01*
X204340Y319327D01*
X204263Y318965D01*
X204072Y318707D01*
X203842Y318603D01*
X203458D01*
X203113Y318448D01*
X202883Y318138D01*
X202807Y317777D01*
X202883Y317415D01*
X203075Y317157D01*
X203382Y317002D01*
X203650Y316950D01*
G01X194193Y311792D02*
X193963Y311947D01*
X193695Y312050D01*
X193388D01*
X193043Y311895D01*
X192775Y311637D01*
X192583Y311327D01*
X192430Y310810D01*
X192392Y310345D01*
X192468Y309880D01*
X192583Y309570D01*
X192813Y309260D01*
X193082Y309053D01*
X193350Y308950D01*
X193618D01*
X193887Y309053D01*
X194117Y309208D01*
X194308Y309415D01*
G01X195607Y309570D02*
X195837Y309208D01*
X196143Y309002D01*
X196488Y308950D01*
X196795Y309002D01*
X197102Y309260D01*
X197293Y309570D01*
X197332Y309880D01*
X197255Y310242D01*
X196987Y310500D01*
X196718Y310603D01*
X196373D01*
G01X196718D02*
X196948Y310758D01*
X197140Y311017D01*
X197217Y311327D01*
X197140Y311637D01*
X196948Y311895D01*
X196603Y312050D01*
X196258Y311998D01*
X195913Y311792D01*
G01X199550Y312050D02*
X199243Y311947D01*
X199013Y311688D01*
X198860Y311378D01*
X198745Y310965D01*
X198707Y310500D01*
X198745Y310035D01*
X198860Y309622D01*
X199013Y309312D01*
X199243Y309053D01*
X199550Y308950D01*
X199857Y309053D01*
X200087Y309312D01*
X200240Y309622D01*
X200355Y310035D01*
X200393Y310500D01*
X200355Y310965D01*
X200240Y311378D01*
X200087Y311688D01*
X199857Y311947D01*
X199550Y312050D01*
G01X202650D02*
X202343Y311947D01*
X202113Y311688D01*
X201960Y311378D01*
X201845Y310965D01*
X201807Y310500D01*
X201845Y310035D01*
X201960Y309622D01*
X202113Y309312D01*
X202343Y309053D01*
X202650Y308950D01*
X202957Y309053D01*
X203187Y309312D01*
X203340Y309622D01*
X203455Y310035D01*
X203493Y310500D01*
X203455Y310965D01*
X203340Y311378D01*
X203187Y311688D01*
X202957Y311947D01*
X202650Y312050D01*
G01X189450Y317133D02*
X192550D01*
Y318667D01*
G01X189967Y320272D02*
X189657Y320502D01*
X189502Y320770D01*
X189450Y321077D01*
X189553Y321460D01*
X189812Y321728D01*
X190122Y321805D01*
X190432Y321767D01*
X190690Y321613D01*
X191207Y320847D01*
X191568Y320502D01*
X192085Y320272D01*
X192550Y320195D01*
Y321805D01*
G01X191930Y323257D02*
X192292Y323487D01*
X192498Y323793D01*
X192550Y324138D01*
X192498Y324445D01*
X192240Y324752D01*
X191930Y324943D01*
X191620Y324982D01*
X191258Y324905D01*
X191000Y324637D01*
X190897Y324368D01*
Y324023D01*
G01Y324368D02*
X190742Y324598D01*
X190483Y324790D01*
X190173Y324867D01*
X189863Y324790D01*
X189605Y324598D01*
X189450Y324253D01*
X189502Y323908D01*
X189708Y323563D01*
G01X198050Y334583D02*
X194950D01*
Y335542D01*
X195105Y335848D01*
X195312Y336040D01*
X195725Y336117D01*
X196138Y336040D01*
X196397Y335810D01*
X196552Y335542D01*
Y334583D01*
G01Y335542D02*
X198050Y336117D01*
G01Y338910D02*
X194950D01*
X197172Y337492D01*
Y339408D01*
G01X195467Y340822D02*
X195157Y341052D01*
X195002Y341320D01*
X194950Y341627D01*
X195053Y342010D01*
X195312Y342278D01*
X195622Y342355D01*
X195932Y342317D01*
X196190Y342163D01*
X196707Y341397D01*
X197068Y341052D01*
X197585Y340822D01*
X198050Y340745D01*
Y342355D01*
G01X195467Y343922D02*
X195157Y344152D01*
X195002Y344420D01*
X194950Y344727D01*
X195053Y345110D01*
X195312Y345378D01*
X195622Y345455D01*
X195932Y345417D01*
X196190Y345263D01*
X196707Y344497D01*
X197068Y344152D01*
X197585Y343922D01*
X198050Y343845D01*
Y345455D01*
G01X199950Y332350D02*
X203050D01*
G01X199950Y331468D02*
Y333232D01*
G01X203050Y334683D02*
X199950D01*
Y335603D01*
X200105Y335910D01*
X200467Y336140D01*
X200880Y336217D01*
X201293Y336140D01*
X201603Y335948D01*
X201758Y335603D01*
Y334683D01*
G01X200467Y337822D02*
X200157Y338052D01*
X200002Y338320D01*
X199950Y338627D01*
X200053Y339010D01*
X200312Y339278D01*
X200622Y339355D01*
X200932Y339317D01*
X201190Y339163D01*
X201707Y338397D01*
X202068Y338052D01*
X202585Y337822D01*
X203050Y337745D01*
Y339355D01*
G01X202430Y340807D02*
X202792Y341037D01*
X202998Y341343D01*
X203050Y341688D01*
X202998Y341995D01*
X202740Y342302D01*
X202430Y342493D01*
X202120Y342532D01*
X201758Y342455D01*
X201500Y342187D01*
X201397Y341918D01*
Y341573D01*
G01Y341918D02*
X201242Y342148D01*
X200983Y342340D01*
X200673Y342417D01*
X200363Y342340D01*
X200105Y342148D01*
X199950Y341803D01*
X200002Y341458D01*
X200208Y341113D01*
G01X194183Y381050D02*
Y377950D01*
X195717D01*
G01X198050D02*
Y381050D01*
X197590Y380430D01*
G01Y377950D02*
X198510D01*
G01X210708Y71693D02*
X210553Y71463D01*
X210450Y71195D01*
Y70888D01*
X210605Y70543D01*
X210863Y70275D01*
X211173Y70083D01*
X211690Y69930D01*
X212155Y69892D01*
X212620Y69968D01*
X212930Y70083D01*
X213240Y70313D01*
X213447Y70582D01*
X213550Y70850D01*
Y71118D01*
X213447Y71387D01*
X213292Y71617D01*
X213085Y71808D01*
G01X210967Y73222D02*
X210657Y73452D01*
X210502Y73720D01*
X210450Y74027D01*
X210553Y74410D01*
X210812Y74678D01*
X211122Y74755D01*
X211432Y74717D01*
X211690Y74563D01*
X212207Y73797D01*
X212568Y73452D01*
X213085Y73222D01*
X213550Y73145D01*
Y74755D01*
G01Y77050D02*
X213498Y77318D01*
X213343Y77625D01*
X213085Y77817D01*
X212723Y77893D01*
X212362Y77817D01*
X212052Y77587D01*
X211897Y77242D01*
Y76858D01*
X211793Y76628D01*
X211535Y76437D01*
X211173Y76360D01*
X210812Y76475D01*
X210553Y76743D01*
X210450Y77050D01*
X210553Y77357D01*
X210812Y77625D01*
X211173Y77740D01*
X211535Y77663D01*
X211793Y77472D01*
X211897Y77242D01*
Y76858D01*
X212052Y76513D01*
X212362Y76283D01*
X212723Y76207D01*
X213085Y76283D01*
X213343Y76475D01*
X213498Y76782D01*
X213550Y77050D01*
G01Y80073D02*
X212878Y80150D01*
X212310Y80265D01*
X211793Y80418D01*
X211225Y80610D01*
X210450Y80917D01*
Y79383D01*
G01X215708Y71693D02*
X215553Y71463D01*
X215450Y71195D01*
Y70888D01*
X215605Y70543D01*
X215863Y70275D01*
X216173Y70083D01*
X216690Y69930D01*
X217155Y69892D01*
X217620Y69968D01*
X217930Y70083D01*
X218240Y70313D01*
X218447Y70582D01*
X218550Y70850D01*
Y71118D01*
X218447Y71387D01*
X218292Y71617D01*
X218085Y71808D01*
G01X215967Y73222D02*
X215657Y73452D01*
X215502Y73720D01*
X215450Y74027D01*
X215553Y74410D01*
X215812Y74678D01*
X216122Y74755D01*
X216432Y74717D01*
X216690Y74563D01*
X217207Y73797D01*
X217568Y73452D01*
X218085Y73222D01*
X218550Y73145D01*
Y74755D01*
G01Y77050D02*
X218498Y77318D01*
X218343Y77625D01*
X218085Y77817D01*
X217723Y77893D01*
X217362Y77817D01*
X217052Y77587D01*
X216897Y77242D01*
Y76858D01*
X216793Y76628D01*
X216535Y76437D01*
X216173Y76360D01*
X215812Y76475D01*
X215553Y76743D01*
X215450Y77050D01*
X215553Y77357D01*
X215812Y77625D01*
X216173Y77740D01*
X216535Y77663D01*
X216793Y77472D01*
X216897Y77242D01*
Y76858D01*
X217052Y76513D01*
X217362Y76283D01*
X217723Y76207D01*
X218085Y76283D01*
X218343Y76475D01*
X218498Y76782D01*
X218550Y77050D01*
G01Y80150D02*
X218498Y80418D01*
X218343Y80725D01*
X218085Y80917D01*
X217723Y80993D01*
X217362Y80917D01*
X217052Y80687D01*
X216897Y80342D01*
Y79958D01*
X216793Y79728D01*
X216535Y79537D01*
X216173Y79460D01*
X215812Y79575D01*
X215553Y79843D01*
X215450Y80150D01*
X215553Y80457D01*
X215812Y80725D01*
X216173Y80840D01*
X216535Y80763D01*
X216793Y80572D01*
X216897Y80342D01*
Y79958D01*
X217052Y79613D01*
X217362Y79383D01*
X217723Y79307D01*
X218085Y79383D01*
X218343Y79575D01*
X218498Y79882D01*
X218550Y80150D01*
G01X207050Y69133D02*
X203950D01*
Y70092D01*
X204105Y70398D01*
X204312Y70590D01*
X204725Y70667D01*
X205138Y70590D01*
X205397Y70360D01*
X205552Y70092D01*
Y69133D01*
G01Y70092D02*
X207050Y70667D01*
G01X204467Y72272D02*
X204157Y72502D01*
X204002Y72770D01*
X203950Y73077D01*
X204053Y73460D01*
X204312Y73728D01*
X204622Y73805D01*
X204932Y73767D01*
X205190Y73613D01*
X205707Y72847D01*
X206068Y72502D01*
X206585Y72272D01*
X207050Y72195D01*
Y73805D01*
G01X206585Y75257D02*
X206843Y75487D01*
X206998Y75755D01*
X207050Y76100D01*
X206947Y76445D01*
X206740Y76713D01*
X206378Y76905D01*
X205965Y76943D01*
X205552Y76867D01*
X205293Y76675D01*
X205087Y76407D01*
X205035Y76138D01*
X205087Y75870D01*
X205293Y75525D01*
X203950Y75640D01*
Y76675D01*
G01X205413Y301325D02*
X205573Y301117D01*
X205760Y300992D01*
X206000Y300950D01*
X206240Y301033D01*
X206427Y301200D01*
X206560Y301492D01*
X206587Y301825D01*
X206533Y302158D01*
X206400Y302367D01*
X206213Y302533D01*
X206027Y302575D01*
X205840Y302533D01*
X205600Y302367D01*
X205680Y303450D01*
X206400D01*
G01X206820Y332450D02*
Y334950D01*
X205833Y333158D01*
X207167D01*
G01X211272Y381033D02*
X211502Y381343D01*
X211770Y381498D01*
X212077Y381550D01*
X212460Y381447D01*
X212728Y381188D01*
X212805Y380878D01*
X212767Y380568D01*
X212613Y380310D01*
X211847Y379793D01*
X211502Y379432D01*
X211272Y378915D01*
X211195Y378450D01*
X212805D01*
G01X231130Y35000D02*
X231897D01*
Y34070D01*
X231667Y33760D01*
X231398Y33553D01*
X231015Y33450D01*
X230632Y33553D01*
X230363Y33760D01*
X230133Y34070D01*
X229980Y34432D01*
X229903Y34845D01*
Y35207D01*
X229980Y35517D01*
X230133Y35878D01*
X230363Y36188D01*
X230593Y36395D01*
X230900Y36550D01*
X231168D01*
X231475Y36447D01*
X231705Y36240D01*
G01X233272Y33450D02*
Y36550D01*
X234728D01*
G01X234192Y35052D02*
X233272D01*
G01X237100Y33450D02*
Y36550D01*
X236640Y35930D01*
G01Y33450D02*
X237560D01*
G01X226850Y56550D02*
Y53450D01*
G01X225968Y56550D02*
X227732D01*
G01X229183Y53450D02*
Y56550D01*
X230103D01*
X230410Y56395D01*
X230640Y56033D01*
X230717Y55620D01*
X230640Y55207D01*
X230448Y54897D01*
X230103Y54742D01*
X229183D01*
G01X233510Y53450D02*
Y56550D01*
X232092Y54328D01*
X234008D01*
G01X236150Y53450D02*
X236418Y53502D01*
X236725Y53657D01*
X236917Y53915D01*
X236993Y54277D01*
X236917Y54638D01*
X236687Y54948D01*
X236342Y55103D01*
X235958D01*
X235728Y55207D01*
X235537Y55465D01*
X235460Y55827D01*
X235575Y56188D01*
X235843Y56447D01*
X236150Y56550D01*
X236457Y56447D01*
X236725Y56188D01*
X236840Y55827D01*
X236763Y55465D01*
X236572Y55207D01*
X236342Y55103D01*
X235958D01*
X235613Y54948D01*
X235383Y54638D01*
X235307Y54277D01*
X235383Y53915D01*
X235575Y53657D01*
X235882Y53502D01*
X236150Y53450D01*
G01X226623Y81890D02*
Y84990D01*
X227620Y82407D01*
X228617Y84990D01*
Y81890D01*
G01X229762D02*
X230720Y84990D01*
X231678Y81890D01*
G01X231333Y82975D02*
X230107D01*
G01X234663Y84732D02*
X234433Y84887D01*
X234165Y84990D01*
X233858D01*
X233513Y84835D01*
X233245Y84577D01*
X233053Y84267D01*
X232900Y83750D01*
X232862Y83285D01*
X232938Y82820D01*
X233053Y82510D01*
X233283Y82200D01*
X233552Y81993D01*
X233820Y81890D01*
X234088D01*
X234357Y81993D01*
X234587Y82148D01*
X234778Y82355D01*
G01X235770Y80857D02*
X238070D01*
G01X239253Y81890D02*
Y84990D01*
X240173D01*
X240480Y84835D01*
X240710Y84473D01*
X240787Y84060D01*
X240710Y83647D01*
X240518Y83337D01*
X240173Y83182D01*
X239253D01*
G01X242660Y84990D02*
X243580D01*
G01X243120D02*
Y81890D01*
G01X242660D02*
X243580D01*
G01X245338D02*
Y84990D01*
X247102Y81890D01*
Y84990D01*
G01X249320Y81890D02*
X249588Y81942D01*
X249895Y82097D01*
X250087Y82355D01*
X250163Y82717D01*
X250087Y83078D01*
X249857Y83388D01*
X249512Y83543D01*
X249128D01*
X248898Y83647D01*
X248707Y83905D01*
X248630Y84267D01*
X248745Y84628D01*
X249013Y84887D01*
X249320Y84990D01*
X249627Y84887D01*
X249895Y84628D01*
X250010Y84267D01*
X249933Y83905D01*
X249742Y83647D01*
X249512Y83543D01*
X249128D01*
X248783Y83388D01*
X248553Y83078D01*
X248477Y82717D01*
X248553Y82355D01*
X248745Y82097D01*
X249052Y81942D01*
X249320Y81890D01*
G01X236708Y289193D02*
X236553Y288963D01*
X236450Y288695D01*
Y288388D01*
X236605Y288043D01*
X236863Y287775D01*
X237173Y287583D01*
X237690Y287430D01*
X238155Y287392D01*
X238620Y287468D01*
X238930Y287583D01*
X239240Y287813D01*
X239447Y288082D01*
X239550Y288350D01*
Y288618D01*
X239447Y288887D01*
X239292Y289117D01*
X239085Y289308D01*
G01X238930Y290607D02*
X239292Y290837D01*
X239498Y291143D01*
X239550Y291488D01*
X239498Y291795D01*
X239240Y292102D01*
X238930Y292293D01*
X238620Y292332D01*
X238258Y292255D01*
X238000Y291987D01*
X237897Y291718D01*
Y291373D01*
G01Y291718D02*
X237742Y291948D01*
X237483Y292140D01*
X237173Y292217D01*
X236863Y292140D01*
X236605Y291948D01*
X236450Y291603D01*
X236502Y291258D01*
X236708Y290913D01*
G01X236450Y294550D02*
X236553Y294243D01*
X236812Y294013D01*
X237122Y293860D01*
X237535Y293745D01*
X238000Y293707D01*
X238465Y293745D01*
X238878Y293860D01*
X239188Y294013D01*
X239447Y294243D01*
X239550Y294550D01*
X239447Y294857D01*
X239188Y295087D01*
X238878Y295240D01*
X238465Y295355D01*
X238000Y295393D01*
X237535Y295355D01*
X237122Y295240D01*
X236812Y295087D01*
X236553Y294857D01*
X236450Y294550D01*
G01X238258Y296922D02*
X237897Y297190D01*
X237690Y297420D01*
X237587Y297727D01*
X237690Y297995D01*
X237897Y298187D01*
X238207Y298340D01*
X238568Y298378D01*
X238878Y298340D01*
X239188Y298187D01*
X239447Y297957D01*
X239550Y297688D01*
X239447Y297382D01*
X239137Y297113D01*
X238672Y296960D01*
X238155Y296922D01*
X237483Y296998D01*
X237122Y297113D01*
X236760Y297305D01*
X236502Y297573D01*
X236450Y297842D01*
X236553Y298110D01*
X236812Y298302D01*
G01X235550Y287583D02*
X232450D01*
Y288542D01*
X232605Y288848D01*
X232812Y289040D01*
X233225Y289117D01*
X233638Y289040D01*
X233897Y288810D01*
X234052Y288542D01*
Y287583D01*
G01Y288542D02*
X235550Y289117D01*
G01Y291910D02*
X232450D01*
X234672Y290492D01*
Y292408D01*
G01X235550Y294550D02*
X232450D01*
X233070Y294090D01*
G01X235550D02*
Y295010D01*
G01Y297650D02*
X235498Y297918D01*
X235343Y298225D01*
X235085Y298417D01*
X234723Y298493D01*
X234362Y298417D01*
X234052Y298187D01*
X233897Y297842D01*
Y297458D01*
X233793Y297228D01*
X233535Y297037D01*
X233173Y296960D01*
X232812Y297075D01*
X232553Y297343D01*
X232450Y297650D01*
X232553Y297957D01*
X232812Y298225D01*
X233173Y298340D01*
X233535Y298263D01*
X233793Y298072D01*
X233897Y297842D01*
Y297458D01*
X234052Y297113D01*
X234362Y296883D01*
X234723Y296807D01*
X235085Y296883D01*
X235343Y297075D01*
X235498Y297382D01*
X235550Y297650D01*
G01X231550Y287583D02*
X228450D01*
Y288542D01*
X228605Y288848D01*
X228812Y289040D01*
X229225Y289117D01*
X229638Y289040D01*
X229897Y288810D01*
X230052Y288542D01*
Y287583D01*
G01Y288542D02*
X231550Y289117D01*
G01Y291910D02*
X228450D01*
X230672Y290492D01*
Y292408D01*
G01X231550Y294550D02*
X228450D01*
X229070Y294090D01*
G01X231550D02*
Y295010D01*
G01X228967Y296922D02*
X228657Y297152D01*
X228502Y297420D01*
X228450Y297727D01*
X228553Y298110D01*
X228812Y298378D01*
X229122Y298455D01*
X229432Y298417D01*
X229690Y298263D01*
X230207Y297497D01*
X230568Y297152D01*
X231085Y296922D01*
X231550Y296845D01*
Y298455D01*
G01X227550Y287583D02*
X224450D01*
Y288542D01*
X224605Y288848D01*
X224812Y289040D01*
X225225Y289117D01*
X225638Y289040D01*
X225897Y288810D01*
X226052Y288542D01*
Y287583D01*
G01Y288542D02*
X227550Y289117D01*
G01Y291910D02*
X224450D01*
X226672Y290492D01*
Y292408D01*
G01X224450Y294550D02*
X224553Y294243D01*
X224812Y294013D01*
X225122Y293860D01*
X225535Y293745D01*
X226000Y293707D01*
X226465Y293745D01*
X226878Y293860D01*
X227188Y294013D01*
X227447Y294243D01*
X227550Y294550D01*
X227447Y294857D01*
X227188Y295087D01*
X226878Y295240D01*
X226465Y295355D01*
X226000Y295393D01*
X225535Y295355D01*
X225122Y295240D01*
X224812Y295087D01*
X224553Y294857D01*
X224450Y294550D01*
G01X227550Y297650D02*
X227498Y297918D01*
X227343Y298225D01*
X227085Y298417D01*
X226723Y298493D01*
X226362Y298417D01*
X226052Y298187D01*
X225897Y297842D01*
Y297458D01*
X225793Y297228D01*
X225535Y297037D01*
X225173Y296960D01*
X224812Y297075D01*
X224553Y297343D01*
X224450Y297650D01*
X224553Y297957D01*
X224812Y298225D01*
X225173Y298340D01*
X225535Y298263D01*
X225793Y298072D01*
X225897Y297842D01*
Y297458D01*
X226052Y297113D01*
X226362Y296883D01*
X226723Y296807D01*
X227085Y296883D01*
X227343Y297075D01*
X227498Y297382D01*
X227550Y297650D01*
G01X223000Y302950D02*
X223187Y302992D01*
X223400Y303117D01*
X223533Y303325D01*
X223587Y303617D01*
X223533Y303908D01*
X223373Y304158D01*
X223133Y304283D01*
X222867D01*
X222707Y304367D01*
X222573Y304575D01*
X222520Y304867D01*
X222600Y305158D01*
X222787Y305367D01*
X223000Y305450D01*
X223213Y305367D01*
X223400Y305158D01*
X223480Y304867D01*
X223427Y304575D01*
X223293Y304367D01*
X223133Y304283D01*
X222867D01*
X222627Y304158D01*
X222467Y303908D01*
X222413Y303617D01*
X222467Y303325D01*
X222600Y303117D01*
X222813Y302992D01*
X223000Y302950D01*
G01X222450Y311557D02*
X224672D01*
X225137Y311710D01*
X225447Y312017D01*
X225550Y312400D01*
X225447Y312783D01*
X225137Y313090D01*
X224672Y313243D01*
X222450D01*
G01X224930Y314657D02*
X225292Y314887D01*
X225498Y315193D01*
X225550Y315538D01*
X225498Y315845D01*
X225240Y316152D01*
X224930Y316343D01*
X224620Y316382D01*
X224258Y316305D01*
X224000Y316037D01*
X223897Y315768D01*
Y315423D01*
G01Y315768D02*
X223742Y315998D01*
X223483Y316190D01*
X223173Y316267D01*
X222863Y316190D01*
X222605Y315998D01*
X222450Y315653D01*
X222502Y315308D01*
X222708Y314963D01*
G01X225085Y317757D02*
X225343Y317987D01*
X225498Y318255D01*
X225550Y318600D01*
X225447Y318945D01*
X225240Y319213D01*
X224878Y319405D01*
X224465Y319443D01*
X224052Y319367D01*
X223793Y319175D01*
X223587Y318907D01*
X223535Y318638D01*
X223587Y318370D01*
X223793Y318025D01*
X222450Y318140D01*
Y319175D01*
G01X232050Y322083D02*
X228950D01*
Y323042D01*
X229105Y323348D01*
X229312Y323540D01*
X229725Y323617D01*
X230138Y323540D01*
X230397Y323310D01*
X230552Y323042D01*
Y322083D01*
G01Y323042D02*
X232050Y323617D01*
G01Y326410D02*
X228950D01*
X231172Y324992D01*
Y326908D01*
G01X228950Y329050D02*
X229053Y328743D01*
X229312Y328513D01*
X229622Y328360D01*
X230035Y328245D01*
X230500Y328207D01*
X230965Y328245D01*
X231378Y328360D01*
X231688Y328513D01*
X231947Y328743D01*
X232050Y329050D01*
X231947Y329357D01*
X231688Y329587D01*
X231378Y329740D01*
X230965Y329855D01*
X230500Y329893D01*
X230035Y329855D01*
X229622Y329740D01*
X229312Y329587D01*
X229053Y329357D01*
X228950Y329050D01*
G01X230758Y331422D02*
X230397Y331690D01*
X230190Y331920D01*
X230087Y332227D01*
X230190Y332495D01*
X230397Y332687D01*
X230707Y332840D01*
X231068Y332878D01*
X231378Y332840D01*
X231688Y332687D01*
X231947Y332457D01*
X232050Y332188D01*
X231947Y331882D01*
X231637Y331613D01*
X231172Y331460D01*
X230655Y331422D01*
X229983Y331498D01*
X229622Y331613D01*
X229260Y331805D01*
X229002Y332073D01*
X228950Y332342D01*
X229053Y332610D01*
X229312Y332802D01*
G01X230308Y384843D02*
X230153Y384613D01*
X230050Y384345D01*
Y384038D01*
X230205Y383693D01*
X230463Y383425D01*
X230773Y383233D01*
X231290Y383080D01*
X231755Y383042D01*
X232220Y383118D01*
X232530Y383233D01*
X232840Y383463D01*
X233047Y383732D01*
X233150Y384000D01*
Y384268D01*
X233047Y384537D01*
X232892Y384767D01*
X232685Y384958D01*
G01X233150Y387100D02*
X230050D01*
X230670Y386640D01*
G01X233150D02*
Y387560D01*
G01X230567Y389472D02*
X230257Y389702D01*
X230102Y389970D01*
X230050Y390277D01*
X230153Y390660D01*
X230412Y390928D01*
X230722Y391005D01*
X231032Y390967D01*
X231290Y390813D01*
X231807Y390047D01*
X232168Y389702D01*
X232685Y389472D01*
X233150Y389395D01*
Y391005D01*
G01X236308Y384343D02*
X236153Y384113D01*
X236050Y383845D01*
Y383538D01*
X236205Y383193D01*
X236463Y382925D01*
X236773Y382733D01*
X237290Y382580D01*
X237755Y382542D01*
X238220Y382618D01*
X238530Y382733D01*
X238840Y382963D01*
X239047Y383232D01*
X239150Y383500D01*
Y383768D01*
X239047Y384037D01*
X238892Y384267D01*
X238685Y384458D01*
G01X239150Y386600D02*
X236050D01*
X236670Y386140D01*
G01X239150D02*
Y387060D01*
G01X238530Y388857D02*
X238892Y389087D01*
X239098Y389393D01*
X239150Y389738D01*
X239098Y390045D01*
X238840Y390352D01*
X238530Y390543D01*
X238220Y390582D01*
X237858Y390505D01*
X237600Y390237D01*
X237497Y389968D01*
Y389623D01*
G01Y389968D02*
X237342Y390198D01*
X237083Y390390D01*
X236773Y390467D01*
X236463Y390390D01*
X236205Y390198D01*
X236050Y389853D01*
X236102Y389508D01*
X236308Y389163D01*
G01X232308Y404843D02*
X232153Y404613D01*
X232050Y404345D01*
Y404038D01*
X232205Y403693D01*
X232463Y403425D01*
X232773Y403233D01*
X233290Y403080D01*
X233755Y403042D01*
X234220Y403118D01*
X234530Y403233D01*
X234840Y403463D01*
X235047Y403732D01*
X235150Y404000D01*
Y404268D01*
X235047Y404537D01*
X234892Y404767D01*
X234685Y404958D01*
G01X235150Y407100D02*
X232050D01*
X232670Y406640D01*
G01X235150D02*
Y407560D01*
G01Y410660D02*
X232050D01*
X234272Y409242D01*
Y411158D01*
G01X232650Y397100D02*
Y394000D01*
G01X231768Y397100D02*
X233532D01*
G01X234983Y394000D02*
Y397100D01*
X235903D01*
X236210Y396945D01*
X236440Y396583D01*
X236517Y396170D01*
X236440Y395757D01*
X236248Y395447D01*
X235903Y395292D01*
X234983D01*
G01X238122D02*
X238390Y395653D01*
X238620Y395860D01*
X238927Y395963D01*
X239195Y395860D01*
X239387Y395653D01*
X239540Y395343D01*
X239578Y394982D01*
X239540Y394672D01*
X239387Y394362D01*
X239157Y394103D01*
X238888Y394000D01*
X238582Y394103D01*
X238313Y394413D01*
X238160Y394878D01*
X238122Y395395D01*
X238198Y396067D01*
X238313Y396428D01*
X238505Y396790D01*
X238773Y397048D01*
X239042Y397100D01*
X239310Y396997D01*
X239502Y396738D01*
G01X241950Y397100D02*
X241643Y396997D01*
X241413Y396738D01*
X241260Y396428D01*
X241145Y396015D01*
X241107Y395550D01*
X241145Y395085D01*
X241260Y394672D01*
X241413Y394362D01*
X241643Y394103D01*
X241950Y394000D01*
X242257Y394103D01*
X242487Y394362D01*
X242640Y394672D01*
X242755Y395085D01*
X242793Y395550D01*
X242755Y396015D01*
X242640Y396428D01*
X242487Y396738D01*
X242257Y396997D01*
X241950Y397100D01*
G01X252670Y66133D02*
X249570D01*
Y67092D01*
X249725Y67398D01*
X249932Y67590D01*
X250345Y67667D01*
X250758Y67590D01*
X251017Y67360D01*
X251172Y67092D01*
Y66133D01*
G01Y67092D02*
X252670Y67667D01*
G01X250087Y69272D02*
X249777Y69502D01*
X249622Y69770D01*
X249570Y70077D01*
X249673Y70460D01*
X249932Y70728D01*
X250242Y70805D01*
X250552Y70767D01*
X250810Y70613D01*
X251327Y69847D01*
X251688Y69502D01*
X252205Y69272D01*
X252670Y69195D01*
Y70805D01*
G01X250087Y72372D02*
X249777Y72602D01*
X249622Y72870D01*
X249570Y73177D01*
X249673Y73560D01*
X249932Y73828D01*
X250242Y73905D01*
X250552Y73867D01*
X250810Y73713D01*
X251327Y72947D01*
X251688Y72602D01*
X252205Y72372D01*
X252670Y72295D01*
Y73905D01*
G01X251623Y81890D02*
Y84990D01*
X252620Y82407D01*
X253617Y84990D01*
Y81890D01*
G01X254762D02*
X255720Y84990D01*
X256678Y81890D01*
G01X256333Y82975D02*
X255107D01*
G01X259663Y84732D02*
X259433Y84887D01*
X259165Y84990D01*
X258858D01*
X258513Y84835D01*
X258245Y84577D01*
X258053Y84267D01*
X257900Y83750D01*
X257862Y83285D01*
X257938Y82820D01*
X258053Y82510D01*
X258283Y82200D01*
X258552Y81993D01*
X258820Y81890D01*
X259088D01*
X259357Y81993D01*
X259587Y82148D01*
X259778Y82355D01*
G01X260770Y80857D02*
X263070D01*
G01X264253Y81890D02*
Y84990D01*
X265173D01*
X265480Y84835D01*
X265710Y84473D01*
X265787Y84060D01*
X265710Y83647D01*
X265518Y83337D01*
X265173Y83182D01*
X264253D01*
G01X267660Y84990D02*
X268580D01*
G01X268120D02*
Y81890D01*
G01X267660D02*
X268580D01*
G01X270338D02*
Y84990D01*
X272102Y81890D01*
Y84990D01*
G01X274243Y81890D02*
X274320Y82562D01*
X274435Y83130D01*
X274588Y83647D01*
X274780Y84215D01*
X275087Y84990D01*
X273553D01*
G01X246973Y246390D02*
Y249490D01*
X247970Y246907D01*
X248967Y249490D01*
Y246390D01*
G01X251837D02*
X250303D01*
Y249490D01*
X251837D01*
G01X251223Y247992D02*
X250303D01*
G01X253442Y247682D02*
X253710Y248043D01*
X253940Y248250D01*
X254247Y248353D01*
X254515Y248250D01*
X254707Y248043D01*
X254860Y247733D01*
X254898Y247372D01*
X254860Y247062D01*
X254707Y246752D01*
X254477Y246493D01*
X254208Y246390D01*
X253902Y246493D01*
X253633Y246803D01*
X253480Y247268D01*
X253442Y247785D01*
X253518Y248457D01*
X253633Y248818D01*
X253825Y249180D01*
X254093Y249438D01*
X254362Y249490D01*
X254630Y249387D01*
X254822Y249128D01*
G01X252403Y325450D02*
Y328550D01*
X253400Y325967D01*
X254397Y328550D01*
Y325450D01*
G01X257267D02*
X255733D01*
Y328550D01*
X257267D01*
G01X256653Y327052D02*
X255733D01*
G01X258872Y328033D02*
X259102Y328343D01*
X259370Y328498D01*
X259677Y328550D01*
X260060Y328447D01*
X260328Y328188D01*
X260405Y327878D01*
X260367Y327568D01*
X260213Y327310D01*
X259447Y326793D01*
X259102Y326432D01*
X258872Y325915D01*
X258795Y325450D01*
X260405D01*
G01X246500Y339500D02*
Y382500D01*
G01X280500Y339500D02*
X246500D01*
G01X248708Y347693D02*
X248553Y347463D01*
X248450Y347195D01*
Y346888D01*
X248605Y346543D01*
X248863Y346275D01*
X249173Y346083D01*
X249690Y345930D01*
X250155Y345892D01*
X250620Y345968D01*
X250930Y346083D01*
X251240Y346313D01*
X251447Y346582D01*
X251550Y346850D01*
Y347118D01*
X251447Y347387D01*
X251292Y347617D01*
X251085Y347808D01*
G01X251550Y349950D02*
X248450D01*
X249070Y349490D01*
G01X251550D02*
Y350410D01*
G01X251188Y352398D02*
X251447Y352667D01*
X251550Y352973D01*
X251447Y353280D01*
X251137Y353548D01*
X250672Y353740D01*
X250207Y353817D01*
X249638D01*
X249173Y353740D01*
X248760Y353548D01*
X248553Y353318D01*
X248450Y353050D01*
X248553Y352743D01*
X248760Y352513D01*
X249070Y352360D01*
X249483Y352283D01*
X249845Y352360D01*
X250207Y352552D01*
X250413Y352782D01*
X250465Y353050D01*
X250362Y353357D01*
X250103Y353587D01*
X249638Y353817D01*
G01X251550Y356150D02*
X251498Y356418D01*
X251343Y356725D01*
X251085Y356917D01*
X250723Y356993D01*
X250362Y356917D01*
X250052Y356687D01*
X249897Y356342D01*
Y355958D01*
X249793Y355728D01*
X249535Y355537D01*
X249173Y355460D01*
X248812Y355575D01*
X248553Y355843D01*
X248450Y356150D01*
X248553Y356457D01*
X248812Y356725D01*
X249173Y356840D01*
X249535Y356763D01*
X249793Y356572D01*
X249897Y356342D01*
Y355958D01*
X250052Y355613D01*
X250362Y355383D01*
X250723Y355307D01*
X251085Y355383D01*
X251343Y355575D01*
X251498Y355882D01*
X251550Y356150D01*
G01X247000Y372000D02*
X255000D01*
G01X248708Y361193D02*
X248553Y360963D01*
X248450Y360695D01*
Y360388D01*
X248605Y360043D01*
X248863Y359775D01*
X249173Y359583D01*
X249690Y359430D01*
X250155Y359392D01*
X250620Y359468D01*
X250930Y359583D01*
X251240Y359813D01*
X251447Y360082D01*
X251550Y360350D01*
Y360618D01*
X251447Y360887D01*
X251292Y361117D01*
X251085Y361308D01*
G01X251550Y363450D02*
X248450D01*
X249070Y362990D01*
G01X251550D02*
Y363910D01*
G01X251188Y365898D02*
X251447Y366167D01*
X251550Y366473D01*
X251447Y366780D01*
X251137Y367048D01*
X250672Y367240D01*
X250207Y367317D01*
X249638D01*
X249173Y367240D01*
X248760Y367048D01*
X248553Y366818D01*
X248450Y366550D01*
X248553Y366243D01*
X248760Y366013D01*
X249070Y365860D01*
X249483Y365783D01*
X249845Y365860D01*
X250207Y366052D01*
X250413Y366282D01*
X250465Y366550D01*
X250362Y366857D01*
X250103Y367087D01*
X249638Y367317D01*
G01X251188Y368998D02*
X251447Y369267D01*
X251550Y369573D01*
X251447Y369880D01*
X251137Y370148D01*
X250672Y370340D01*
X250207Y370417D01*
X249638D01*
X249173Y370340D01*
X248760Y370148D01*
X248553Y369918D01*
X248450Y369650D01*
X248553Y369343D01*
X248760Y369113D01*
X249070Y368960D01*
X249483Y368883D01*
X249845Y368960D01*
X250207Y369152D01*
X250413Y369382D01*
X250465Y369650D01*
X250362Y369957D01*
X250103Y370187D01*
X249638Y370417D01*
G01X251307Y376103D02*
X251460Y376258D01*
X251575Y376517D01*
X251652Y376878D01*
X251575Y377188D01*
X251422Y377395D01*
X251153Y377550D01*
X250118D01*
Y374450D01*
X251383D01*
X251652Y374657D01*
X251805Y374967D01*
X251882Y375328D01*
X251805Y375690D01*
X251575Y376000D01*
X251307Y376103D01*
X250118D01*
G01X246500Y382500D02*
X250500D01*
G01D02*
X280500D01*
G01X237208Y404743D02*
X237053Y404513D01*
X236950Y404245D01*
Y403938D01*
X237105Y403593D01*
X237363Y403325D01*
X237673Y403133D01*
X238190Y402980D01*
X238655Y402942D01*
X239120Y403018D01*
X239430Y403133D01*
X239740Y403363D01*
X239947Y403632D01*
X240050Y403900D01*
Y404168D01*
X239947Y404437D01*
X239792Y404667D01*
X239585Y404858D01*
G01X240050Y407000D02*
X236950D01*
X237570Y406540D01*
G01X240050D02*
Y407460D01*
G01X239585Y409257D02*
X239843Y409487D01*
X239998Y409755D01*
X240050Y410100D01*
X239947Y410445D01*
X239740Y410713D01*
X239378Y410905D01*
X238965Y410943D01*
X238552Y410867D01*
X238293Y410675D01*
X238087Y410407D01*
X238035Y410138D01*
X238087Y409870D01*
X238293Y409525D01*
X236950Y409640D01*
Y410675D01*
G01X252903Y393450D02*
Y396550D01*
X253900Y393967D01*
X254897Y396550D01*
Y393450D01*
G01X257767D02*
X256233D01*
Y396550D01*
X257767D01*
G01X257153Y395052D02*
X256233D01*
G01X260100Y393450D02*
Y396550D01*
X259640Y395930D01*
G01Y393450D02*
X260560D01*
G01X269757Y56586D02*
X269987Y56224D01*
X270293Y56018D01*
X270638Y55966D01*
X270945Y56018D01*
X271252Y56276D01*
X271443Y56586D01*
X271482Y56896D01*
X271405Y57258D01*
X271137Y57516D01*
X270868Y57619D01*
X270523D01*
G01X270868D02*
X271098Y57774D01*
X271290Y58033D01*
X271367Y58343D01*
X271290Y58653D01*
X271098Y58911D01*
X270753Y59066D01*
X270408Y59014D01*
X270063Y58808D01*
G01X257633Y50450D02*
Y53550D01*
X258592D01*
X258898Y53395D01*
X259090Y53188D01*
X259167Y52775D01*
X259090Y52362D01*
X258860Y52103D01*
X258592Y51948D01*
X257633D01*
G01X258592D02*
X259167Y50450D01*
G01X260657Y50915D02*
X260887Y50657D01*
X261155Y50502D01*
X261500Y50450D01*
X261845Y50553D01*
X262113Y50760D01*
X262305Y51122D01*
X262343Y51535D01*
X262267Y51948D01*
X262075Y52207D01*
X261807Y52413D01*
X261538Y52465D01*
X261270Y52413D01*
X260925Y52207D01*
X261040Y53550D01*
X262075D01*
G01X263872Y51742D02*
X264140Y52103D01*
X264370Y52310D01*
X264677Y52413D01*
X264945Y52310D01*
X265137Y52103D01*
X265290Y51793D01*
X265328Y51432D01*
X265290Y51122D01*
X265137Y50812D01*
X264907Y50553D01*
X264638Y50450D01*
X264332Y50553D01*
X264063Y50863D01*
X263910Y51328D01*
X263872Y51845D01*
X263948Y52517D01*
X264063Y52878D01*
X264255Y53240D01*
X264523Y53498D01*
X264792Y53550D01*
X265060Y53447D01*
X265252Y53188D01*
G01X261633Y68950D02*
Y72050D01*
X262592D01*
X262898Y71895D01*
X263090Y71688D01*
X263167Y71275D01*
X263090Y70862D01*
X262860Y70603D01*
X262592Y70448D01*
X261633D01*
G01X262592D02*
X263167Y68950D01*
G01X264657Y69415D02*
X264887Y69157D01*
X265155Y69002D01*
X265500Y68950D01*
X265845Y69053D01*
X266113Y69260D01*
X266305Y69622D01*
X266343Y70035D01*
X266267Y70448D01*
X266075Y70707D01*
X265807Y70913D01*
X265538Y70965D01*
X265270Y70913D01*
X264925Y70707D01*
X265040Y72050D01*
X266075D01*
G01X267757Y69415D02*
X267987Y69157D01*
X268255Y69002D01*
X268600Y68950D01*
X268945Y69053D01*
X269213Y69260D01*
X269405Y69622D01*
X269443Y70035D01*
X269367Y70448D01*
X269175Y70707D01*
X268907Y70913D01*
X268638Y70965D01*
X268370Y70913D01*
X268025Y70707D01*
X268140Y72050D01*
X269175D01*
G01X268900Y173250D02*
Y175750D01*
X268580Y175250D01*
G01Y173250D02*
X269220D01*
G01X270647Y173542D02*
X270833Y173333D01*
X271047Y173250D01*
X271260Y173333D01*
X271447Y173583D01*
X271580Y173958D01*
X271633Y174333D01*
Y174792D01*
X271580Y175167D01*
X271447Y175500D01*
X271287Y175667D01*
X271100Y175750D01*
X270887Y175667D01*
X270727Y175500D01*
X270620Y175250D01*
X270567Y174917D01*
X270620Y174625D01*
X270753Y174333D01*
X270913Y174167D01*
X271100Y174125D01*
X271313Y174208D01*
X271473Y174417D01*
X271633Y174792D01*
G01X270000Y193250D02*
Y195750D01*
X269680Y195250D01*
G01Y193250D02*
X270320D01*
G01X270000Y287500D02*
X297500D01*
G01X270000Y335500D02*
Y287500D01*
G01X284500Y335500D02*
X270000D01*
G01X267583Y349950D02*
Y353050D01*
X268542D01*
X268848Y352895D01*
X269040Y352688D01*
X269117Y352275D01*
X269040Y351862D01*
X268810Y351603D01*
X268542Y351448D01*
X267583D01*
G01X268542D02*
X269117Y349950D01*
G01X271450D02*
Y353050D01*
X270990Y352430D01*
G01Y349950D02*
X271910D01*
G01X274550D02*
X274818Y350002D01*
X275125Y350157D01*
X275317Y350415D01*
X275393Y350777D01*
X275317Y351138D01*
X275087Y351448D01*
X274742Y351603D01*
X274358D01*
X274128Y351707D01*
X273937Y351965D01*
X273860Y352327D01*
X273975Y352688D01*
X274243Y352947D01*
X274550Y353050D01*
X274857Y352947D01*
X275125Y352688D01*
X275240Y352327D01*
X275163Y351965D01*
X274972Y351707D01*
X274742Y351603D01*
X274358D01*
X274013Y351448D01*
X273783Y351138D01*
X273707Y350777D01*
X273783Y350415D01*
X273975Y350157D01*
X274282Y350002D01*
X274550Y349950D01*
G01X276807Y350415D02*
X277037Y350157D01*
X277305Y350002D01*
X277650Y349950D01*
X277995Y350053D01*
X278263Y350260D01*
X278455Y350622D01*
X278493Y351035D01*
X278417Y351448D01*
X278225Y351707D01*
X277957Y351913D01*
X277688Y351965D01*
X277420Y351913D01*
X277075Y351707D01*
X277190Y353050D01*
X278225D01*
G01X267783Y341466D02*
Y344566D01*
X268742D01*
X269048Y344411D01*
X269240Y344204D01*
X269317Y343791D01*
X269240Y343378D01*
X269010Y343119D01*
X268742Y342964D01*
X267783D01*
G01X268742D02*
X269317Y341466D01*
G01X271650D02*
Y344566D01*
X271190Y343946D01*
G01Y341466D02*
X272110D01*
G01X274750D02*
X275018Y341518D01*
X275325Y341673D01*
X275517Y341931D01*
X275593Y342293D01*
X275517Y342654D01*
X275287Y342964D01*
X274942Y343119D01*
X274558D01*
X274328Y343223D01*
X274137Y343481D01*
X274060Y343843D01*
X274175Y344204D01*
X274443Y344463D01*
X274750Y344566D01*
X275057Y344463D01*
X275325Y344204D01*
X275440Y343843D01*
X275363Y343481D01*
X275172Y343223D01*
X274942Y343119D01*
X274558D01*
X274213Y342964D01*
X273983Y342654D01*
X273907Y342293D01*
X273983Y341931D01*
X274175Y341673D01*
X274482Y341518D01*
X274750Y341466D01*
G01X277122Y342758D02*
X277390Y343119D01*
X277620Y343326D01*
X277927Y343429D01*
X278195Y343326D01*
X278387Y343119D01*
X278540Y342809D01*
X278578Y342448D01*
X278540Y342138D01*
X278387Y341828D01*
X278157Y341569D01*
X277888Y341466D01*
X277582Y341569D01*
X277313Y341879D01*
X277160Y342344D01*
X277122Y342861D01*
X277198Y343533D01*
X277313Y343894D01*
X277505Y344256D01*
X277773Y344514D01*
X278042Y344566D01*
X278310Y344463D01*
X278502Y344204D01*
G01X255083Y345950D02*
Y349050D01*
X256042D01*
X256348Y348895D01*
X256540Y348688D01*
X256617Y348275D01*
X256540Y347862D01*
X256310Y347603D01*
X256042Y347448D01*
X255083D01*
G01X256042D02*
X256617Y345950D01*
G01X258950D02*
Y349050D01*
X258490Y348430D01*
G01Y345950D02*
X259410D01*
G01X261322Y347242D02*
X261590Y347603D01*
X261820Y347810D01*
X262127Y347913D01*
X262395Y347810D01*
X262587Y347603D01*
X262740Y347293D01*
X262778Y346932D01*
X262740Y346622D01*
X262587Y346312D01*
X262357Y346053D01*
X262088Y345950D01*
X261782Y346053D01*
X261513Y346363D01*
X261360Y346828D01*
X261322Y347345D01*
X261398Y348017D01*
X261513Y348378D01*
X261705Y348740D01*
X261973Y348998D01*
X262242Y349050D01*
X262510Y348947D01*
X262702Y348688D01*
G01X265073Y345950D02*
X265150Y346622D01*
X265265Y347190D01*
X265418Y347707D01*
X265610Y348275D01*
X265917Y349050D01*
X264383D01*
G01X267583Y345450D02*
Y348550D01*
X268542D01*
X268848Y348395D01*
X269040Y348188D01*
X269117Y347775D01*
X269040Y347362D01*
X268810Y347103D01*
X268542Y346948D01*
X267583D01*
G01X268542D02*
X269117Y345450D01*
G01X271450D02*
Y348550D01*
X270990Y347930D01*
G01Y345450D02*
X271910D01*
G01X274550D02*
X274818Y345502D01*
X275125Y345657D01*
X275317Y345915D01*
X275393Y346277D01*
X275317Y346638D01*
X275087Y346948D01*
X274742Y347103D01*
X274358D01*
X274128Y347207D01*
X273937Y347465D01*
X273860Y347827D01*
X273975Y348188D01*
X274243Y348447D01*
X274550Y348550D01*
X274857Y348447D01*
X275125Y348188D01*
X275240Y347827D01*
X275163Y347465D01*
X274972Y347207D01*
X274742Y347103D01*
X274358D01*
X274013Y346948D01*
X273783Y346638D01*
X273707Y346277D01*
X273783Y345915D01*
X273975Y345657D01*
X274282Y345502D01*
X274550Y345450D01*
G01X276998Y345812D02*
X277267Y345553D01*
X277573Y345450D01*
X277880Y345553D01*
X278148Y345863D01*
X278340Y346328D01*
X278417Y346793D01*
Y347362D01*
X278340Y347827D01*
X278148Y348240D01*
X277918Y348447D01*
X277650Y348550D01*
X277343Y348447D01*
X277113Y348240D01*
X276960Y347930D01*
X276883Y347517D01*
X276960Y347155D01*
X277152Y346793D01*
X277382Y346587D01*
X277650Y346535D01*
X277957Y346638D01*
X278187Y346897D01*
X278417Y347362D01*
G01X255000Y372000D02*
Y382500D01*
G01X258208Y370693D02*
X258053Y370463D01*
X257950Y370195D01*
Y369888D01*
X258105Y369543D01*
X258363Y369275D01*
X258673Y369083D01*
X259190Y368930D01*
X259655Y368892D01*
X260120Y368968D01*
X260430Y369083D01*
X260740Y369313D01*
X260947Y369582D01*
X261050Y369850D01*
Y370118D01*
X260947Y370387D01*
X260792Y370617D01*
X260585Y370808D01*
G01X261050Y372950D02*
X257950D01*
X258570Y372490D01*
G01X261050D02*
Y373410D01*
G01Y376050D02*
X260998Y376318D01*
X260843Y376625D01*
X260585Y376817D01*
X260223Y376893D01*
X259862Y376817D01*
X259552Y376587D01*
X259397Y376242D01*
Y375858D01*
X259293Y375628D01*
X259035Y375437D01*
X258673Y375360D01*
X258312Y375475D01*
X258053Y375743D01*
X257950Y376050D01*
X258053Y376357D01*
X258312Y376625D01*
X258673Y376740D01*
X259035Y376663D01*
X259293Y376472D01*
X259397Y376242D01*
Y375858D01*
X259552Y375513D01*
X259862Y375283D01*
X260223Y375207D01*
X260585Y375283D01*
X260843Y375475D01*
X260998Y375782D01*
X261050Y376050D01*
G01X258467Y378422D02*
X258157Y378652D01*
X258002Y378920D01*
X257950Y379227D01*
X258053Y379610D01*
X258312Y379878D01*
X258622Y379955D01*
X258932Y379917D01*
X259190Y379763D01*
X259707Y378997D01*
X260068Y378652D01*
X260585Y378422D01*
X261050Y378345D01*
Y379955D01*
G01X268708Y370693D02*
X268553Y370463D01*
X268450Y370195D01*
Y369888D01*
X268605Y369543D01*
X268863Y369275D01*
X269173Y369083D01*
X269690Y368930D01*
X270155Y368892D01*
X270620Y368968D01*
X270930Y369083D01*
X271240Y369313D01*
X271447Y369582D01*
X271550Y369850D01*
Y370118D01*
X271447Y370387D01*
X271292Y370617D01*
X271085Y370808D01*
G01X271550Y372950D02*
X268450D01*
X269070Y372490D01*
G01X271550D02*
Y373410D01*
G01Y376050D02*
X271498Y376318D01*
X271343Y376625D01*
X271085Y376817D01*
X270723Y376893D01*
X270362Y376817D01*
X270052Y376587D01*
X269897Y376242D01*
Y375858D01*
X269793Y375628D01*
X269535Y375437D01*
X269173Y375360D01*
X268812Y375475D01*
X268553Y375743D01*
X268450Y376050D01*
X268553Y376357D01*
X268812Y376625D01*
X269173Y376740D01*
X269535Y376663D01*
X269793Y376472D01*
X269897Y376242D01*
Y375858D01*
X270052Y375513D01*
X270362Y375283D01*
X270723Y375207D01*
X271085Y375283D01*
X271343Y375475D01*
X271498Y375782D01*
X271550Y376050D01*
G01Y379150D02*
X271498Y379418D01*
X271343Y379725D01*
X271085Y379917D01*
X270723Y379993D01*
X270362Y379917D01*
X270052Y379687D01*
X269897Y379342D01*
Y378958D01*
X269793Y378728D01*
X269535Y378537D01*
X269173Y378460D01*
X268812Y378575D01*
X268553Y378843D01*
X268450Y379150D01*
X268553Y379457D01*
X268812Y379725D01*
X269173Y379840D01*
X269535Y379763D01*
X269793Y379572D01*
X269897Y379342D01*
Y378958D01*
X270052Y378613D01*
X270362Y378383D01*
X270723Y378307D01*
X271085Y378383D01*
X271343Y378575D01*
X271498Y378882D01*
X271550Y379150D01*
G01X268708Y358193D02*
X268553Y357963D01*
X268450Y357695D01*
Y357388D01*
X268605Y357043D01*
X268863Y356775D01*
X269173Y356583D01*
X269690Y356430D01*
X270155Y356392D01*
X270620Y356468D01*
X270930Y356583D01*
X271240Y356813D01*
X271447Y357082D01*
X271550Y357350D01*
Y357618D01*
X271447Y357887D01*
X271292Y358117D01*
X271085Y358308D01*
G01X271550Y360450D02*
X268450D01*
X269070Y359990D01*
G01X271550D02*
Y360910D01*
G01X271188Y362898D02*
X271447Y363167D01*
X271550Y363473D01*
X271447Y363780D01*
X271137Y364048D01*
X270672Y364240D01*
X270207Y364317D01*
X269638D01*
X269173Y364240D01*
X268760Y364048D01*
X268553Y363818D01*
X268450Y363550D01*
X268553Y363243D01*
X268760Y363013D01*
X269070Y362860D01*
X269483Y362783D01*
X269845Y362860D01*
X270207Y363052D01*
X270413Y363282D01*
X270465Y363550D01*
X270362Y363857D01*
X270103Y364087D01*
X269638Y364317D01*
G01X270258Y365922D02*
X269897Y366190D01*
X269690Y366420D01*
X269587Y366727D01*
X269690Y366995D01*
X269897Y367187D01*
X270207Y367340D01*
X270568Y367378D01*
X270878Y367340D01*
X271188Y367187D01*
X271447Y366957D01*
X271550Y366688D01*
X271447Y366382D01*
X271137Y366113D01*
X270672Y365960D01*
X270155Y365922D01*
X269483Y365998D01*
X269122Y366113D01*
X268760Y366305D01*
X268502Y366573D01*
X268450Y366842D01*
X268553Y367110D01*
X268812Y367302D01*
G01X263208Y370693D02*
X263053Y370463D01*
X262950Y370195D01*
Y369888D01*
X263105Y369543D01*
X263363Y369275D01*
X263673Y369083D01*
X264190Y368930D01*
X264655Y368892D01*
X265120Y368968D01*
X265430Y369083D01*
X265740Y369313D01*
X265947Y369582D01*
X266050Y369850D01*
Y370118D01*
X265947Y370387D01*
X265792Y370617D01*
X265585Y370808D01*
G01X266050Y372950D02*
X262950D01*
X263570Y372490D01*
G01X266050D02*
Y373410D01*
G01Y376050D02*
X265998Y376318D01*
X265843Y376625D01*
X265585Y376817D01*
X265223Y376893D01*
X264862Y376817D01*
X264552Y376587D01*
X264397Y376242D01*
Y375858D01*
X264293Y375628D01*
X264035Y375437D01*
X263673Y375360D01*
X263312Y375475D01*
X263053Y375743D01*
X262950Y376050D01*
X263053Y376357D01*
X263312Y376625D01*
X263673Y376740D01*
X264035Y376663D01*
X264293Y376472D01*
X264397Y376242D01*
Y375858D01*
X264552Y375513D01*
X264862Y375283D01*
X265223Y375207D01*
X265585Y375283D01*
X265843Y375475D01*
X265998Y375782D01*
X266050Y376050D01*
G01X265585Y378307D02*
X265843Y378537D01*
X265998Y378805D01*
X266050Y379150D01*
X265947Y379495D01*
X265740Y379763D01*
X265378Y379955D01*
X264965Y379993D01*
X264552Y379917D01*
X264293Y379725D01*
X264087Y379457D01*
X264035Y379188D01*
X264087Y378920D01*
X264293Y378575D01*
X262950Y378690D01*
Y379725D01*
G01X263208Y358193D02*
X263053Y357963D01*
X262950Y357695D01*
Y357388D01*
X263105Y357043D01*
X263363Y356775D01*
X263673Y356583D01*
X264190Y356430D01*
X264655Y356392D01*
X265120Y356468D01*
X265430Y356583D01*
X265740Y356813D01*
X265947Y357082D01*
X266050Y357350D01*
Y357618D01*
X265947Y357887D01*
X265792Y358117D01*
X265585Y358308D01*
G01X266050Y360450D02*
X262950D01*
X263570Y359990D01*
G01X266050D02*
Y360910D01*
G01X265688Y362898D02*
X265947Y363167D01*
X266050Y363473D01*
X265947Y363780D01*
X265637Y364048D01*
X265172Y364240D01*
X264707Y364317D01*
X264138D01*
X263673Y364240D01*
X263260Y364048D01*
X263053Y363818D01*
X262950Y363550D01*
X263053Y363243D01*
X263260Y363013D01*
X263570Y362860D01*
X263983Y362783D01*
X264345Y362860D01*
X264707Y363052D01*
X264913Y363282D01*
X264965Y363550D01*
X264862Y363857D01*
X264603Y364087D01*
X264138Y364317D01*
G01X266050Y367110D02*
X262950D01*
X265172Y365692D01*
Y367608D01*
G01X290178Y56055D02*
Y59155D01*
X288760Y56933D01*
X290676D01*
G01X288757Y61932D02*
X288987Y61674D01*
X289255Y61519D01*
X289600Y61467D01*
X289945Y61570D01*
X290213Y61777D01*
X290405Y62139D01*
X290443Y62552D01*
X290367Y62965D01*
X290175Y63224D01*
X289907Y63430D01*
X289638Y63482D01*
X289370Y63430D01*
X289025Y63224D01*
X289140Y64567D01*
X290175D01*
G01X277207Y70550D02*
Y68328D01*
X277360Y67863D01*
X277667Y67553D01*
X278050Y67450D01*
X278433Y67553D01*
X278740Y67863D01*
X278893Y68328D01*
Y70550D01*
G01X280307Y68070D02*
X280537Y67708D01*
X280843Y67502D01*
X281188Y67450D01*
X281495Y67502D01*
X281802Y67760D01*
X281993Y68070D01*
X282032Y68380D01*
X281955Y68742D01*
X281687Y69000D01*
X281418Y69103D01*
X281073D01*
G01X281418D02*
X281648Y69258D01*
X281840Y69517D01*
X281917Y69827D01*
X281840Y70137D01*
X281648Y70395D01*
X281303Y70550D01*
X280958Y70498D01*
X280613Y70292D01*
G01X276523Y81890D02*
Y84990D01*
X277520Y82407D01*
X278517Y84990D01*
Y81890D01*
G01X279662D02*
X280620Y84990D01*
X281578Y81890D01*
G01X281233Y82975D02*
X280007D01*
G01X284563Y84732D02*
X284333Y84887D01*
X284065Y84990D01*
X283758D01*
X283413Y84835D01*
X283145Y84577D01*
X282953Y84267D01*
X282800Y83750D01*
X282762Y83285D01*
X282838Y82820D01*
X282953Y82510D01*
X283183Y82200D01*
X283452Y81993D01*
X283720Y81890D01*
X283988D01*
X284257Y81993D01*
X284487Y82148D01*
X284678Y82355D01*
G01X285670Y80857D02*
X287970D01*
G01X289153Y81890D02*
Y84990D01*
X290073D01*
X290380Y84835D01*
X290610Y84473D01*
X290687Y84060D01*
X290610Y83647D01*
X290418Y83337D01*
X290073Y83182D01*
X289153D01*
G01X292560Y84990D02*
X293480D01*
G01X293020D02*
Y81890D01*
G01X292560D02*
X293480D01*
G01X295238D02*
Y84990D01*
X297002Y81890D01*
Y84990D01*
G01X298492Y83182D02*
X298760Y83543D01*
X298990Y83750D01*
X299297Y83853D01*
X299565Y83750D01*
X299757Y83543D01*
X299910Y83233D01*
X299948Y82872D01*
X299910Y82562D01*
X299757Y82252D01*
X299527Y81993D01*
X299258Y81890D01*
X298952Y81993D01*
X298683Y82303D01*
X298530Y82768D01*
X298492Y83285D01*
X298568Y83957D01*
X298683Y84318D01*
X298875Y84680D01*
X299143Y84938D01*
X299412Y84990D01*
X299680Y84887D01*
X299872Y84628D01*
G01X285723Y92490D02*
Y95590D01*
X286720Y93007D01*
X287717Y95590D01*
Y92490D01*
G01X288862D02*
X289820Y95590D01*
X290778Y92490D01*
G01X290433Y93575D02*
X289207D01*
G01X293763Y95332D02*
X293533Y95487D01*
X293265Y95590D01*
X292958D01*
X292613Y95435D01*
X292345Y95177D01*
X292153Y94867D01*
X292000Y94350D01*
X291962Y93885D01*
X292038Y93420D01*
X292153Y93110D01*
X292383Y92800D01*
X292652Y92593D01*
X292920Y92490D01*
X293188D01*
X293457Y92593D01*
X293687Y92748D01*
X293878Y92955D01*
G01X294870Y91457D02*
X297170D01*
G01X298353Y92490D02*
Y95590D01*
X299273D01*
X299580Y95435D01*
X299810Y95073D01*
X299887Y94660D01*
X299810Y94247D01*
X299618Y93937D01*
X299273Y93782D01*
X298353D01*
G01X301760Y95590D02*
X302680D01*
G01X302220D02*
Y92490D01*
G01X301760D02*
X302680D01*
G01X304438D02*
Y95590D01*
X306202Y92490D01*
Y95590D01*
G01X308880Y92490D02*
Y95590D01*
X307462Y93368D01*
X309378D01*
G01X276903Y124950D02*
Y128050D01*
X277900Y125467D01*
X278897Y128050D01*
Y124950D01*
G01X281767D02*
X280233D01*
Y128050D01*
X281767D01*
G01X281153Y126552D02*
X280233D01*
G01X284100Y124950D02*
X284368Y125002D01*
X284675Y125157D01*
X284867Y125415D01*
X284943Y125777D01*
X284867Y126138D01*
X284637Y126448D01*
X284292Y126603D01*
X283908D01*
X283678Y126707D01*
X283487Y126965D01*
X283410Y127327D01*
X283525Y127688D01*
X283793Y127947D01*
X284100Y128050D01*
X284407Y127947D01*
X284675Y127688D01*
X284790Y127327D01*
X284713Y126965D01*
X284522Y126707D01*
X284292Y126603D01*
X283908D01*
X283563Y126448D01*
X283333Y126138D01*
X283257Y125777D01*
X283333Y125415D01*
X283525Y125157D01*
X283832Y125002D01*
X284100Y124950D01*
G01X278153Y274967D02*
Y278067D01*
X279150Y275484D01*
X280147Y278067D01*
Y274967D01*
G01X281292D02*
X282250Y278067D01*
X283208Y274967D01*
G01X282863Y276052D02*
X281637D01*
G01X286193Y277809D02*
X285963Y277964D01*
X285695Y278067D01*
X285388D01*
X285043Y277912D01*
X284775Y277654D01*
X284583Y277344D01*
X284430Y276827D01*
X284392Y276362D01*
X284468Y275897D01*
X284583Y275587D01*
X284813Y275277D01*
X285082Y275070D01*
X285350Y274967D01*
X285618D01*
X285887Y275070D01*
X286117Y275225D01*
X286308Y275432D01*
G01X287300Y273934D02*
X289600D01*
G01X290783Y274967D02*
Y278067D01*
X291703D01*
X292010Y277912D01*
X292240Y277550D01*
X292317Y277137D01*
X292240Y276724D01*
X292048Y276414D01*
X291703Y276259D01*
X290783D01*
G01X294190Y278067D02*
X295110D01*
G01X294650D02*
Y274967D01*
G01X294190D02*
X295110D01*
G01X296868D02*
Y278067D01*
X298632Y274967D01*
Y278067D01*
G01X300007Y275432D02*
X300237Y275174D01*
X300505Y275019D01*
X300850Y274967D01*
X301195Y275070D01*
X301463Y275277D01*
X301655Y275639D01*
X301693Y276052D01*
X301617Y276465D01*
X301425Y276724D01*
X301157Y276930D01*
X300888Y276982D01*
X300620Y276930D01*
X300275Y276724D01*
X300390Y278067D01*
X301425D01*
G01X287000Y298500D02*
Y314000D01*
G01X320000Y298500D02*
X287000D01*
G01X297500Y297000D02*
X284500D01*
G01D02*
Y335500D01*
G01X291550Y300583D02*
X288450D01*
Y301542D01*
X288605Y301848D01*
X288812Y302040D01*
X289225Y302117D01*
X289638Y302040D01*
X289897Y301810D01*
X290052Y301542D01*
Y300583D01*
G01Y301542D02*
X291550Y302117D01*
G01X290930Y303607D02*
X291292Y303837D01*
X291498Y304143D01*
X291550Y304488D01*
X291498Y304795D01*
X291240Y305102D01*
X290930Y305293D01*
X290620Y305332D01*
X290258Y305255D01*
X290000Y304987D01*
X289897Y304718D01*
Y304373D01*
G01Y304718D02*
X289742Y304948D01*
X289483Y305140D01*
X289173Y305217D01*
X288863Y305140D01*
X288605Y304948D01*
X288450Y304603D01*
X288502Y304258D01*
X288708Y303913D01*
G01X288450Y307550D02*
X288553Y307243D01*
X288812Y307013D01*
X289122Y306860D01*
X289535Y306745D01*
X290000Y306707D01*
X290465Y306745D01*
X290878Y306860D01*
X291188Y307013D01*
X291447Y307243D01*
X291550Y307550D01*
X291447Y307857D01*
X291188Y308087D01*
X290878Y308240D01*
X290465Y308355D01*
X290000Y308393D01*
X289535Y308355D01*
X289122Y308240D01*
X288812Y308087D01*
X288553Y307857D01*
X288450Y307550D01*
G01X290930Y309807D02*
X291292Y310037D01*
X291498Y310343D01*
X291550Y310688D01*
X291498Y310995D01*
X291240Y311302D01*
X290930Y311493D01*
X290620Y311532D01*
X290258Y311455D01*
X290000Y311187D01*
X289897Y310918D01*
Y310573D01*
G01Y310918D02*
X289742Y311148D01*
X289483Y311340D01*
X289173Y311417D01*
X288863Y311340D01*
X288605Y311148D01*
X288450Y310803D01*
X288502Y310458D01*
X288708Y310113D01*
G01X285083Y288450D02*
Y291550D01*
X286042D01*
X286348Y291395D01*
X286540Y291188D01*
X286617Y290775D01*
X286540Y290362D01*
X286310Y290103D01*
X286042Y289948D01*
X285083D01*
G01X286042D02*
X286617Y288450D01*
G01X288222Y291033D02*
X288452Y291343D01*
X288720Y291498D01*
X289027Y291550D01*
X289410Y291447D01*
X289678Y291188D01*
X289755Y290878D01*
X289717Y290568D01*
X289563Y290310D01*
X288797Y289793D01*
X288452Y289432D01*
X288222Y288915D01*
X288145Y288450D01*
X289755D01*
G01X291398Y288812D02*
X291667Y288553D01*
X291973Y288450D01*
X292280Y288553D01*
X292548Y288863D01*
X292740Y289328D01*
X292817Y289793D01*
Y290362D01*
X292740Y290827D01*
X292548Y291240D01*
X292318Y291447D01*
X292050Y291550D01*
X291743Y291447D01*
X291513Y291240D01*
X291360Y290930D01*
X291283Y290517D01*
X291360Y290155D01*
X291552Y289793D01*
X291782Y289587D01*
X292050Y289535D01*
X292357Y289638D01*
X292587Y289897D01*
X292817Y290362D01*
G01X295150Y291550D02*
X294843Y291447D01*
X294613Y291188D01*
X294460Y290878D01*
X294345Y290465D01*
X294307Y290000D01*
X294345Y289535D01*
X294460Y289122D01*
X294613Y288812D01*
X294843Y288553D01*
X295150Y288450D01*
X295457Y288553D01*
X295687Y288812D01*
X295840Y289122D01*
X295955Y289535D01*
X295993Y290000D01*
X295955Y290465D01*
X295840Y290878D01*
X295687Y291188D01*
X295457Y291447D01*
X295150Y291550D01*
G01X272583Y288950D02*
Y292050D01*
X273542D01*
X273848Y291895D01*
X274040Y291688D01*
X274117Y291275D01*
X274040Y290862D01*
X273810Y290603D01*
X273542Y290448D01*
X272583D01*
G01X273542D02*
X274117Y288950D01*
G01X275607Y289570D02*
X275837Y289208D01*
X276143Y289002D01*
X276488Y288950D01*
X276795Y289002D01*
X277102Y289260D01*
X277293Y289570D01*
X277332Y289880D01*
X277255Y290242D01*
X276987Y290500D01*
X276718Y290603D01*
X276373D01*
G01X276718D02*
X276948Y290758D01*
X277140Y291017D01*
X277217Y291327D01*
X277140Y291637D01*
X276948Y291895D01*
X276603Y292050D01*
X276258Y291998D01*
X275913Y291792D01*
G01X279550Y292050D02*
X279243Y291947D01*
X279013Y291688D01*
X278860Y291378D01*
X278745Y290965D01*
X278707Y290500D01*
X278745Y290035D01*
X278860Y289622D01*
X279013Y289312D01*
X279243Y289053D01*
X279550Y288950D01*
X279857Y289053D01*
X280087Y289312D01*
X280240Y289622D01*
X280355Y290035D01*
X280393Y290500D01*
X280355Y290965D01*
X280240Y291378D01*
X280087Y291688D01*
X279857Y291947D01*
X279550Y292050D01*
G01X281922Y291533D02*
X282152Y291843D01*
X282420Y291998D01*
X282727Y292050D01*
X283110Y291947D01*
X283378Y291688D01*
X283455Y291378D01*
X283417Y291068D01*
X283263Y290810D01*
X282497Y290293D01*
X282152Y289932D01*
X281922Y289415D01*
X281845Y288950D01*
X283455D01*
G01X272083Y296350D02*
Y299450D01*
X273042D01*
X273348Y299295D01*
X273540Y299088D01*
X273617Y298675D01*
X273540Y298262D01*
X273310Y298003D01*
X273042Y297848D01*
X272083D01*
G01X273042D02*
X273617Y296350D01*
G01X275222Y298933D02*
X275452Y299243D01*
X275720Y299398D01*
X276027Y299450D01*
X276410Y299347D01*
X276678Y299088D01*
X276755Y298778D01*
X276717Y298468D01*
X276563Y298210D01*
X275797Y297693D01*
X275452Y297332D01*
X275222Y296815D01*
X275145Y296350D01*
X276755D01*
G01X279050D02*
X279318Y296402D01*
X279625Y296557D01*
X279817Y296815D01*
X279893Y297177D01*
X279817Y297538D01*
X279587Y297848D01*
X279242Y298003D01*
X278858D01*
X278628Y298107D01*
X278437Y298365D01*
X278360Y298727D01*
X278475Y299088D01*
X278743Y299347D01*
X279050Y299450D01*
X279357Y299347D01*
X279625Y299088D01*
X279740Y298727D01*
X279663Y298365D01*
X279472Y298107D01*
X279242Y298003D01*
X278858D01*
X278513Y297848D01*
X278283Y297538D01*
X278207Y297177D01*
X278283Y296815D01*
X278475Y296557D01*
X278782Y296402D01*
X279050Y296350D01*
G01X281498Y296712D02*
X281767Y296453D01*
X282073Y296350D01*
X282380Y296453D01*
X282648Y296763D01*
X282840Y297228D01*
X282917Y297693D01*
Y298262D01*
X282840Y298727D01*
X282648Y299140D01*
X282418Y299347D01*
X282150Y299450D01*
X281843Y299347D01*
X281613Y299140D01*
X281460Y298830D01*
X281383Y298417D01*
X281460Y298055D01*
X281652Y297693D01*
X281882Y297487D01*
X282150Y297435D01*
X282457Y297538D01*
X282687Y297797D01*
X282917Y298262D01*
G01X272133Y300350D02*
Y303450D01*
X273092D01*
X273398Y303295D01*
X273590Y303088D01*
X273667Y302675D01*
X273590Y302262D01*
X273360Y302003D01*
X273092Y301848D01*
X272133D01*
G01X273092D02*
X273667Y300350D01*
G01X275923D02*
X276000Y301022D01*
X276115Y301590D01*
X276268Y302107D01*
X276460Y302675D01*
X276767Y303450D01*
X275233D01*
G01X278448Y300712D02*
X278717Y300453D01*
X279023Y300350D01*
X279330Y300453D01*
X279598Y300763D01*
X279790Y301228D01*
X279867Y301693D01*
Y302262D01*
X279790Y302727D01*
X279598Y303140D01*
X279368Y303347D01*
X279100Y303450D01*
X278793Y303347D01*
X278563Y303140D01*
X278410Y302830D01*
X278333Y302417D01*
X278410Y302055D01*
X278602Y301693D01*
X278832Y301487D01*
X279100Y301435D01*
X279407Y301538D01*
X279637Y301797D01*
X279867Y302262D01*
G01X287000Y314000D02*
X291500D01*
G01X272083Y309850D02*
Y312950D01*
X273042D01*
X273348Y312795D01*
X273540Y312588D01*
X273617Y312175D01*
X273540Y311762D01*
X273310Y311503D01*
X273042Y311348D01*
X272083D01*
G01X273042D02*
X273617Y309850D01*
G01X275107Y310470D02*
X275337Y310108D01*
X275643Y309902D01*
X275988Y309850D01*
X276295Y309902D01*
X276602Y310160D01*
X276793Y310470D01*
X276832Y310780D01*
X276755Y311142D01*
X276487Y311400D01*
X276218Y311503D01*
X275873D01*
G01X276218D02*
X276448Y311658D01*
X276640Y311917D01*
X276717Y312227D01*
X276640Y312537D01*
X276448Y312795D01*
X276103Y312950D01*
X275758Y312898D01*
X275413Y312692D01*
G01X279050Y312950D02*
X278743Y312847D01*
X278513Y312588D01*
X278360Y312278D01*
X278245Y311865D01*
X278207Y311400D01*
X278245Y310935D01*
X278360Y310522D01*
X278513Y310212D01*
X278743Y309953D01*
X279050Y309850D01*
X279357Y309953D01*
X279587Y310212D01*
X279740Y310522D01*
X279855Y310935D01*
X279893Y311400D01*
X279855Y311865D01*
X279740Y312278D01*
X279587Y312588D01*
X279357Y312847D01*
X279050Y312950D01*
G01X282150Y309850D02*
Y312950D01*
X281690Y312330D01*
G01Y309850D02*
X282610D01*
G01X272133Y304850D02*
Y307950D01*
X273092D01*
X273398Y307795D01*
X273590Y307588D01*
X273667Y307175D01*
X273590Y306762D01*
X273360Y306503D01*
X273092Y306348D01*
X272133D01*
G01X273092D02*
X273667Y304850D01*
G01X275923D02*
X276000Y305522D01*
X276115Y306090D01*
X276268Y306607D01*
X276460Y307175D01*
X276767Y307950D01*
X275233D01*
G01X279100Y304850D02*
X279368Y304902D01*
X279675Y305057D01*
X279867Y305315D01*
X279943Y305677D01*
X279867Y306038D01*
X279637Y306348D01*
X279292Y306503D01*
X278908D01*
X278678Y306607D01*
X278487Y306865D01*
X278410Y307227D01*
X278525Y307588D01*
X278793Y307847D01*
X279100Y307950D01*
X279407Y307847D01*
X279675Y307588D01*
X279790Y307227D01*
X279713Y306865D01*
X279522Y306607D01*
X279292Y306503D01*
X278908D01*
X278563Y306348D01*
X278333Y306038D01*
X278257Y305677D01*
X278333Y305315D01*
X278525Y305057D01*
X278832Y304902D01*
X279100Y304850D01*
G01X272083Y314350D02*
Y317450D01*
X273042D01*
X273348Y317295D01*
X273540Y317088D01*
X273617Y316675D01*
X273540Y316262D01*
X273310Y316003D01*
X273042Y315848D01*
X272083D01*
G01X273042D02*
X273617Y314350D01*
G01X275222Y316933D02*
X275452Y317243D01*
X275720Y317398D01*
X276027Y317450D01*
X276410Y317347D01*
X276678Y317088D01*
X276755Y316778D01*
X276717Y316468D01*
X276563Y316210D01*
X275797Y315693D01*
X275452Y315332D01*
X275222Y314815D01*
X275145Y314350D01*
X276755D01*
G01X278398Y314712D02*
X278667Y314453D01*
X278973Y314350D01*
X279280Y314453D01*
X279548Y314763D01*
X279740Y315228D01*
X279817Y315693D01*
Y316262D01*
X279740Y316727D01*
X279548Y317140D01*
X279318Y317347D01*
X279050Y317450D01*
X278743Y317347D01*
X278513Y317140D01*
X278360Y316830D01*
X278283Y316417D01*
X278360Y316055D01*
X278552Y315693D01*
X278782Y315487D01*
X279050Y315435D01*
X279357Y315538D01*
X279587Y315797D01*
X279817Y316262D01*
G01X282150Y314350D02*
Y317450D01*
X281690Y316830D01*
G01Y314350D02*
X282610D01*
G01X272083Y318850D02*
Y321950D01*
X273042D01*
X273348Y321795D01*
X273540Y321588D01*
X273617Y321175D01*
X273540Y320762D01*
X273310Y320503D01*
X273042Y320348D01*
X272083D01*
G01X273042D02*
X273617Y318850D01*
G01X275107Y319470D02*
X275337Y319108D01*
X275643Y318902D01*
X275988Y318850D01*
X276295Y318902D01*
X276602Y319160D01*
X276793Y319470D01*
X276832Y319780D01*
X276755Y320142D01*
X276487Y320400D01*
X276218Y320503D01*
X275873D01*
G01X276218D02*
X276448Y320658D01*
X276640Y320917D01*
X276717Y321227D01*
X276640Y321537D01*
X276448Y321795D01*
X276103Y321950D01*
X275758Y321898D01*
X275413Y321692D01*
G01X279050Y321950D02*
X278743Y321847D01*
X278513Y321588D01*
X278360Y321278D01*
X278245Y320865D01*
X278207Y320400D01*
X278245Y319935D01*
X278360Y319522D01*
X278513Y319212D01*
X278743Y318953D01*
X279050Y318850D01*
X279357Y318953D01*
X279587Y319212D01*
X279740Y319522D01*
X279855Y319935D01*
X279893Y320400D01*
X279855Y320865D01*
X279740Y321278D01*
X279587Y321588D01*
X279357Y321847D01*
X279050Y321950D01*
G01X281422Y320142D02*
X281690Y320503D01*
X281920Y320710D01*
X282227Y320813D01*
X282495Y320710D01*
X282687Y320503D01*
X282840Y320193D01*
X282878Y319832D01*
X282840Y319522D01*
X282687Y319212D01*
X282457Y318953D01*
X282188Y318850D01*
X281882Y318953D01*
X281613Y319263D01*
X281460Y319728D01*
X281422Y320245D01*
X281498Y320917D01*
X281613Y321278D01*
X281805Y321640D01*
X282073Y321898D01*
X282342Y321950D01*
X282610Y321847D01*
X282802Y321588D01*
G01X287243Y339792D02*
X287013Y339947D01*
X286745Y340050D01*
X286438D01*
X286093Y339895D01*
X285825Y339637D01*
X285633Y339327D01*
X285480Y338810D01*
X285442Y338345D01*
X285518Y337880D01*
X285633Y337570D01*
X285863Y337260D01*
X286132Y337053D01*
X286400Y336950D01*
X286668D01*
X286937Y337053D01*
X287167Y337208D01*
X287358Y337415D01*
G01X288657Y337570D02*
X288887Y337208D01*
X289193Y337002D01*
X289538Y336950D01*
X289845Y337002D01*
X290152Y337260D01*
X290343Y337570D01*
X290382Y337880D01*
X290305Y338242D01*
X290037Y338500D01*
X289768Y338603D01*
X289423D01*
G01X289768D02*
X289998Y338758D01*
X290190Y339017D01*
X290267Y339327D01*
X290190Y339637D01*
X289998Y339895D01*
X289653Y340050D01*
X289308Y339998D01*
X288963Y339792D01*
G01X292600Y336950D02*
X292868Y337002D01*
X293175Y337157D01*
X293367Y337415D01*
X293443Y337777D01*
X293367Y338138D01*
X293137Y338448D01*
X292792Y338603D01*
X292408D01*
X292178Y338707D01*
X291987Y338965D01*
X291910Y339327D01*
X292025Y339688D01*
X292293Y339947D01*
X292600Y340050D01*
X292907Y339947D01*
X293175Y339688D01*
X293290Y339327D01*
X293213Y338965D01*
X293022Y338707D01*
X292792Y338603D01*
X292408D01*
X292063Y338448D01*
X291833Y338138D01*
X291757Y337777D01*
X291833Y337415D01*
X292025Y337157D01*
X292332Y337002D01*
X292600Y336950D01*
G01X273693Y329792D02*
X273463Y329947D01*
X273195Y330050D01*
X272888D01*
X272543Y329895D01*
X272275Y329637D01*
X272083Y329327D01*
X271930Y328810D01*
X271892Y328345D01*
X271968Y327880D01*
X272083Y327570D01*
X272313Y327260D01*
X272582Y327053D01*
X272850Y326950D01*
X273118D01*
X273387Y327053D01*
X273617Y327208D01*
X273808Y327415D01*
G01X275222Y329533D02*
X275452Y329843D01*
X275720Y329998D01*
X276027Y330050D01*
X276410Y329947D01*
X276678Y329688D01*
X276755Y329378D01*
X276717Y329068D01*
X276563Y328810D01*
X275797Y328293D01*
X275452Y327932D01*
X275222Y327415D01*
X275145Y326950D01*
X276755D01*
G01X279050D02*
X279318Y327002D01*
X279625Y327157D01*
X279817Y327415D01*
X279893Y327777D01*
X279817Y328138D01*
X279587Y328448D01*
X279242Y328603D01*
X278858D01*
X278628Y328707D01*
X278437Y328965D01*
X278360Y329327D01*
X278475Y329688D01*
X278743Y329947D01*
X279050Y330050D01*
X279357Y329947D01*
X279625Y329688D01*
X279740Y329327D01*
X279663Y328965D01*
X279472Y328707D01*
X279242Y328603D01*
X278858D01*
X278513Y328448D01*
X278283Y328138D01*
X278207Y327777D01*
X278283Y327415D01*
X278475Y327157D01*
X278782Y327002D01*
X279050Y326950D01*
G01X281307Y327415D02*
X281537Y327157D01*
X281805Y327002D01*
X282150Y326950D01*
X282495Y327053D01*
X282763Y327260D01*
X282955Y327622D01*
X282993Y328035D01*
X282917Y328448D01*
X282725Y328707D01*
X282457Y328913D01*
X282188Y328965D01*
X281920Y328913D01*
X281575Y328707D01*
X281690Y330050D01*
X282725D01*
G01X272083Y330950D02*
Y334050D01*
X273042D01*
X273348Y333895D01*
X273540Y333688D01*
X273617Y333275D01*
X273540Y332862D01*
X273310Y332603D01*
X273042Y332448D01*
X272083D01*
G01X273042D02*
X273617Y330950D01*
G01X275107Y331570D02*
X275337Y331208D01*
X275643Y331002D01*
X275988Y330950D01*
X276295Y331002D01*
X276602Y331260D01*
X276793Y331570D01*
X276832Y331880D01*
X276755Y332242D01*
X276487Y332500D01*
X276218Y332603D01*
X275873D01*
G01X276218D02*
X276448Y332758D01*
X276640Y333017D01*
X276717Y333327D01*
X276640Y333637D01*
X276448Y333895D01*
X276103Y334050D01*
X275758Y333998D01*
X275413Y333792D01*
G01X279050Y334050D02*
X278743Y333947D01*
X278513Y333688D01*
X278360Y333378D01*
X278245Y332965D01*
X278207Y332500D01*
X278245Y332035D01*
X278360Y331622D01*
X278513Y331312D01*
X278743Y331053D01*
X279050Y330950D01*
X279357Y331053D01*
X279587Y331312D01*
X279740Y331622D01*
X279855Y332035D01*
X279893Y332500D01*
X279855Y332965D01*
X279740Y333378D01*
X279587Y333688D01*
X279357Y333947D01*
X279050Y334050D01*
G01X281307Y331415D02*
X281537Y331157D01*
X281805Y331002D01*
X282150Y330950D01*
X282495Y331053D01*
X282763Y331260D01*
X282955Y331622D01*
X282993Y332035D01*
X282917Y332448D01*
X282725Y332707D01*
X282457Y332913D01*
X282188Y332965D01*
X281920Y332913D01*
X281575Y332707D01*
X281690Y334050D01*
X282725D01*
G01X272083Y322950D02*
Y326050D01*
X273042D01*
X273348Y325895D01*
X273540Y325688D01*
X273617Y325275D01*
X273540Y324862D01*
X273310Y324603D01*
X273042Y324448D01*
X272083D01*
G01X273042D02*
X273617Y322950D01*
G01X275107Y323570D02*
X275337Y323208D01*
X275643Y323002D01*
X275988Y322950D01*
X276295Y323002D01*
X276602Y323260D01*
X276793Y323570D01*
X276832Y323880D01*
X276755Y324242D01*
X276487Y324500D01*
X276218Y324603D01*
X275873D01*
G01X276218D02*
X276448Y324758D01*
X276640Y325017D01*
X276717Y325327D01*
X276640Y325637D01*
X276448Y325895D01*
X276103Y326050D01*
X275758Y325998D01*
X275413Y325792D01*
G01X279050Y326050D02*
X278743Y325947D01*
X278513Y325688D01*
X278360Y325378D01*
X278245Y324965D01*
X278207Y324500D01*
X278245Y324035D01*
X278360Y323622D01*
X278513Y323312D01*
X278743Y323053D01*
X279050Y322950D01*
X279357Y323053D01*
X279587Y323312D01*
X279740Y323622D01*
X279855Y324035D01*
X279893Y324500D01*
X279855Y324965D01*
X279740Y325378D01*
X279587Y325688D01*
X279357Y325947D01*
X279050Y326050D01*
G01X282073Y322950D02*
X282150Y323622D01*
X282265Y324190D01*
X282418Y324707D01*
X282610Y325275D01*
X282917Y326050D01*
X281383D01*
G01X280500Y382500D02*
Y339500D01*
G01X285583Y340950D02*
Y344050D01*
X286542D01*
X286848Y343895D01*
X287040Y343688D01*
X287117Y343275D01*
X287040Y342862D01*
X286810Y342603D01*
X286542Y342448D01*
X285583D01*
G01X286542D02*
X287117Y340950D01*
G01X288607Y341570D02*
X288837Y341208D01*
X289143Y341002D01*
X289488Y340950D01*
X289795Y341002D01*
X290102Y341260D01*
X290293Y341570D01*
X290332Y341880D01*
X290255Y342242D01*
X289987Y342500D01*
X289718Y342603D01*
X289373D01*
G01X289718D02*
X289948Y342758D01*
X290140Y343017D01*
X290217Y343327D01*
X290140Y343637D01*
X289948Y343895D01*
X289603Y344050D01*
X289258Y343998D01*
X288913Y343792D01*
G01X292550Y340950D02*
Y344050D01*
X292090Y343430D01*
G01Y340950D02*
X293010D01*
G01X295650Y344050D02*
X295343Y343947D01*
X295113Y343688D01*
X294960Y343378D01*
X294845Y342965D01*
X294807Y342500D01*
X294845Y342035D01*
X294960Y341622D01*
X295113Y341312D01*
X295343Y341053D01*
X295650Y340950D01*
X295957Y341053D01*
X296187Y341312D01*
X296340Y341622D01*
X296455Y342035D01*
X296493Y342500D01*
X296455Y342965D01*
X296340Y343378D01*
X296187Y343688D01*
X295957Y343947D01*
X295650Y344050D01*
G01X285583Y344950D02*
Y348050D01*
X286542D01*
X286848Y347895D01*
X287040Y347688D01*
X287117Y347275D01*
X287040Y346862D01*
X286810Y346603D01*
X286542Y346448D01*
X285583D01*
G01X286542D02*
X287117Y344950D01*
G01X288607Y345570D02*
X288837Y345208D01*
X289143Y345002D01*
X289488Y344950D01*
X289795Y345002D01*
X290102Y345260D01*
X290293Y345570D01*
X290332Y345880D01*
X290255Y346242D01*
X289987Y346500D01*
X289718Y346603D01*
X289373D01*
G01X289718D02*
X289948Y346758D01*
X290140Y347017D01*
X290217Y347327D01*
X290140Y347637D01*
X289948Y347895D01*
X289603Y348050D01*
X289258Y347998D01*
X288913Y347792D01*
G01X292550Y344950D02*
Y348050D01*
X292090Y347430D01*
G01Y344950D02*
X293010D01*
G01X295650D02*
Y348050D01*
X295190Y347430D01*
G01Y344950D02*
X296110D01*
G01X283450Y383683D02*
X286550D01*
Y385217D01*
G01X283967Y386822D02*
X283657Y387052D01*
X283502Y387320D01*
X283450Y387627D01*
X283553Y388010D01*
X283812Y388278D01*
X284122Y388355D01*
X284432Y388317D01*
X284690Y388163D01*
X285207Y387397D01*
X285568Y387052D01*
X286085Y386822D01*
X286550Y386745D01*
Y388355D01*
G01X299707Y32103D02*
X299860Y32258D01*
X299975Y32517D01*
X300052Y32878D01*
X299975Y33188D01*
X299822Y33395D01*
X299553Y33550D01*
X298518D01*
Y30450D01*
X299783D01*
X300052Y30657D01*
X300205Y30967D01*
X300282Y31328D01*
X300205Y31690D01*
X299975Y32000D01*
X299707Y32103D01*
X298518D01*
G01X301657Y31070D02*
X301887Y30708D01*
X302193Y30502D01*
X302538Y30450D01*
X302845Y30502D01*
X303152Y30760D01*
X303343Y31070D01*
X303382Y31380D01*
X303305Y31742D01*
X303037Y32000D01*
X302768Y32103D01*
X302423D01*
G01X302768D02*
X302998Y32258D01*
X303190Y32517D01*
X303267Y32827D01*
X303190Y33137D01*
X302998Y33395D01*
X302653Y33550D01*
X302308Y33498D01*
X301963Y33292D01*
G01X304872Y33033D02*
X305102Y33343D01*
X305370Y33498D01*
X305677Y33550D01*
X306060Y33447D01*
X306328Y33188D01*
X306405Y32878D01*
X306367Y32568D01*
X306213Y32310D01*
X305447Y31793D01*
X305102Y31432D01*
X304872Y30915D01*
X304795Y30450D01*
X306405D01*
G01X294133Y50950D02*
Y54050D01*
X295092D01*
X295398Y53895D01*
X295590Y53688D01*
X295667Y53275D01*
X295590Y52862D01*
X295360Y52603D01*
X295092Y52448D01*
X294133D01*
G01X295092D02*
X295667Y50950D01*
G01X297157Y51415D02*
X297387Y51157D01*
X297655Y51002D01*
X298000Y50950D01*
X298345Y51053D01*
X298613Y51260D01*
X298805Y51622D01*
X298843Y52035D01*
X298767Y52448D01*
X298575Y52707D01*
X298307Y52913D01*
X298038Y52965D01*
X297770Y52913D01*
X297425Y52707D01*
X297540Y54050D01*
X298575D01*
G01X301023Y50950D02*
X301100Y51622D01*
X301215Y52190D01*
X301368Y52707D01*
X301560Y53275D01*
X301867Y54050D01*
X300333D01*
G01X296743Y79292D02*
X296513Y79447D01*
X296245Y79550D01*
X295938D01*
X295593Y79395D01*
X295325Y79137D01*
X295133Y78827D01*
X294980Y78310D01*
X294942Y77845D01*
X295018Y77380D01*
X295133Y77070D01*
X295363Y76760D01*
X295632Y76553D01*
X295900Y76450D01*
X296168D01*
X296437Y76553D01*
X296667Y76708D01*
X296858Y76915D01*
G01X298157Y77070D02*
X298387Y76708D01*
X298693Y76502D01*
X299038Y76450D01*
X299345Y76502D01*
X299652Y76760D01*
X299843Y77070D01*
X299882Y77380D01*
X299805Y77742D01*
X299537Y78000D01*
X299268Y78103D01*
X298923D01*
G01X299268D02*
X299498Y78258D01*
X299690Y78517D01*
X299767Y78827D01*
X299690Y79137D01*
X299498Y79395D01*
X299153Y79550D01*
X298808Y79498D01*
X298463Y79292D01*
G01X302023Y76450D02*
X302100Y77122D01*
X302215Y77690D01*
X302368Y78207D01*
X302560Y78775D01*
X302867Y79550D01*
X301333D01*
G01X295133Y72450D02*
Y75550D01*
X296092D01*
X296398Y75395D01*
X296590Y75188D01*
X296667Y74775D01*
X296590Y74362D01*
X296360Y74103D01*
X296092Y73948D01*
X295133D01*
G01X296092D02*
X296667Y72450D01*
G01X298272Y73742D02*
X298540Y74103D01*
X298770Y74310D01*
X299077Y74413D01*
X299345Y74310D01*
X299537Y74103D01*
X299690Y73793D01*
X299728Y73432D01*
X299690Y73122D01*
X299537Y72812D01*
X299307Y72553D01*
X299038Y72450D01*
X298732Y72553D01*
X298463Y72863D01*
X298310Y73328D01*
X298272Y73845D01*
X298348Y74517D01*
X298463Y74878D01*
X298655Y75240D01*
X298923Y75498D01*
X299192Y75550D01*
X299460Y75447D01*
X299652Y75188D01*
G01X301257Y73070D02*
X301487Y72708D01*
X301793Y72502D01*
X302138Y72450D01*
X302445Y72502D01*
X302752Y72760D01*
X302943Y73070D01*
X302982Y73380D01*
X302905Y73742D01*
X302637Y74000D01*
X302368Y74103D01*
X302023D01*
G01X302368D02*
X302598Y74258D01*
X302790Y74517D01*
X302867Y74827D01*
X302790Y75137D01*
X302598Y75395D01*
X302253Y75550D01*
X301908Y75498D01*
X301563Y75292D01*
G01X298950Y159350D02*
X302050D01*
G01X298950Y158468D02*
Y160232D01*
G01X302050Y161683D02*
X298950D01*
Y162603D01*
X299105Y162910D01*
X299467Y163140D01*
X299880Y163217D01*
X300293Y163140D01*
X300603Y162948D01*
X300758Y162603D01*
Y161683D01*
G01X301585Y164707D02*
X301843Y164937D01*
X301998Y165205D01*
X302050Y165550D01*
X301947Y165895D01*
X301740Y166163D01*
X301378Y166355D01*
X300965Y166393D01*
X300552Y166317D01*
X300293Y166125D01*
X300087Y165857D01*
X300035Y165588D01*
X300087Y165320D01*
X300293Y164975D01*
X298950Y165090D01*
Y166125D01*
G01X302050Y168650D02*
X298950D01*
X299570Y168190D01*
G01X302050D02*
Y169110D01*
G01X300683Y180450D02*
Y183550D01*
X301603D01*
X301910Y183395D01*
X302140Y183033D01*
X302217Y182620D01*
X302140Y182207D01*
X301948Y181897D01*
X301603Y181742D01*
X300683D01*
G01X304550Y180450D02*
Y183550D01*
X304090Y182930D01*
G01Y180450D02*
X305010D01*
G01X299393Y178333D02*
X299553Y178583D01*
X299740Y178708D01*
X299953Y178750D01*
X300220Y178667D01*
X300407Y178458D01*
X300460Y178208D01*
X300433Y177958D01*
X300327Y177750D01*
X299793Y177333D01*
X299553Y177042D01*
X299393Y176625D01*
X299340Y176250D01*
X300460D01*
G01X302100Y178750D02*
X301887Y178667D01*
X301727Y178458D01*
X301620Y178208D01*
X301540Y177875D01*
X301513Y177500D01*
X301540Y177125D01*
X301620Y176792D01*
X301727Y176542D01*
X301887Y176333D01*
X302100Y176250D01*
X302313Y176333D01*
X302473Y176542D01*
X302580Y176792D01*
X302660Y177125D01*
X302687Y177500D01*
X302660Y177875D01*
X302580Y178208D01*
X302473Y178458D01*
X302313Y178667D01*
X302100Y178750D01*
G01X298993Y195333D02*
X299153Y195583D01*
X299340Y195708D01*
X299553Y195750D01*
X299820Y195667D01*
X300007Y195458D01*
X300060Y195208D01*
X300033Y194958D01*
X299927Y194750D01*
X299393Y194333D01*
X299153Y194042D01*
X298993Y193625D01*
X298940Y193250D01*
X300060D01*
G01X297500Y287500D02*
X311000D01*
G01X297500D02*
Y297000D01*
G01X304208Y301693D02*
X304053Y301463D01*
X303950Y301195D01*
Y300888D01*
X304105Y300543D01*
X304363Y300275D01*
X304673Y300083D01*
X305190Y299930D01*
X305655Y299892D01*
X306120Y299968D01*
X306430Y300083D01*
X306740Y300313D01*
X306947Y300582D01*
X307050Y300850D01*
Y301118D01*
X306947Y301387D01*
X306792Y301617D01*
X306585Y301808D01*
G01X304467Y303222D02*
X304157Y303452D01*
X304002Y303720D01*
X303950Y304027D01*
X304053Y304410D01*
X304312Y304678D01*
X304622Y304755D01*
X304932Y304717D01*
X305190Y304563D01*
X305707Y303797D01*
X306068Y303452D01*
X306585Y303222D01*
X307050Y303145D01*
Y304755D01*
G01Y307050D02*
X306998Y307318D01*
X306843Y307625D01*
X306585Y307817D01*
X306223Y307893D01*
X305862Y307817D01*
X305552Y307587D01*
X305397Y307242D01*
Y306858D01*
X305293Y306628D01*
X305035Y306437D01*
X304673Y306360D01*
X304312Y306475D01*
X304053Y306743D01*
X303950Y307050D01*
X304053Y307357D01*
X304312Y307625D01*
X304673Y307740D01*
X305035Y307663D01*
X305293Y307472D01*
X305397Y307242D01*
Y306858D01*
X305552Y306513D01*
X305862Y306283D01*
X306223Y306207D01*
X306585Y306283D01*
X306843Y306475D01*
X306998Y306782D01*
X307050Y307050D01*
G01Y310150D02*
X303950D01*
X304570Y309690D01*
G01X307050D02*
Y310610D01*
G01X300208Y301693D02*
X300053Y301463D01*
X299950Y301195D01*
Y300888D01*
X300105Y300543D01*
X300363Y300275D01*
X300673Y300083D01*
X301190Y299930D01*
X301655Y299892D01*
X302120Y299968D01*
X302430Y300083D01*
X302740Y300313D01*
X302947Y300582D01*
X303050Y300850D01*
Y301118D01*
X302947Y301387D01*
X302792Y301617D01*
X302585Y301808D01*
G01X300467Y303222D02*
X300157Y303452D01*
X300002Y303720D01*
X299950Y304027D01*
X300053Y304410D01*
X300312Y304678D01*
X300622Y304755D01*
X300932Y304717D01*
X301190Y304563D01*
X301707Y303797D01*
X302068Y303452D01*
X302585Y303222D01*
X303050Y303145D01*
Y304755D01*
G01Y307050D02*
X302998Y307318D01*
X302843Y307625D01*
X302585Y307817D01*
X302223Y307893D01*
X301862Y307817D01*
X301552Y307587D01*
X301397Y307242D01*
Y306858D01*
X301293Y306628D01*
X301035Y306437D01*
X300673Y306360D01*
X300312Y306475D01*
X300053Y306743D01*
X299950Y307050D01*
X300053Y307357D01*
X300312Y307625D01*
X300673Y307740D01*
X301035Y307663D01*
X301293Y307472D01*
X301397Y307242D01*
Y306858D01*
X301552Y306513D01*
X301862Y306283D01*
X302223Y306207D01*
X302585Y306283D01*
X302843Y306475D01*
X302998Y306782D01*
X303050Y307050D01*
G01X299950Y310150D02*
X300053Y309843D01*
X300312Y309613D01*
X300622Y309460D01*
X301035Y309345D01*
X301500Y309307D01*
X301965Y309345D01*
X302378Y309460D01*
X302688Y309613D01*
X302947Y309843D01*
X303050Y310150D01*
X302947Y310457D01*
X302688Y310687D01*
X302378Y310840D01*
X301965Y310955D01*
X301500Y310993D01*
X301035Y310955D01*
X300622Y310840D01*
X300312Y310687D01*
X300053Y310457D01*
X299950Y310150D01*
G01X295550Y300583D02*
X292450D01*
Y301542D01*
X292605Y301848D01*
X292812Y302040D01*
X293225Y302117D01*
X293638Y302040D01*
X293897Y301810D01*
X294052Y301542D01*
Y300583D01*
G01Y301542D02*
X295550Y302117D01*
G01X294930Y303607D02*
X295292Y303837D01*
X295498Y304143D01*
X295550Y304488D01*
X295498Y304795D01*
X295240Y305102D01*
X294930Y305293D01*
X294620Y305332D01*
X294258Y305255D01*
X294000Y304987D01*
X293897Y304718D01*
Y304373D01*
G01Y304718D02*
X293742Y304948D01*
X293483Y305140D01*
X293173Y305217D01*
X292863Y305140D01*
X292605Y304948D01*
X292450Y304603D01*
X292502Y304258D01*
X292708Y303913D01*
G01X292450Y307550D02*
X292553Y307243D01*
X292812Y307013D01*
X293122Y306860D01*
X293535Y306745D01*
X294000Y306707D01*
X294465Y306745D01*
X294878Y306860D01*
X295188Y307013D01*
X295447Y307243D01*
X295550Y307550D01*
X295447Y307857D01*
X295188Y308087D01*
X294878Y308240D01*
X294465Y308355D01*
X294000Y308393D01*
X293535Y308355D01*
X293122Y308240D01*
X292812Y308087D01*
X292553Y307857D01*
X292450Y307550D01*
G01X295550Y311110D02*
X292450D01*
X294672Y309692D01*
Y311608D01*
G01X291500Y314000D02*
X324000D01*
G01X303450Y315450D02*
Y318550D01*
X302990Y317930D01*
G01Y315450D02*
X303910D01*
G01X305822Y316742D02*
X306090Y317103D01*
X306320Y317310D01*
X306627Y317413D01*
X306895Y317310D01*
X307087Y317103D01*
X307240Y316793D01*
X307278Y316432D01*
X307240Y316122D01*
X307087Y315812D01*
X306857Y315553D01*
X306588Y315450D01*
X306282Y315553D01*
X306013Y315863D01*
X305860Y316328D01*
X305822Y316845D01*
X305898Y317517D01*
X306013Y317878D01*
X306205Y318240D01*
X306473Y318498D01*
X306742Y318550D01*
X307010Y318447D01*
X307202Y318188D01*
G01X298952Y341638D02*
X298683Y341897D01*
X298377Y342000D01*
X298070Y341897D01*
X297802Y341587D01*
X297610Y341122D01*
X297533Y340657D01*
Y340088D01*
X297610Y339623D01*
X297802Y339210D01*
X298032Y339003D01*
X298300Y338900D01*
X298607Y339003D01*
X298837Y339210D01*
X298990Y339520D01*
X299067Y339933D01*
X298990Y340295D01*
X298798Y340657D01*
X298568Y340863D01*
X298300Y340915D01*
X297993Y340812D01*
X297763Y340553D01*
X297533Y340088D01*
G01X305272Y366033D02*
X305502Y366343D01*
X305770Y366498D01*
X306077Y366550D01*
X306460Y366447D01*
X306728Y366188D01*
X306805Y365878D01*
X306767Y365568D01*
X306613Y365310D01*
X305847Y364793D01*
X305502Y364432D01*
X305272Y363915D01*
X305195Y363450D01*
X306805D01*
G01X305000Y406450D02*
Y409550D01*
X304540Y408930D01*
G01Y406450D02*
X305460D01*
G01X307500Y165000D02*
Y162000D01*
X309500D01*
Y107000D01*
X324500D01*
Y174500D01*
G01X310583Y108450D02*
Y111550D01*
X311542D01*
X311848Y111395D01*
X312040Y111188D01*
X312117Y110775D01*
X312040Y110362D01*
X311810Y110103D01*
X311542Y109948D01*
X310583D01*
G01X311542D02*
X312117Y108450D01*
G01X313722Y111033D02*
X313952Y111343D01*
X314220Y111498D01*
X314527Y111550D01*
X314910Y111447D01*
X315178Y111188D01*
X315255Y110878D01*
X315217Y110568D01*
X315063Y110310D01*
X314297Y109793D01*
X313952Y109432D01*
X313722Y108915D01*
X313645Y108450D01*
X315255D01*
G01X317550D02*
X317818Y108502D01*
X318125Y108657D01*
X318317Y108915D01*
X318393Y109277D01*
X318317Y109638D01*
X318087Y109948D01*
X317742Y110103D01*
X317358D01*
X317128Y110207D01*
X316937Y110465D01*
X316860Y110827D01*
X316975Y111188D01*
X317243Y111447D01*
X317550Y111550D01*
X317857Y111447D01*
X318125Y111188D01*
X318240Y110827D01*
X318163Y110465D01*
X317972Y110207D01*
X317742Y110103D01*
X317358D01*
X317013Y109948D01*
X316783Y109638D01*
X316707Y109277D01*
X316783Y108915D01*
X316975Y108657D01*
X317282Y108502D01*
X317550Y108450D01*
G01X320573D02*
X320650Y109122D01*
X320765Y109690D01*
X320918Y110207D01*
X321110Y110775D01*
X321417Y111550D01*
X319883D01*
G01X310633Y122950D02*
Y126050D01*
X311592D01*
X311898Y125895D01*
X312090Y125688D01*
X312167Y125275D01*
X312090Y124862D01*
X311860Y124603D01*
X311592Y124448D01*
X310633D01*
G01X311592D02*
X312167Y122950D01*
G01X314500D02*
X314768Y123002D01*
X315075Y123157D01*
X315267Y123415D01*
X315343Y123777D01*
X315267Y124138D01*
X315037Y124448D01*
X314692Y124603D01*
X314308D01*
X314078Y124707D01*
X313887Y124965D01*
X313810Y125327D01*
X313925Y125688D01*
X314193Y125947D01*
X314500Y126050D01*
X314807Y125947D01*
X315075Y125688D01*
X315190Y125327D01*
X315113Y124965D01*
X314922Y124707D01*
X314692Y124603D01*
X314308D01*
X313963Y124448D01*
X313733Y124138D01*
X313657Y123777D01*
X313733Y123415D01*
X313925Y123157D01*
X314232Y123002D01*
X314500Y122950D01*
G01X317523D02*
X317600Y123622D01*
X317715Y124190D01*
X317868Y124707D01*
X318060Y125275D01*
X318367Y126050D01*
X316833D01*
G01X310633Y127950D02*
Y131050D01*
X311592D01*
X311898Y130895D01*
X312090Y130688D01*
X312167Y130275D01*
X312090Y129862D01*
X311860Y129603D01*
X311592Y129448D01*
X310633D01*
G01X311592D02*
X312167Y127950D01*
G01X313848Y128312D02*
X314117Y128053D01*
X314423Y127950D01*
X314730Y128053D01*
X314998Y128363D01*
X315190Y128828D01*
X315267Y129293D01*
Y129862D01*
X315190Y130327D01*
X314998Y130740D01*
X314768Y130947D01*
X314500Y131050D01*
X314193Y130947D01*
X313963Y130740D01*
X313810Y130430D01*
X313733Y130017D01*
X313810Y129655D01*
X314002Y129293D01*
X314232Y129087D01*
X314500Y129035D01*
X314807Y129138D01*
X315037Y129397D01*
X315267Y129862D01*
G01X317600Y127950D02*
X317868Y128002D01*
X318175Y128157D01*
X318367Y128415D01*
X318443Y128777D01*
X318367Y129138D01*
X318137Y129448D01*
X317792Y129603D01*
X317408D01*
X317178Y129707D01*
X316987Y129965D01*
X316910Y130327D01*
X317025Y130688D01*
X317293Y130947D01*
X317600Y131050D01*
X317907Y130947D01*
X318175Y130688D01*
X318290Y130327D01*
X318213Y129965D01*
X318022Y129707D01*
X317792Y129603D01*
X317408D01*
X317063Y129448D01*
X316833Y129138D01*
X316757Y128777D01*
X316833Y128415D01*
X317025Y128157D01*
X317332Y128002D01*
X317600Y127950D01*
G01X310633Y113450D02*
Y116550D01*
X311592D01*
X311898Y116395D01*
X312090Y116188D01*
X312167Y115775D01*
X312090Y115362D01*
X311860Y115103D01*
X311592Y114948D01*
X310633D01*
G01X311592D02*
X312167Y113450D01*
G01X313848Y113812D02*
X314117Y113553D01*
X314423Y113450D01*
X314730Y113553D01*
X314998Y113863D01*
X315190Y114328D01*
X315267Y114793D01*
Y115362D01*
X315190Y115827D01*
X314998Y116240D01*
X314768Y116447D01*
X314500Y116550D01*
X314193Y116447D01*
X313963Y116240D01*
X313810Y115930D01*
X313733Y115517D01*
X313810Y115155D01*
X314002Y114793D01*
X314232Y114587D01*
X314500Y114535D01*
X314807Y114638D01*
X315037Y114897D01*
X315267Y115362D01*
G01X316872Y114742D02*
X317140Y115103D01*
X317370Y115310D01*
X317677Y115413D01*
X317945Y115310D01*
X318137Y115103D01*
X318290Y114793D01*
X318328Y114432D01*
X318290Y114122D01*
X318137Y113812D01*
X317907Y113553D01*
X317638Y113450D01*
X317332Y113553D01*
X317063Y113863D01*
X316910Y114328D01*
X316872Y114845D01*
X316948Y115517D01*
X317063Y115878D01*
X317255Y116240D01*
X317523Y116498D01*
X317792Y116550D01*
X318060Y116447D01*
X318252Y116188D01*
G01X310633Y118450D02*
Y121550D01*
X311592D01*
X311898Y121395D01*
X312090Y121188D01*
X312167Y120775D01*
X312090Y120362D01*
X311860Y120103D01*
X311592Y119948D01*
X310633D01*
G01X311592D02*
X312167Y118450D01*
G01X314500D02*
X314768Y118502D01*
X315075Y118657D01*
X315267Y118915D01*
X315343Y119277D01*
X315267Y119638D01*
X315037Y119948D01*
X314692Y120103D01*
X314308D01*
X314078Y120207D01*
X313887Y120465D01*
X313810Y120827D01*
X313925Y121188D01*
X314193Y121447D01*
X314500Y121550D01*
X314807Y121447D01*
X315075Y121188D01*
X315190Y120827D01*
X315113Y120465D01*
X314922Y120207D01*
X314692Y120103D01*
X314308D01*
X313963Y119948D01*
X313733Y119638D01*
X313657Y119277D01*
X313733Y118915D01*
X313925Y118657D01*
X314232Y118502D01*
X314500Y118450D01*
G01X317600D02*
X317868Y118502D01*
X318175Y118657D01*
X318367Y118915D01*
X318443Y119277D01*
X318367Y119638D01*
X318137Y119948D01*
X317792Y120103D01*
X317408D01*
X317178Y120207D01*
X316987Y120465D01*
X316910Y120827D01*
X317025Y121188D01*
X317293Y121447D01*
X317600Y121550D01*
X317907Y121447D01*
X318175Y121188D01*
X318290Y120827D01*
X318213Y120465D01*
X318022Y120207D01*
X317792Y120103D01*
X317408D01*
X317063Y119948D01*
X316833Y119638D01*
X316757Y119277D01*
X316833Y118915D01*
X317025Y118657D01*
X317332Y118502D01*
X317600Y118450D01*
G01X311033Y137450D02*
Y140550D01*
X311992D01*
X312298Y140395D01*
X312490Y140188D01*
X312567Y139775D01*
X312490Y139362D01*
X312260Y139103D01*
X311992Y138948D01*
X311033D01*
G01X311992D02*
X312567Y137450D01*
G01X314900D02*
X315168Y137502D01*
X315475Y137657D01*
X315667Y137915D01*
X315743Y138277D01*
X315667Y138638D01*
X315437Y138948D01*
X315092Y139103D01*
X314708D01*
X314478Y139207D01*
X314287Y139465D01*
X314210Y139827D01*
X314325Y140188D01*
X314593Y140447D01*
X314900Y140550D01*
X315207Y140447D01*
X315475Y140188D01*
X315590Y139827D01*
X315513Y139465D01*
X315322Y139207D01*
X315092Y139103D01*
X314708D01*
X314363Y138948D01*
X314133Y138638D01*
X314057Y138277D01*
X314133Y137915D01*
X314325Y137657D01*
X314632Y137502D01*
X314900Y137450D01*
G01X317272Y138742D02*
X317540Y139103D01*
X317770Y139310D01*
X318077Y139413D01*
X318345Y139310D01*
X318537Y139103D01*
X318690Y138793D01*
X318728Y138432D01*
X318690Y138122D01*
X318537Y137812D01*
X318307Y137553D01*
X318038Y137450D01*
X317732Y137553D01*
X317463Y137863D01*
X317310Y138328D01*
X317272Y138845D01*
X317348Y139517D01*
X317463Y139878D01*
X317655Y140240D01*
X317923Y140498D01*
X318192Y140550D01*
X318460Y140447D01*
X318652Y140188D01*
G01X323000Y136583D02*
X319900D01*
Y137542D01*
X320055Y137848D01*
X320262Y138040D01*
X320675Y138117D01*
X321088Y138040D01*
X321347Y137810D01*
X321502Y137542D01*
Y136583D01*
G01Y137542D02*
X323000Y138117D01*
G01X320417Y139722D02*
X320107Y139952D01*
X319952Y140220D01*
X319900Y140527D01*
X320003Y140910D01*
X320262Y141178D01*
X320572Y141255D01*
X320882Y141217D01*
X321140Y141063D01*
X321657Y140297D01*
X322018Y139952D01*
X322535Y139722D01*
X323000Y139645D01*
Y141255D01*
G01Y143473D02*
X322328Y143550D01*
X321760Y143665D01*
X321243Y143818D01*
X320675Y144010D01*
X319900Y144317D01*
Y142783D01*
G01X321708Y145922D02*
X321347Y146190D01*
X321140Y146420D01*
X321037Y146727D01*
X321140Y146995D01*
X321347Y147187D01*
X321657Y147340D01*
X322018Y147378D01*
X322328Y147340D01*
X322638Y147187D01*
X322897Y146957D01*
X323000Y146688D01*
X322897Y146382D01*
X322587Y146113D01*
X322122Y145960D01*
X321605Y145922D01*
X320933Y145998D01*
X320572Y146113D01*
X320210Y146305D01*
X319952Y146573D01*
X319900Y146842D01*
X320003Y147110D01*
X320262Y147302D01*
G01X311133Y141500D02*
Y144600D01*
X312092D01*
X312398Y144445D01*
X312590Y144238D01*
X312667Y143825D01*
X312590Y143412D01*
X312360Y143153D01*
X312092Y142998D01*
X311133D01*
G01X312092D02*
X312667Y141500D01*
G01X315000D02*
X315268Y141552D01*
X315575Y141707D01*
X315767Y141965D01*
X315843Y142327D01*
X315767Y142688D01*
X315537Y142998D01*
X315192Y143153D01*
X314808D01*
X314578Y143257D01*
X314387Y143515D01*
X314310Y143877D01*
X314425Y144238D01*
X314693Y144497D01*
X315000Y144600D01*
X315307Y144497D01*
X315575Y144238D01*
X315690Y143877D01*
X315613Y143515D01*
X315422Y143257D01*
X315192Y143153D01*
X314808D01*
X314463Y142998D01*
X314233Y142688D01*
X314157Y142327D01*
X314233Y141965D01*
X314425Y141707D01*
X314732Y141552D01*
X315000Y141500D01*
G01X317257Y141965D02*
X317487Y141707D01*
X317755Y141552D01*
X318100Y141500D01*
X318445Y141603D01*
X318713Y141810D01*
X318905Y142172D01*
X318943Y142585D01*
X318867Y142998D01*
X318675Y143257D01*
X318407Y143463D01*
X318138Y143515D01*
X317870Y143463D01*
X317525Y143257D01*
X317640Y144600D01*
X318675D01*
G01X310633Y131950D02*
Y135050D01*
X311592D01*
X311898Y134895D01*
X312090Y134688D01*
X312167Y134275D01*
X312090Y133862D01*
X311860Y133603D01*
X311592Y133448D01*
X310633D01*
G01X311592D02*
X312167Y131950D01*
G01X313848Y132312D02*
X314117Y132053D01*
X314423Y131950D01*
X314730Y132053D01*
X314998Y132363D01*
X315190Y132828D01*
X315267Y133293D01*
Y133862D01*
X315190Y134327D01*
X314998Y134740D01*
X314768Y134947D01*
X314500Y135050D01*
X314193Y134947D01*
X313963Y134740D01*
X313810Y134430D01*
X313733Y134017D01*
X313810Y133655D01*
X314002Y133293D01*
X314232Y133087D01*
X314500Y133035D01*
X314807Y133138D01*
X315037Y133397D01*
X315267Y133862D01*
G01X317523Y131950D02*
X317600Y132622D01*
X317715Y133190D01*
X317868Y133707D01*
X318060Y134275D01*
X318367Y135050D01*
X316833D01*
G01X311133Y147950D02*
Y151050D01*
X312092D01*
X312398Y150895D01*
X312590Y150688D01*
X312667Y150275D01*
X312590Y149862D01*
X312360Y149603D01*
X312092Y149448D01*
X311133D01*
G01X312092D02*
X312667Y147950D01*
G01X315000D02*
X315268Y148002D01*
X315575Y148157D01*
X315767Y148415D01*
X315843Y148777D01*
X315767Y149138D01*
X315537Y149448D01*
X315192Y149603D01*
X314808D01*
X314578Y149707D01*
X314387Y149965D01*
X314310Y150327D01*
X314425Y150688D01*
X314693Y150947D01*
X315000Y151050D01*
X315307Y150947D01*
X315575Y150688D01*
X315690Y150327D01*
X315613Y149965D01*
X315422Y149707D01*
X315192Y149603D01*
X314808D01*
X314463Y149448D01*
X314233Y149138D01*
X314157Y148777D01*
X314233Y148415D01*
X314425Y148157D01*
X314732Y148002D01*
X315000Y147950D01*
G01X318560D02*
Y151050D01*
X317142Y148828D01*
X319058D01*
G01X323500Y149583D02*
X320400D01*
Y150542D01*
X320555Y150848D01*
X320762Y151040D01*
X321175Y151117D01*
X321588Y151040D01*
X321847Y150810D01*
X322002Y150542D01*
Y149583D01*
G01Y150542D02*
X323500Y151117D01*
G01X320917Y152722D02*
X320607Y152952D01*
X320452Y153220D01*
X320400Y153527D01*
X320503Y153910D01*
X320762Y154178D01*
X321072Y154255D01*
X321382Y154217D01*
X321640Y154063D01*
X322157Y153297D01*
X322518Y152952D01*
X323035Y152722D01*
X323500Y152645D01*
Y154255D01*
G01Y156473D02*
X322828Y156550D01*
X322260Y156665D01*
X321743Y156818D01*
X321175Y157010D01*
X320400Y157317D01*
Y155783D01*
G01X323500Y159573D02*
X322828Y159650D01*
X322260Y159765D01*
X321743Y159918D01*
X321175Y160110D01*
X320400Y160417D01*
Y158883D01*
G01X311133Y151950D02*
Y155050D01*
X312092D01*
X312398Y154895D01*
X312590Y154688D01*
X312667Y154275D01*
X312590Y153862D01*
X312360Y153603D01*
X312092Y153448D01*
X311133D01*
G01X312092D02*
X312667Y151950D01*
G01X315000D02*
X315268Y152002D01*
X315575Y152157D01*
X315767Y152415D01*
X315843Y152777D01*
X315767Y153138D01*
X315537Y153448D01*
X315192Y153603D01*
X314808D01*
X314578Y153707D01*
X314387Y153965D01*
X314310Y154327D01*
X314425Y154688D01*
X314693Y154947D01*
X315000Y155050D01*
X315307Y154947D01*
X315575Y154688D01*
X315690Y154327D01*
X315613Y153965D01*
X315422Y153707D01*
X315192Y153603D01*
X314808D01*
X314463Y153448D01*
X314233Y153138D01*
X314157Y152777D01*
X314233Y152415D01*
X314425Y152157D01*
X314732Y152002D01*
X315000Y151950D01*
G01X317257Y152570D02*
X317487Y152208D01*
X317793Y152002D01*
X318138Y151950D01*
X318445Y152002D01*
X318752Y152260D01*
X318943Y152570D01*
X318982Y152880D01*
X318905Y153242D01*
X318637Y153500D01*
X318368Y153603D01*
X318023D01*
G01X318368D02*
X318598Y153758D01*
X318790Y154017D01*
X318867Y154327D01*
X318790Y154637D01*
X318598Y154895D01*
X318253Y155050D01*
X317908Y154998D01*
X317563Y154792D01*
G01X307500Y185500D02*
Y179500D01*
G01X310500Y197500D02*
Y195000D01*
X308000D01*
Y190000D01*
G01X310000Y213500D02*
Y259500D01*
G01X331000Y213500D02*
X310000D01*
G01X314000Y213000D02*
X311000D01*
Y210500D01*
G01Y207000D02*
Y200500D01*
G01X323500Y219000D02*
X329000D01*
G01X323000Y226000D02*
Y222500D01*
G01Y235000D02*
Y229000D01*
G01Y258000D02*
Y237500D01*
G01X310000Y259500D02*
X321000D01*
G01X311000Y287500D02*
Y260500D01*
G01D02*
X313500Y264500D01*
G01X311000Y260500D02*
X309500Y264500D01*
G01X315200Y267250D02*
Y264750D01*
G01X314587Y267250D02*
X315813D01*
G01X316867Y264750D02*
Y267250D01*
X317507D01*
X317720Y267125D01*
X317880Y266833D01*
X317933Y266500D01*
X317880Y266167D01*
X317747Y265917D01*
X317507Y265792D01*
X316867D01*
G01X319600Y264750D02*
Y267250D01*
X319280Y266750D01*
G01Y264750D02*
X319920D01*
G01X321293Y265792D02*
X321480Y266083D01*
X321640Y266250D01*
X321853Y266333D01*
X322040Y266250D01*
X322173Y266083D01*
X322280Y265833D01*
X322307Y265542D01*
X322280Y265292D01*
X322173Y265042D01*
X322013Y264833D01*
X321827Y264750D01*
X321613Y264833D01*
X321427Y265083D01*
X321320Y265458D01*
X321293Y265875D01*
X321347Y266417D01*
X321427Y266708D01*
X321560Y267000D01*
X321747Y267208D01*
X321933Y267250D01*
X322120Y267167D01*
X322253Y266958D01*
G01X324200Y269750D02*
Y267250D01*
G01X323587Y269750D02*
X324813D01*
G01X325867Y267250D02*
Y269750D01*
X326507D01*
X326720Y269625D01*
X326880Y269333D01*
X326933Y269000D01*
X326880Y268667D01*
X326747Y268417D01*
X326507Y268292D01*
X325867D01*
G01X328600Y267250D02*
Y269750D01*
X328280Y269250D01*
G01Y267250D02*
X328920D01*
G01X330747D02*
X330800Y267792D01*
X330880Y268250D01*
X330987Y268667D01*
X331120Y269125D01*
X331333Y269750D01*
X330267D01*
G01X312772Y281533D02*
X313002Y281843D01*
X313270Y281998D01*
X313577Y282050D01*
X313960Y281947D01*
X314228Y281688D01*
X314305Y281378D01*
X314267Y281068D01*
X314113Y280810D01*
X313347Y280293D01*
X313002Y279932D01*
X312772Y279415D01*
X312695Y278950D01*
X314305D01*
G01X320000Y305500D02*
Y298500D01*
G01X315208Y301193D02*
X315053Y300963D01*
X314950Y300695D01*
Y300388D01*
X315105Y300043D01*
X315363Y299775D01*
X315673Y299583D01*
X316190Y299430D01*
X316655Y299392D01*
X317120Y299468D01*
X317430Y299583D01*
X317740Y299813D01*
X317947Y300082D01*
X318050Y300350D01*
Y300618D01*
X317947Y300887D01*
X317792Y301117D01*
X317585Y301308D01*
G01X315467Y302722D02*
X315157Y302952D01*
X315002Y303220D01*
X314950Y303527D01*
X315053Y303910D01*
X315312Y304178D01*
X315622Y304255D01*
X315932Y304217D01*
X316190Y304063D01*
X316707Y303297D01*
X317068Y302952D01*
X317585Y302722D01*
X318050Y302645D01*
Y304255D01*
G01Y306473D02*
X317378Y306550D01*
X316810Y306665D01*
X316293Y306818D01*
X315725Y307010D01*
X314950Y307317D01*
Y305783D01*
G01X317688Y308998D02*
X317947Y309267D01*
X318050Y309573D01*
X317947Y309880D01*
X317637Y310148D01*
X317172Y310340D01*
X316707Y310417D01*
X316138D01*
X315673Y310340D01*
X315260Y310148D01*
X315053Y309918D01*
X314950Y309650D01*
X315053Y309343D01*
X315260Y309113D01*
X315570Y308960D01*
X315983Y308883D01*
X316345Y308960D01*
X316707Y309152D01*
X316913Y309382D01*
X316965Y309650D01*
X316862Y309957D01*
X316603Y310187D01*
X316138Y310417D01*
G01X313960Y288450D02*
Y291550D01*
X312542Y289328D01*
X314458D01*
G01X307950Y300133D02*
X311050D01*
Y301667D01*
G01Y304000D02*
X307950D01*
X308570Y303540D01*
G01X311050D02*
Y304460D01*
G01X310688Y306448D02*
X310947Y306717D01*
X311050Y307023D01*
X310947Y307330D01*
X310637Y307598D01*
X310172Y307790D01*
X309707Y307867D01*
X309138D01*
X308673Y307790D01*
X308260Y307598D01*
X308053Y307368D01*
X307950Y307100D01*
X308053Y306793D01*
X308260Y306563D01*
X308570Y306410D01*
X308983Y306333D01*
X309345Y306410D01*
X309707Y306602D01*
X309913Y306832D01*
X309965Y307100D01*
X309862Y307407D01*
X309603Y307637D01*
X309138Y307867D01*
G01X320042Y306950D02*
X321000Y310050D01*
X321958Y306950D01*
G01X321613Y308035D02*
X320387D01*
G01X324000Y305500D02*
X320000D01*
G01X309500Y348000D02*
X329000D01*
G01X309500Y368000D02*
Y348000D01*
G01X312607Y347100D02*
Y344878D01*
X312760Y344413D01*
X313067Y344103D01*
X313450Y344000D01*
X313833Y344103D01*
X314140Y344413D01*
X314293Y344878D01*
Y347100D01*
G01X317010Y344000D02*
Y347100D01*
X315592Y344878D01*
X317508D01*
G01X310708Y351243D02*
X310553Y351013D01*
X310450Y350745D01*
Y350438D01*
X310605Y350093D01*
X310863Y349825D01*
X311173Y349633D01*
X311690Y349480D01*
X312155Y349442D01*
X312620Y349518D01*
X312930Y349633D01*
X313240Y349863D01*
X313447Y350132D01*
X313550Y350400D01*
Y350668D01*
X313447Y350937D01*
X313292Y351167D01*
X313085Y351358D01*
G01X313550Y353500D02*
X310450D01*
X311070Y353040D01*
G01X313550D02*
Y353960D01*
G01Y356600D02*
X313498Y356868D01*
X313343Y357175D01*
X313085Y357367D01*
X312723Y357443D01*
X312362Y357367D01*
X312052Y357137D01*
X311897Y356792D01*
Y356408D01*
X311793Y356178D01*
X311535Y355987D01*
X311173Y355910D01*
X310812Y356025D01*
X310553Y356293D01*
X310450Y356600D01*
X310553Y356907D01*
X310812Y357175D01*
X311173Y357290D01*
X311535Y357213D01*
X311793Y357022D01*
X311897Y356792D01*
Y356408D01*
X312052Y356063D01*
X312362Y355833D01*
X312723Y355757D01*
X313085Y355833D01*
X313343Y356025D01*
X313498Y356332D01*
X313550Y356600D01*
G01X319708Y351243D02*
X319553Y351013D01*
X319450Y350745D01*
Y350438D01*
X319605Y350093D01*
X319863Y349825D01*
X320173Y349633D01*
X320690Y349480D01*
X321155Y349442D01*
X321620Y349518D01*
X321930Y349633D01*
X322240Y349863D01*
X322447Y350132D01*
X322550Y350400D01*
Y350668D01*
X322447Y350937D01*
X322292Y351167D01*
X322085Y351358D01*
G01X319967Y352772D02*
X319657Y353002D01*
X319502Y353270D01*
X319450Y353577D01*
X319553Y353960D01*
X319812Y354228D01*
X320122Y354305D01*
X320432Y354267D01*
X320690Y354113D01*
X321207Y353347D01*
X321568Y353002D01*
X322085Y352772D01*
X322550Y352695D01*
Y354305D01*
G01X319967Y355872D02*
X319657Y356102D01*
X319502Y356370D01*
X319450Y356677D01*
X319553Y357060D01*
X319812Y357328D01*
X320122Y357405D01*
X320432Y357367D01*
X320690Y357213D01*
X321207Y356447D01*
X321568Y356102D01*
X322085Y355872D01*
X322550Y355795D01*
Y357405D01*
G01X323708Y351243D02*
X323553Y351013D01*
X323450Y350745D01*
Y350438D01*
X323605Y350093D01*
X323863Y349825D01*
X324173Y349633D01*
X324690Y349480D01*
X325155Y349442D01*
X325620Y349518D01*
X325930Y349633D01*
X326240Y349863D01*
X326447Y350132D01*
X326550Y350400D01*
Y350668D01*
X326447Y350937D01*
X326292Y351167D01*
X326085Y351358D01*
G01X323967Y352772D02*
X323657Y353002D01*
X323502Y353270D01*
X323450Y353577D01*
X323553Y353960D01*
X323812Y354228D01*
X324122Y354305D01*
X324432Y354267D01*
X324690Y354113D01*
X325207Y353347D01*
X325568Y353002D01*
X326085Y352772D01*
X326550Y352695D01*
Y354305D01*
G01X323450Y356600D02*
X323553Y356293D01*
X323812Y356063D01*
X324122Y355910D01*
X324535Y355795D01*
X325000Y355757D01*
X325465Y355795D01*
X325878Y355910D01*
X326188Y356063D01*
X326447Y356293D01*
X326550Y356600D01*
X326447Y356907D01*
X326188Y357137D01*
X325878Y357290D01*
X325465Y357405D01*
X325000Y357443D01*
X324535Y357405D01*
X324122Y357290D01*
X323812Y357137D01*
X323553Y356907D01*
X323450Y356600D01*
G01X315208Y351243D02*
X315053Y351013D01*
X314950Y350745D01*
Y350438D01*
X315105Y350093D01*
X315363Y349825D01*
X315673Y349633D01*
X316190Y349480D01*
X316655Y349442D01*
X317120Y349518D01*
X317430Y349633D01*
X317740Y349863D01*
X317947Y350132D01*
X318050Y350400D01*
Y350668D01*
X317947Y350937D01*
X317792Y351167D01*
X317585Y351358D01*
G01X315467Y352772D02*
X315157Y353002D01*
X315002Y353270D01*
X314950Y353577D01*
X315053Y353960D01*
X315312Y354228D01*
X315622Y354305D01*
X315932Y354267D01*
X316190Y354113D01*
X316707Y353347D01*
X317068Y353002D01*
X317585Y352772D01*
X318050Y352695D01*
Y354305D01*
G01Y356600D02*
X314950D01*
X315570Y356140D01*
G01X318050D02*
Y357060D01*
G01X322500Y368000D02*
X309500D01*
G01X322500Y389500D02*
Y368000D01*
G01X312243Y365792D02*
X312013Y365947D01*
X311745Y366050D01*
X311438D01*
X311093Y365895D01*
X310825Y365637D01*
X310633Y365327D01*
X310480Y364810D01*
X310442Y364345D01*
X310518Y363880D01*
X310633Y363570D01*
X310863Y363260D01*
X311132Y363053D01*
X311400Y362950D01*
X311668D01*
X311937Y363053D01*
X312167Y363208D01*
X312358Y363415D01*
G01X313657D02*
X313887Y363157D01*
X314155Y363002D01*
X314500Y362950D01*
X314845Y363053D01*
X315113Y363260D01*
X315305Y363622D01*
X315343Y364035D01*
X315267Y364448D01*
X315075Y364707D01*
X314807Y364913D01*
X314538Y364965D01*
X314270Y364913D01*
X313925Y364707D01*
X314040Y366050D01*
X315075D01*
G01X316872Y365533D02*
X317102Y365843D01*
X317370Y365998D01*
X317677Y366050D01*
X318060Y365947D01*
X318328Y365688D01*
X318405Y365378D01*
X318367Y365068D01*
X318213Y364810D01*
X317447Y364293D01*
X317102Y363932D01*
X316872Y363415D01*
X316795Y362950D01*
X318405D01*
G01X312243Y361792D02*
X312013Y361947D01*
X311745Y362050D01*
X311438D01*
X311093Y361895D01*
X310825Y361637D01*
X310633Y361327D01*
X310480Y360810D01*
X310442Y360345D01*
X310518Y359880D01*
X310633Y359570D01*
X310863Y359260D01*
X311132Y359053D01*
X311400Y358950D01*
X311668D01*
X311937Y359053D01*
X312167Y359208D01*
X312358Y359415D01*
G01X314960Y358950D02*
Y362050D01*
X313542Y359828D01*
X315458D01*
G01X317600Y358950D02*
X317868Y359002D01*
X318175Y359157D01*
X318367Y359415D01*
X318443Y359777D01*
X318367Y360138D01*
X318137Y360448D01*
X317792Y360603D01*
X317408D01*
X317178Y360707D01*
X316987Y360965D01*
X316910Y361327D01*
X317025Y361688D01*
X317293Y361947D01*
X317600Y362050D01*
X317907Y361947D01*
X318175Y361688D01*
X318290Y361327D01*
X318213Y360965D01*
X318022Y360707D01*
X317792Y360603D01*
X317408D01*
X317063Y360448D01*
X316833Y360138D01*
X316757Y359777D01*
X316833Y359415D01*
X317025Y359157D01*
X317332Y359002D01*
X317600Y358950D01*
G01X322550Y359133D02*
X319450D01*
Y360092D01*
X319605Y360398D01*
X319812Y360590D01*
X320225Y360667D01*
X320638Y360590D01*
X320897Y360360D01*
X321052Y360092D01*
Y359133D01*
G01Y360092D02*
X322550Y360667D01*
G01X321930Y362157D02*
X322292Y362387D01*
X322498Y362693D01*
X322550Y363038D01*
X322498Y363345D01*
X322240Y363652D01*
X321930Y363843D01*
X321620Y363882D01*
X321258Y363805D01*
X321000Y363537D01*
X320897Y363268D01*
Y362923D01*
G01Y363268D02*
X320742Y363498D01*
X320483Y363690D01*
X320173Y363767D01*
X319863Y363690D01*
X319605Y363498D01*
X319450Y363153D01*
X319502Y362808D01*
X319708Y362463D01*
G01X322085Y365257D02*
X322343Y365487D01*
X322498Y365755D01*
X322550Y366100D01*
X322447Y366445D01*
X322240Y366713D01*
X321878Y366905D01*
X321465Y366943D01*
X321052Y366867D01*
X320793Y366675D01*
X320587Y366407D01*
X320535Y366138D01*
X320587Y365870D01*
X320793Y365525D01*
X319450Y365640D01*
Y366675D01*
G01X327500Y389500D02*
X322500D01*
G01X323500Y392250D02*
X323687Y392292D01*
X323900Y392417D01*
X324033Y392625D01*
X324087Y392917D01*
X324033Y393208D01*
X323873Y393458D01*
X323633Y393583D01*
X323367D01*
X323207Y393667D01*
X323073Y393875D01*
X323020Y394167D01*
X323100Y394458D01*
X323287Y394667D01*
X323500Y394750D01*
X323713Y394667D01*
X323900Y394458D01*
X323980Y394167D01*
X323927Y393875D01*
X323793Y393667D01*
X323633Y393583D01*
X323367D01*
X323127Y393458D01*
X322967Y393208D01*
X322913Y392917D01*
X322967Y392625D01*
X323100Y392417D01*
X323313Y392292D01*
X323500Y392250D01*
G01X324447Y397250D02*
X324500Y397792D01*
X324580Y398250D01*
X324687Y398667D01*
X324820Y399125D01*
X325033Y399750D01*
X323967D01*
G01X317543Y414492D02*
X317313Y414647D01*
X317045Y414750D01*
X316738D01*
X316393Y414595D01*
X316125Y414337D01*
X315933Y414027D01*
X315780Y413510D01*
X315742Y413045D01*
X315818Y412580D01*
X315933Y412270D01*
X316163Y411960D01*
X316432Y411753D01*
X316700Y411650D01*
X316968D01*
X317237Y411753D01*
X317467Y411908D01*
X317658Y412115D01*
G01X318957D02*
X319187Y411857D01*
X319455Y411702D01*
X319800Y411650D01*
X320145Y411753D01*
X320413Y411960D01*
X320605Y412322D01*
X320643Y412735D01*
X320567Y413148D01*
X320375Y413407D01*
X320107Y413613D01*
X319838Y413665D01*
X319570Y413613D01*
X319225Y413407D01*
X319340Y414750D01*
X320375D01*
G01X322057Y412270D02*
X322287Y411908D01*
X322593Y411702D01*
X322938Y411650D01*
X323245Y411702D01*
X323552Y411960D01*
X323743Y412270D01*
X323782Y412580D01*
X323705Y412942D01*
X323437Y413200D01*
X323168Y413303D01*
X322823D01*
G01X323168D02*
X323398Y413458D01*
X323590Y413717D01*
X323667Y414027D01*
X323590Y414337D01*
X323398Y414595D01*
X323053Y414750D01*
X322708Y414698D01*
X322363Y414492D01*
G01X340193Y97792D02*
X339963Y97947D01*
X339695Y98050D01*
X339388D01*
X339043Y97895D01*
X338775Y97637D01*
X338583Y97327D01*
X338430Y96810D01*
X338392Y96345D01*
X338468Y95880D01*
X338583Y95570D01*
X338813Y95260D01*
X339082Y95053D01*
X339350Y94950D01*
X339618D01*
X339887Y95053D01*
X340117Y95208D01*
X340308Y95415D01*
G01X341722Y97533D02*
X341952Y97843D01*
X342220Y97998D01*
X342527Y98050D01*
X342910Y97947D01*
X343178Y97688D01*
X343255Y97378D01*
X343217Y97068D01*
X343063Y96810D01*
X342297Y96293D01*
X341952Y95932D01*
X341722Y95415D01*
X341645Y94950D01*
X343255D01*
G01X346010D02*
Y98050D01*
X344592Y95828D01*
X346508D01*
G01X347998Y95312D02*
X348267Y95053D01*
X348573Y94950D01*
X348880Y95053D01*
X349148Y95363D01*
X349340Y95828D01*
X349417Y96293D01*
Y96862D01*
X349340Y97327D01*
X349148Y97740D01*
X348918Y97947D01*
X348650Y98050D01*
X348343Y97947D01*
X348113Y97740D01*
X347960Y97430D01*
X347883Y97017D01*
X347960Y96655D01*
X348152Y96293D01*
X348382Y96087D01*
X348650Y96035D01*
X348957Y96138D01*
X349187Y96397D01*
X349417Y96862D01*
G01X327693Y97292D02*
X327463Y97447D01*
X327195Y97550D01*
X326888D01*
X326543Y97395D01*
X326275Y97137D01*
X326083Y96827D01*
X325930Y96310D01*
X325892Y95845D01*
X325968Y95380D01*
X326083Y95070D01*
X326313Y94760D01*
X326582Y94553D01*
X326850Y94450D01*
X327118D01*
X327387Y94553D01*
X327617Y94708D01*
X327808Y94915D01*
G01X329222Y97033D02*
X329452Y97343D01*
X329720Y97498D01*
X330027Y97550D01*
X330410Y97447D01*
X330678Y97188D01*
X330755Y96878D01*
X330717Y96568D01*
X330563Y96310D01*
X329797Y95793D01*
X329452Y95432D01*
X329222Y94915D01*
X329145Y94450D01*
X330755D01*
G01X333510D02*
Y97550D01*
X332092Y95328D01*
X334008D01*
G01X336073Y94450D02*
X336150Y95122D01*
X336265Y95690D01*
X336418Y96207D01*
X336610Y96775D01*
X336917Y97550D01*
X335383D01*
G01X324500Y179000D02*
Y185500D01*
X329500D01*
Y188500D01*
G01Y192500D02*
Y196000D01*
G01X333000Y215000D02*
Y219000D01*
G01X329500Y201000D02*
Y206000D01*
G01Y210000D02*
Y213000D01*
X328500D01*
G01X337350Y209050D02*
Y205950D01*
G01X336468Y209050D02*
X338232D01*
G01X339683Y205950D02*
Y209050D01*
X340603D01*
X340910Y208895D01*
X341140Y208533D01*
X341217Y208120D01*
X341140Y207707D01*
X340948Y207397D01*
X340603Y207242D01*
X339683D01*
G01X342822D02*
X343090Y207603D01*
X343320Y207810D01*
X343627Y207913D01*
X343895Y207810D01*
X344087Y207603D01*
X344240Y207293D01*
X344278Y206932D01*
X344240Y206622D01*
X344087Y206312D01*
X343857Y206053D01*
X343588Y205950D01*
X343282Y206053D01*
X343013Y206363D01*
X342860Y206828D01*
X342822Y207345D01*
X342898Y208017D01*
X343013Y208378D01*
X343205Y208740D01*
X343473Y208998D01*
X343742Y209050D01*
X344010Y208947D01*
X344202Y208688D01*
G01X346650Y205950D02*
Y209050D01*
X346190Y208430D01*
G01Y205950D02*
X347110D01*
G01X333000Y219000D02*
X332500D01*
G01X325450Y227057D02*
X327672D01*
X328137Y227210D01*
X328447Y227517D01*
X328550Y227900D01*
X328447Y228283D01*
X328137Y228590D01*
X327672Y228743D01*
X325450D01*
G01X325967Y230272D02*
X325657Y230502D01*
X325502Y230770D01*
X325450Y231077D01*
X325553Y231460D01*
X325812Y231728D01*
X326122Y231805D01*
X326432Y231767D01*
X326690Y231613D01*
X327207Y230847D01*
X327568Y230502D01*
X328085Y230272D01*
X328550Y230195D01*
Y231805D01*
G01X328188Y233448D02*
X328447Y233717D01*
X328550Y234023D01*
X328447Y234330D01*
X328137Y234598D01*
X327672Y234790D01*
X327207Y234867D01*
X326638D01*
X326173Y234790D01*
X325760Y234598D01*
X325553Y234368D01*
X325450Y234100D01*
X325553Y233793D01*
X325760Y233563D01*
X326070Y233410D01*
X326483Y233333D01*
X326845Y233410D01*
X327207Y233602D01*
X327413Y233832D01*
X327465Y234100D01*
X327362Y234407D01*
X327103Y234637D01*
X326638Y234867D01*
G01X326900Y222250D02*
Y224750D01*
X326580Y224250D01*
G01Y222250D02*
X327220D01*
G01X328513Y222625D02*
X328673Y222417D01*
X328860Y222292D01*
X329100Y222250D01*
X329340Y222333D01*
X329527Y222500D01*
X329660Y222792D01*
X329687Y223125D01*
X329633Y223458D01*
X329500Y223667D01*
X329313Y223833D01*
X329127Y223875D01*
X328940Y223833D01*
X328700Y223667D01*
X328780Y224750D01*
X329500D01*
G01X325500Y248000D02*
Y258500D01*
G01X353000Y248000D02*
X325500D01*
G01X327815Y240496D02*
X328002Y240787D01*
X328162Y240954D01*
X328375Y241037D01*
X328562Y240954D01*
X328695Y240787D01*
X328802Y240537D01*
X328829Y240246D01*
X328802Y239996D01*
X328695Y239746D01*
X328535Y239537D01*
X328349Y239454D01*
X328135Y239537D01*
X327949Y239787D01*
X327842Y240162D01*
X327815Y240579D01*
X327869Y241121D01*
X327949Y241412D01*
X328082Y241704D01*
X328269Y241912D01*
X328455Y241954D01*
X328642Y241871D01*
X328775Y241662D01*
G01X334816Y244129D02*
X334976Y243921D01*
X335163Y243796D01*
X335403Y243754D01*
X335643Y243837D01*
X335830Y244004D01*
X335963Y244296D01*
X335990Y244629D01*
X335936Y244962D01*
X335803Y245171D01*
X335616Y245337D01*
X335430Y245379D01*
X335243Y245337D01*
X335003Y245171D01*
X335083Y246254D01*
X335803D01*
G01X330000Y258500D02*
X332000D01*
G01X325500D02*
X326500D01*
G01X340000D02*
X342000D01*
G01X335000D02*
X337000D01*
G01X333200Y269750D02*
Y267250D01*
G01X332587Y269750D02*
X333813D01*
G01X334867Y267250D02*
Y269750D01*
X335507D01*
X335720Y269625D01*
X335880Y269333D01*
X335933Y269000D01*
X335880Y268667D01*
X335747Y268417D01*
X335507Y268292D01*
X334867D01*
G01X337600Y267250D02*
Y269750D01*
X337280Y269250D01*
G01Y267250D02*
X337920D01*
G01X339800D02*
X339987Y267292D01*
X340200Y267417D01*
X340333Y267625D01*
X340387Y267917D01*
X340333Y268208D01*
X340173Y268458D01*
X339933Y268583D01*
X339667D01*
X339507Y268667D01*
X339373Y268875D01*
X339320Y269167D01*
X339400Y269458D01*
X339587Y269667D01*
X339800Y269750D01*
X340013Y269667D01*
X340200Y269458D01*
X340280Y269167D01*
X340227Y268875D01*
X340093Y268667D01*
X339933Y268583D01*
X339667D01*
X339427Y268458D01*
X339267Y268208D01*
X339213Y267917D01*
X339267Y267625D01*
X339400Y267417D01*
X339613Y267292D01*
X339800Y267250D01*
G01X327133Y294070D02*
X327325Y293760D01*
X327555Y293553D01*
X327823Y293450D01*
X328130Y293553D01*
X328360Y293760D01*
X328590Y294070D01*
X328667Y294483D01*
Y296550D01*
G01X331000Y293450D02*
Y296550D01*
X330540Y295930D01*
G01Y293450D02*
X331460D01*
G01X334023D02*
X334100Y294122D01*
X334215Y294690D01*
X334368Y295207D01*
X334560Y295775D01*
X334867Y296550D01*
X333333D01*
G01X324000Y314000D02*
Y305500D01*
G01X329950Y308900D02*
X333050D01*
G01X329950Y308018D02*
Y309782D01*
G01X333050Y311233D02*
X329950D01*
Y312153D01*
X330105Y312460D01*
X330467Y312690D01*
X330880Y312767D01*
X331293Y312690D01*
X331603Y312498D01*
X331758Y312153D01*
Y311233D01*
G01X333050Y315100D02*
X329950D01*
X330570Y314640D01*
G01X333050D02*
Y315560D01*
G01X334500Y338450D02*
X334768Y338502D01*
X335075Y338657D01*
X335267Y338915D01*
X335343Y339277D01*
X335267Y339638D01*
X335037Y339948D01*
X334692Y340103D01*
X334308D01*
X334078Y340207D01*
X333887Y340465D01*
X333810Y340827D01*
X333925Y341188D01*
X334193Y341447D01*
X334500Y341550D01*
X334807Y341447D01*
X335075Y341188D01*
X335190Y340827D01*
X335113Y340465D01*
X334922Y340207D01*
X334692Y340103D01*
X334308D01*
X333963Y339948D01*
X333733Y339638D01*
X333657Y339277D01*
X333733Y338915D01*
X333925Y338657D01*
X334232Y338502D01*
X334500Y338450D01*
G01X329000Y348000D02*
Y359500D01*
G01X333350Y352050D02*
Y348950D01*
G01X332468Y352050D02*
X334232D01*
G01X335683Y348950D02*
Y352050D01*
X336603D01*
X336910Y351895D01*
X337140Y351533D01*
X337217Y351120D01*
X337140Y350707D01*
X336948Y350397D01*
X336603Y350242D01*
X335683D01*
G01X338822Y351533D02*
X339052Y351843D01*
X339320Y351998D01*
X339627Y352050D01*
X340010Y351947D01*
X340278Y351688D01*
X340355Y351378D01*
X340317Y351068D01*
X340163Y350810D01*
X339397Y350293D01*
X339052Y349932D01*
X338822Y349415D01*
X338745Y348950D01*
X340355D01*
G01X342650D02*
Y352050D01*
X342190Y351430D01*
G01Y348950D02*
X343110D01*
G01X329000Y359500D02*
X353000D01*
G01X327500Y391500D02*
Y389500D01*
G01X341900Y388750D02*
Y391250D01*
X341580Y390750D01*
G01Y388750D02*
X342220D01*
G01X343593Y390833D02*
X343753Y391083D01*
X343940Y391208D01*
X344153Y391250D01*
X344420Y391167D01*
X344607Y390958D01*
X344660Y390708D01*
X344633Y390458D01*
X344527Y390250D01*
X343993Y389833D01*
X343753Y389542D01*
X343593Y389125D01*
X343540Y388750D01*
X344660D01*
G01X338000Y391500D02*
X327500D01*
G01X324413Y406325D02*
X324573Y406117D01*
X324760Y405992D01*
X325000Y405950D01*
X325240Y406033D01*
X325427Y406200D01*
X325560Y406492D01*
X325587Y406825D01*
X325533Y407158D01*
X325400Y407367D01*
X325213Y407533D01*
X325027Y407575D01*
X324840Y407533D01*
X324600Y407367D01*
X324680Y408450D01*
X325400D01*
G01X324493Y402492D02*
X324680Y402783D01*
X324840Y402950D01*
X325053Y403033D01*
X325240Y402950D01*
X325373Y402783D01*
X325480Y402533D01*
X325507Y402242D01*
X325480Y401992D01*
X325373Y401742D01*
X325213Y401533D01*
X325027Y401450D01*
X324813Y401533D01*
X324627Y401783D01*
X324520Y402158D01*
X324493Y402575D01*
X324547Y403117D01*
X324627Y403408D01*
X324760Y403700D01*
X324947Y403908D01*
X325133Y403950D01*
X325320Y403867D01*
X325453Y403658D01*
G01X327743Y428292D02*
X327513Y428447D01*
X327245Y428550D01*
X326938D01*
X326593Y428395D01*
X326325Y428137D01*
X326133Y427827D01*
X325980Y427310D01*
X325942Y426845D01*
X326018Y426380D01*
X326133Y426070D01*
X326363Y425760D01*
X326632Y425553D01*
X326900Y425450D01*
X327168D01*
X327437Y425553D01*
X327667Y425708D01*
X327858Y425915D01*
G01X329157D02*
X329387Y425657D01*
X329655Y425502D01*
X330000Y425450D01*
X330345Y425553D01*
X330613Y425760D01*
X330805Y426122D01*
X330843Y426535D01*
X330767Y426948D01*
X330575Y427207D01*
X330307Y427413D01*
X330038Y427465D01*
X329770Y427413D01*
X329425Y427207D01*
X329540Y428550D01*
X330575D01*
G01X333100D02*
X332793Y428447D01*
X332563Y428188D01*
X332410Y427878D01*
X332295Y427465D01*
X332257Y427000D01*
X332295Y426535D01*
X332410Y426122D01*
X332563Y425812D01*
X332793Y425553D01*
X333100Y425450D01*
X333407Y425553D01*
X333637Y425812D01*
X333790Y426122D01*
X333905Y426535D01*
X333943Y427000D01*
X333905Y427465D01*
X333790Y427878D01*
X333637Y428188D01*
X333407Y428447D01*
X333100Y428550D01*
G01X340683Y427050D02*
Y423950D01*
X342217D01*
G01X344550D02*
X344818Y424002D01*
X345125Y424157D01*
X345317Y424415D01*
X345393Y424777D01*
X345317Y425138D01*
X345087Y425448D01*
X344742Y425603D01*
X344358D01*
X344128Y425707D01*
X343937Y425965D01*
X343860Y426327D01*
X343975Y426688D01*
X344243Y426947D01*
X344550Y427050D01*
X344857Y426947D01*
X345125Y426688D01*
X345240Y426327D01*
X345163Y425965D01*
X344972Y425707D01*
X344742Y425603D01*
X344358D01*
X344013Y425448D01*
X343783Y425138D01*
X343707Y424777D01*
X343783Y424415D01*
X343975Y424157D01*
X344282Y424002D01*
X344550Y423950D01*
G01X350583Y94950D02*
Y98050D01*
X351542D01*
X351848Y97895D01*
X352040Y97688D01*
X352117Y97275D01*
X352040Y96862D01*
X351810Y96603D01*
X351542Y96448D01*
X350583D01*
G01X351542D02*
X352117Y94950D01*
G01X353722Y97533D02*
X353952Y97843D01*
X354220Y97998D01*
X354527Y98050D01*
X354910Y97947D01*
X355178Y97688D01*
X355255Y97378D01*
X355217Y97068D01*
X355063Y96810D01*
X354297Y96293D01*
X353952Y95932D01*
X353722Y95415D01*
X353645Y94950D01*
X355255D01*
G01X358010D02*
Y98050D01*
X356592Y95828D01*
X358508D01*
G01X360650Y98050D02*
X360343Y97947D01*
X360113Y97688D01*
X359960Y97378D01*
X359845Y96965D01*
X359807Y96500D01*
X359845Y96035D01*
X359960Y95622D01*
X360113Y95312D01*
X360343Y95053D01*
X360650Y94950D01*
X360957Y95053D01*
X361187Y95312D01*
X361340Y95622D01*
X361455Y96035D01*
X361493Y96500D01*
X361455Y96965D01*
X361340Y97378D01*
X361187Y97688D01*
X360957Y97947D01*
X360650Y98050D01*
G01X353708Y144193D02*
X353553Y143963D01*
X353450Y143695D01*
Y143388D01*
X353605Y143043D01*
X353863Y142775D01*
X354173Y142583D01*
X354690Y142430D01*
X355155Y142392D01*
X355620Y142468D01*
X355930Y142583D01*
X356240Y142813D01*
X356447Y143082D01*
X356550Y143350D01*
Y143618D01*
X356447Y143887D01*
X356292Y144117D01*
X356085Y144308D01*
G01X356550Y146450D02*
X353450D01*
X354070Y145990D01*
G01X356550D02*
Y146910D01*
G01Y150010D02*
X353450D01*
X355672Y148592D01*
Y150508D01*
G01X356550Y152650D02*
X356498Y152918D01*
X356343Y153225D01*
X356085Y153417D01*
X355723Y153493D01*
X355362Y153417D01*
X355052Y153187D01*
X354897Y152842D01*
Y152458D01*
X354793Y152228D01*
X354535Y152037D01*
X354173Y151960D01*
X353812Y152075D01*
X353553Y152343D01*
X353450Y152650D01*
X353553Y152957D01*
X353812Y153225D01*
X354173Y153340D01*
X354535Y153263D01*
X354793Y153072D01*
X354897Y152842D01*
Y152458D01*
X355052Y152113D01*
X355362Y151883D01*
X355723Y151807D01*
X356085Y151883D01*
X356343Y152075D01*
X356498Y152382D01*
X356550Y152650D01*
G01X349208Y144193D02*
X349053Y143963D01*
X348950Y143695D01*
Y143388D01*
X349105Y143043D01*
X349363Y142775D01*
X349673Y142583D01*
X350190Y142430D01*
X350655Y142392D01*
X351120Y142468D01*
X351430Y142583D01*
X351740Y142813D01*
X351947Y143082D01*
X352050Y143350D01*
Y143618D01*
X351947Y143887D01*
X351792Y144117D01*
X351585Y144308D01*
G01X352050Y146450D02*
X348950D01*
X349570Y145990D01*
G01X352050D02*
Y146910D01*
G01X351585Y148707D02*
X351843Y148937D01*
X351998Y149205D01*
X352050Y149550D01*
X351947Y149895D01*
X351740Y150163D01*
X351378Y150355D01*
X350965Y150393D01*
X350552Y150317D01*
X350293Y150125D01*
X350087Y149857D01*
X350035Y149588D01*
X350087Y149320D01*
X350293Y148975D01*
X348950Y149090D01*
Y150125D01*
G01X351585Y151807D02*
X351843Y152037D01*
X351998Y152305D01*
X352050Y152650D01*
X351947Y152995D01*
X351740Y153263D01*
X351378Y153455D01*
X350965Y153493D01*
X350552Y153417D01*
X350293Y153225D01*
X350087Y152957D01*
X350035Y152688D01*
X350087Y152420D01*
X350293Y152075D01*
X348950Y152190D01*
Y153225D01*
G01X351000Y170583D02*
X347900D01*
Y171542D01*
X348055Y171848D01*
X348262Y172040D01*
X348675Y172117D01*
X349088Y172040D01*
X349347Y171810D01*
X349502Y171542D01*
Y170583D01*
G01Y171542D02*
X351000Y172117D01*
G01X348417Y173722D02*
X348107Y173952D01*
X347952Y174220D01*
X347900Y174527D01*
X348003Y174910D01*
X348262Y175178D01*
X348572Y175255D01*
X348882Y175217D01*
X349140Y175063D01*
X349657Y174297D01*
X350018Y173952D01*
X350535Y173722D01*
X351000Y173645D01*
Y175255D01*
G01X349708Y176822D02*
X349347Y177090D01*
X349140Y177320D01*
X349037Y177627D01*
X349140Y177895D01*
X349347Y178087D01*
X349657Y178240D01*
X350018Y178278D01*
X350328Y178240D01*
X350638Y178087D01*
X350897Y177857D01*
X351000Y177588D01*
X350897Y177282D01*
X350587Y177013D01*
X350122Y176860D01*
X349605Y176822D01*
X348933Y176898D01*
X348572Y177013D01*
X348210Y177205D01*
X347952Y177473D01*
X347900Y177742D01*
X348003Y178010D01*
X348262Y178202D01*
G01X349708Y179922D02*
X349347Y180190D01*
X349140Y180420D01*
X349037Y180727D01*
X349140Y180995D01*
X349347Y181187D01*
X349657Y181340D01*
X350018Y181378D01*
X350328Y181340D01*
X350638Y181187D01*
X350897Y180957D01*
X351000Y180688D01*
X350897Y180382D01*
X350587Y180113D01*
X350122Y179960D01*
X349605Y179922D01*
X348933Y179998D01*
X348572Y180113D01*
X348210Y180305D01*
X347952Y180573D01*
X347900Y180842D01*
X348003Y181110D01*
X348262Y181302D01*
G01X355993Y183833D02*
X356153Y184083D01*
X356340Y184208D01*
X356553Y184250D01*
X356820Y184167D01*
X357007Y183958D01*
X357060Y183708D01*
X357033Y183458D01*
X356927Y183250D01*
X356393Y182833D01*
X356153Y182542D01*
X355993Y182125D01*
X355940Y181750D01*
X357060D01*
G01X353734Y200149D02*
X353692Y200336D01*
X353567Y200549D01*
X353359Y200682D01*
X353067Y200736D01*
X352776Y200682D01*
X352526Y200522D01*
X352401Y200282D01*
Y200016D01*
X352317Y199856D01*
X352109Y199722D01*
X351817Y199669D01*
X351526Y199749D01*
X351317Y199936D01*
X351234Y200149D01*
X351317Y200362D01*
X351526Y200549D01*
X351817Y200629D01*
X352109Y200576D01*
X352317Y200442D01*
X352401Y200282D01*
Y200016D01*
X352526Y199776D01*
X352776Y199616D01*
X353067Y199562D01*
X353359Y199616D01*
X353567Y199749D01*
X353692Y199962D01*
X353734Y200149D01*
G01X357646Y200185D02*
X357104Y200238D01*
X356646Y200318D01*
X356229Y200425D01*
X355771Y200558D01*
X355146Y200771D01*
Y199705D01*
G01X348795Y224625D02*
X348955Y224875D01*
X349142Y225000D01*
X349355Y225042D01*
X349622Y224959D01*
X349809Y224750D01*
X349862Y224500D01*
X349835Y224250D01*
X349729Y224042D01*
X349195Y223625D01*
X348955Y223334D01*
X348795Y222917D01*
X348742Y222542D01*
X349862D01*
G01X351502Y225042D02*
X351289Y224959D01*
X351129Y224750D01*
X351022Y224500D01*
X350942Y224167D01*
X350915Y223792D01*
X350942Y223417D01*
X351022Y223084D01*
X351129Y222834D01*
X351289Y222625D01*
X351502Y222542D01*
X351715Y222625D01*
X351875Y222834D01*
X351982Y223084D01*
X352062Y223417D01*
X352089Y223792D01*
X352062Y224167D01*
X351982Y224500D01*
X351875Y224750D01*
X351715Y224959D01*
X351502Y225042D01*
G01X357542Y250450D02*
X358500Y253550D01*
X359458Y250450D01*
G01X359113Y251535D02*
X357887D01*
G01X357000Y248500D02*
X360500D01*
G01X359050Y243950D02*
X357655D01*
X355950Y243183D01*
G01Y244717D02*
X357655Y243950D01*
G01X359050Y247050D02*
X355950D01*
X356570Y246590D01*
G01X359050D02*
Y247510D01*
G01X341714Y246105D02*
X341874Y246355D01*
X342061Y246480D01*
X342274Y246522D01*
X342541Y246439D01*
X342728Y246230D01*
X342781Y245980D01*
X342754Y245730D01*
X342648Y245522D01*
X342114Y245105D01*
X341874Y244814D01*
X341714Y244397D01*
X341661Y244022D01*
X342781D01*
G01X348393Y240333D02*
X348553Y240583D01*
X348740Y240708D01*
X348953Y240750D01*
X349220Y240667D01*
X349407Y240458D01*
X349460Y240208D01*
X349433Y239958D01*
X349327Y239750D01*
X348793Y239333D01*
X348553Y239042D01*
X348393Y238625D01*
X348340Y238250D01*
X349460D01*
G01X351100D02*
X351287Y238292D01*
X351500Y238417D01*
X351633Y238625D01*
X351687Y238917D01*
X351633Y239208D01*
X351473Y239458D01*
X351233Y239583D01*
X350967D01*
X350807Y239667D01*
X350673Y239875D01*
X350620Y240167D01*
X350700Y240458D01*
X350887Y240667D01*
X351100Y240750D01*
X351313Y240667D01*
X351500Y240458D01*
X351580Y240167D01*
X351527Y239875D01*
X351393Y239667D01*
X351233Y239583D01*
X350967D01*
X350727Y239458D01*
X350567Y239208D01*
X350513Y238917D01*
X350567Y238625D01*
X350700Y238417D01*
X350913Y238292D01*
X351100Y238250D01*
G01X345500Y259500D02*
X346500D01*
G01X345500Y258500D02*
Y259500D01*
G01X345000Y258500D02*
X345500D01*
G01X357500Y254500D02*
Y257000D01*
G01X360500Y254500D02*
X357500D01*
G01X353000Y258500D02*
X355500D01*
G01X350000Y259500D02*
X351000D01*
G01X352200Y267250D02*
Y264750D01*
G01X351587Y267250D02*
X352813D01*
G01X353867Y264750D02*
Y267250D01*
X354507D01*
X354720Y267125D01*
X354880Y266833D01*
X354933Y266500D01*
X354880Y266167D01*
X354747Y265917D01*
X354507Y265792D01*
X353867D01*
G01X356013Y265125D02*
X356173Y264917D01*
X356360Y264792D01*
X356600Y264750D01*
X356840Y264833D01*
X357027Y265000D01*
X357160Y265292D01*
X357187Y265625D01*
X357133Y265958D01*
X357000Y266167D01*
X356813Y266333D01*
X356627Y266375D01*
X356440Y266333D01*
X356200Y266167D01*
X356280Y267250D01*
X357000D01*
G01X358800Y264750D02*
X358987Y264792D01*
X359200Y264917D01*
X359333Y265125D01*
X359387Y265417D01*
X359333Y265708D01*
X359173Y265958D01*
X358933Y266083D01*
X358667D01*
X358507Y266167D01*
X358373Y266375D01*
X358320Y266667D01*
X358400Y266958D01*
X358587Y267167D01*
X358800Y267250D01*
X359013Y267167D01*
X359200Y266958D01*
X359280Y266667D01*
X359227Y266375D01*
X359093Y266167D01*
X358933Y266083D01*
X358667D01*
X358427Y265958D01*
X358267Y265708D01*
X358213Y265417D01*
X358267Y265125D01*
X358400Y264917D01*
X358613Y264792D01*
X358800Y264750D01*
G01X342200Y269750D02*
Y267250D01*
G01X341587Y269750D02*
X342813D01*
G01X343867Y267250D02*
Y269750D01*
X344507D01*
X344720Y269625D01*
X344880Y269333D01*
X344933Y269000D01*
X344880Y268667D01*
X344747Y268417D01*
X344507Y268292D01*
X343867D01*
G01X346600Y267250D02*
Y269750D01*
X346280Y269250D01*
G01Y267250D02*
X346920D01*
G01X348347Y267542D02*
X348533Y267333D01*
X348747Y267250D01*
X348960Y267333D01*
X349147Y267583D01*
X349280Y267958D01*
X349333Y268333D01*
Y268792D01*
X349280Y269167D01*
X349147Y269500D01*
X348987Y269667D01*
X348800Y269750D01*
X348587Y269667D01*
X348427Y269500D01*
X348320Y269250D01*
X348267Y268917D01*
X348320Y268625D01*
X348453Y268333D01*
X348613Y268167D01*
X348800Y268125D01*
X349013Y268208D01*
X349173Y268417D01*
X349333Y268792D01*
G01X355000Y269500D02*
Y273000D01*
G01X366000Y269500D02*
X355000D01*
G01X354000Y278450D02*
Y281550D01*
X353540Y280930D01*
G01Y278450D02*
X354460D01*
G01X354500Y298000D02*
X363000D01*
G01X354500Y291500D02*
Y298000D01*
G01X346157Y293070D02*
X346387Y292708D01*
X346693Y292502D01*
X347038Y292450D01*
X347345Y292502D01*
X347652Y292760D01*
X347843Y293070D01*
X347882Y293380D01*
X347805Y293742D01*
X347537Y294000D01*
X347268Y294103D01*
X346923D01*
G01X347268D02*
X347498Y294258D01*
X347690Y294517D01*
X347767Y294827D01*
X347690Y295137D01*
X347498Y295395D01*
X347153Y295550D01*
X346808Y295498D01*
X346463Y295292D01*
G01X347100Y314150D02*
X347368Y314202D01*
X347675Y314357D01*
X347867Y314615D01*
X347943Y314977D01*
X347867Y315338D01*
X347637Y315648D01*
X347292Y315803D01*
X346908D01*
X346678Y315907D01*
X346487Y316165D01*
X346410Y316527D01*
X346525Y316888D01*
X346793Y317147D01*
X347100Y317250D01*
X347407Y317147D01*
X347675Y316888D01*
X347790Y316527D01*
X347713Y316165D01*
X347522Y315907D01*
X347292Y315803D01*
X346908D01*
X346563Y315648D01*
X346333Y315338D01*
X346257Y314977D01*
X346333Y314615D01*
X346525Y314357D01*
X346832Y314202D01*
X347100Y314150D01*
G01X352633Y312550D02*
Y309450D01*
X354167D01*
G01X356500D02*
Y312550D01*
X356040Y311930D01*
G01Y309450D02*
X356960D01*
G01X359600D02*
Y312550D01*
X359140Y311930D01*
G01Y309450D02*
X360060D01*
G01X345257Y345115D02*
X345487Y344857D01*
X345755Y344702D01*
X346100Y344650D01*
X346445Y344753D01*
X346713Y344960D01*
X346905Y345322D01*
X346943Y345735D01*
X346867Y346148D01*
X346675Y346407D01*
X346407Y346613D01*
X346138Y346665D01*
X345870Y346613D01*
X345525Y346407D01*
X345640Y347750D01*
X346675D01*
G01X353000Y359500D02*
Y375000D01*
G01X357433Y372250D02*
Y375350D01*
X358392D01*
X358698Y375195D01*
X358890Y374988D01*
X358967Y374575D01*
X358890Y374162D01*
X358660Y373903D01*
X358392Y373748D01*
X357433D01*
G01X358392D02*
X358967Y372250D01*
G01X361760D02*
Y375350D01*
X360342Y373128D01*
X362258D01*
G01X364400Y375350D02*
X364093Y375247D01*
X363863Y374988D01*
X363710Y374678D01*
X363595Y374265D01*
X363557Y373800D01*
X363595Y373335D01*
X363710Y372922D01*
X363863Y372612D01*
X364093Y372353D01*
X364400Y372250D01*
X364707Y372353D01*
X364937Y372612D01*
X365090Y372922D01*
X365205Y373335D01*
X365243Y373800D01*
X365205Y374265D01*
X365090Y374678D01*
X364937Y374988D01*
X364707Y375247D01*
X364400Y375350D01*
G01X354133Y367450D02*
Y370550D01*
X355092D01*
X355398Y370395D01*
X355590Y370188D01*
X355667Y369775D01*
X355590Y369362D01*
X355360Y369103D01*
X355092Y368948D01*
X354133D01*
G01X355092D02*
X355667Y367450D01*
G01X357157Y368070D02*
X357387Y367708D01*
X357693Y367502D01*
X358038Y367450D01*
X358345Y367502D01*
X358652Y367760D01*
X358843Y368070D01*
X358882Y368380D01*
X358805Y368742D01*
X358537Y369000D01*
X358268Y369103D01*
X357923D01*
G01X358268D02*
X358498Y369258D01*
X358690Y369517D01*
X358767Y369827D01*
X358690Y370137D01*
X358498Y370395D01*
X358153Y370550D01*
X357808Y370498D01*
X357463Y370292D01*
G01X361100Y367450D02*
X361368Y367502D01*
X361675Y367657D01*
X361867Y367915D01*
X361943Y368277D01*
X361867Y368638D01*
X361637Y368948D01*
X361292Y369103D01*
X360908D01*
X360678Y369207D01*
X360487Y369465D01*
X360410Y369827D01*
X360525Y370188D01*
X360793Y370447D01*
X361100Y370550D01*
X361407Y370447D01*
X361675Y370188D01*
X361790Y369827D01*
X361713Y369465D01*
X361522Y369207D01*
X361292Y369103D01*
X360908D01*
X360563Y368948D01*
X360333Y368638D01*
X360257Y368277D01*
X360333Y367915D01*
X360525Y367657D01*
X360832Y367502D01*
X361100Y367450D01*
G01X346500Y375000D02*
Y377000D01*
G01X353000Y375000D02*
X346500D01*
G01X359043Y379492D02*
X358813Y379647D01*
X358545Y379750D01*
X358238D01*
X357893Y379595D01*
X357625Y379337D01*
X357433Y379027D01*
X357280Y378510D01*
X357242Y378045D01*
X357318Y377580D01*
X357433Y377270D01*
X357663Y376960D01*
X357932Y376753D01*
X358200Y376650D01*
X358468D01*
X358737Y376753D01*
X358967Y376908D01*
X359158Y377115D01*
G01X361300Y376650D02*
Y379750D01*
X360840Y379130D01*
G01Y376650D02*
X361760D01*
G01X363672Y377942D02*
X363940Y378303D01*
X364170Y378510D01*
X364477Y378613D01*
X364745Y378510D01*
X364937Y378303D01*
X365090Y377993D01*
X365128Y377632D01*
X365090Y377322D01*
X364937Y377012D01*
X364707Y376753D01*
X364438Y376650D01*
X364132Y376753D01*
X363863Y377063D01*
X363710Y377528D01*
X363672Y378045D01*
X363748Y378717D01*
X363863Y379078D01*
X364055Y379440D01*
X364323Y379698D01*
X364592Y379750D01*
X364860Y379647D01*
X365052Y379388D01*
G01X359043Y395492D02*
X358813Y395647D01*
X358545Y395750D01*
X358238D01*
X357893Y395595D01*
X357625Y395337D01*
X357433Y395027D01*
X357280Y394510D01*
X357242Y394045D01*
X357318Y393580D01*
X357433Y393270D01*
X357663Y392960D01*
X357932Y392753D01*
X358200Y392650D01*
X358468D01*
X358737Y392753D01*
X358967Y392908D01*
X359158Y393115D01*
G01X360457D02*
X360687Y392857D01*
X360955Y392702D01*
X361300Y392650D01*
X361645Y392753D01*
X361913Y392960D01*
X362105Y393322D01*
X362143Y393735D01*
X362067Y394148D01*
X361875Y394407D01*
X361607Y394613D01*
X361338Y394665D01*
X361070Y394613D01*
X360725Y394407D01*
X360840Y395750D01*
X361875D01*
G01X363557Y393115D02*
X363787Y392857D01*
X364055Y392702D01*
X364400Y392650D01*
X364745Y392753D01*
X365013Y392960D01*
X365205Y393322D01*
X365243Y393735D01*
X365167Y394148D01*
X364975Y394407D01*
X364707Y394613D01*
X364438Y394665D01*
X364170Y394613D01*
X363825Y394407D01*
X363940Y395750D01*
X364975D01*
G01X347750Y393900D02*
X345250D01*
X345750Y393580D01*
G01X347750D02*
Y394220D01*
G01X347250Y395513D02*
X347542Y395673D01*
X347708Y395887D01*
X347750Y396127D01*
X347708Y396340D01*
X347500Y396553D01*
X347250Y396687D01*
X347000Y396713D01*
X346708Y396660D01*
X346500Y396473D01*
X346417Y396287D01*
Y396047D01*
G01Y396287D02*
X346292Y396447D01*
X346083Y396580D01*
X345833Y396633D01*
X345583Y396580D01*
X345375Y396447D01*
X345250Y396207D01*
X345292Y395967D01*
X345458Y395727D01*
G01X344950Y400107D02*
X347172D01*
X347637Y400260D01*
X347947Y400567D01*
X348050Y400950D01*
X347947Y401333D01*
X347637Y401640D01*
X347172Y401793D01*
X344950D01*
G01X346758Y403322D02*
X346397Y403590D01*
X346190Y403820D01*
X346087Y404127D01*
X346190Y404395D01*
X346397Y404587D01*
X346707Y404740D01*
X347068Y404778D01*
X347378Y404740D01*
X347688Y404587D01*
X347947Y404357D01*
X348050Y404088D01*
X347947Y403782D01*
X347637Y403513D01*
X347172Y403360D01*
X346655Y403322D01*
X345983Y403398D01*
X345622Y403513D01*
X345260Y403705D01*
X345002Y403973D01*
X344950Y404242D01*
X345053Y404510D01*
X345312Y404702D01*
G01X355243Y428292D02*
X355013Y428447D01*
X354745Y428550D01*
X354438D01*
X354093Y428395D01*
X353825Y428137D01*
X353633Y427827D01*
X353480Y427310D01*
X353442Y426845D01*
X353518Y426380D01*
X353633Y426070D01*
X353863Y425760D01*
X354132Y425553D01*
X354400Y425450D01*
X354668D01*
X354937Y425553D01*
X355167Y425708D01*
X355358Y425915D01*
G01X357423Y425450D02*
X357500Y426122D01*
X357615Y426690D01*
X357768Y427207D01*
X357960Y427775D01*
X358267Y428550D01*
X356733D01*
G01X359872Y426742D02*
X360140Y427103D01*
X360370Y427310D01*
X360677Y427413D01*
X360945Y427310D01*
X361137Y427103D01*
X361290Y426793D01*
X361328Y426432D01*
X361290Y426122D01*
X361137Y425812D01*
X360907Y425553D01*
X360638Y425450D01*
X360332Y425553D01*
X360063Y425863D01*
X359910Y426328D01*
X359872Y426845D01*
X359948Y427517D01*
X360063Y427878D01*
X360255Y428240D01*
X360523Y428498D01*
X360792Y428550D01*
X361060Y428447D01*
X361252Y428188D01*
G01X358243Y416292D02*
X358013Y416447D01*
X357745Y416550D01*
X357438D01*
X357093Y416395D01*
X356825Y416137D01*
X356633Y415827D01*
X356480Y415310D01*
X356442Y414845D01*
X356518Y414380D01*
X356633Y414070D01*
X356863Y413760D01*
X357132Y413553D01*
X357400Y413450D01*
X357668D01*
X357937Y413553D01*
X358167Y413708D01*
X358358Y413915D01*
G01X360423Y413450D02*
X360500Y414122D01*
X360615Y414690D01*
X360768Y415207D01*
X360960Y415775D01*
X361267Y416550D01*
X359733D01*
G01X363523Y413450D02*
X363600Y414122D01*
X363715Y414690D01*
X363868Y415207D01*
X364060Y415775D01*
X364367Y416550D01*
X362833D01*
G01X347750Y409400D02*
X345250D01*
X345750Y409080D01*
G01X347750D02*
Y409720D01*
G01Y411600D02*
X347708Y411787D01*
X347583Y412000D01*
X347375Y412133D01*
X347083Y412187D01*
X346792Y412133D01*
X346542Y411973D01*
X346417Y411733D01*
Y411467D01*
X346333Y411307D01*
X346125Y411173D01*
X345833Y411120D01*
X345542Y411200D01*
X345333Y411387D01*
X345250Y411600D01*
X345333Y411813D01*
X345542Y412000D01*
X345833Y412080D01*
X346125Y412027D01*
X346333Y411893D01*
X346417Y411733D01*
Y411467D01*
X346542Y411227D01*
X346792Y411067D01*
X347083Y411013D01*
X347375Y411067D01*
X347583Y411200D01*
X347708Y411413D01*
X347750Y411600D01*
G01X378050Y73083D02*
X374950D01*
Y74042D01*
X375105Y74348D01*
X375312Y74540D01*
X375725Y74617D01*
X376138Y74540D01*
X376397Y74310D01*
X376552Y74042D01*
Y73083D01*
G01Y74042D02*
X378050Y74617D01*
G01X375467Y76222D02*
X375157Y76452D01*
X375002Y76720D01*
X374950Y77027D01*
X375053Y77410D01*
X375312Y77678D01*
X375622Y77755D01*
X375932Y77717D01*
X376190Y77563D01*
X376707Y76797D01*
X377068Y76452D01*
X377585Y76222D01*
X378050Y76145D01*
Y77755D01*
G01X377430Y79207D02*
X377792Y79437D01*
X377998Y79743D01*
X378050Y80088D01*
X377998Y80395D01*
X377740Y80702D01*
X377430Y80893D01*
X377120Y80932D01*
X376758Y80855D01*
X376500Y80587D01*
X376397Y80318D01*
Y79973D01*
G01Y80318D02*
X376242Y80548D01*
X375983Y80740D01*
X375673Y80817D01*
X375363Y80740D01*
X375105Y80548D01*
X374950Y80203D01*
X375002Y79858D01*
X375208Y79513D01*
G01X376758Y82422D02*
X376397Y82690D01*
X376190Y82920D01*
X376087Y83227D01*
X376190Y83495D01*
X376397Y83687D01*
X376707Y83840D01*
X377068Y83878D01*
X377378Y83840D01*
X377688Y83687D01*
X377947Y83457D01*
X378050Y83188D01*
X377947Y82882D01*
X377637Y82613D01*
X377172Y82460D01*
X376655Y82422D01*
X375983Y82498D01*
X375622Y82613D01*
X375260Y82805D01*
X375002Y83073D01*
X374950Y83342D01*
X375053Y83610D01*
X375312Y83802D01*
G01X362350Y80050D02*
Y76950D01*
G01X361468Y80050D02*
X363232D01*
G01X364683Y76950D02*
Y80050D01*
X365603D01*
X365910Y79895D01*
X366140Y79533D01*
X366217Y79120D01*
X366140Y78707D01*
X365948Y78397D01*
X365603Y78242D01*
X364683D01*
G01X367707Y77415D02*
X367937Y77157D01*
X368205Y77002D01*
X368550Y76950D01*
X368895Y77053D01*
X369163Y77260D01*
X369355Y77622D01*
X369393Y78035D01*
X369317Y78448D01*
X369125Y78707D01*
X368857Y78913D01*
X368588Y78965D01*
X368320Y78913D01*
X367975Y78707D01*
X368090Y80050D01*
X369125D01*
G01X371650D02*
X371343Y79947D01*
X371113Y79688D01*
X370960Y79378D01*
X370845Y78965D01*
X370807Y78500D01*
X370845Y78035D01*
X370960Y77622D01*
X371113Y77312D01*
X371343Y77053D01*
X371650Y76950D01*
X371957Y77053D01*
X372187Y77312D01*
X372340Y77622D01*
X372455Y78035D01*
X372493Y78500D01*
X372455Y78965D01*
X372340Y79378D01*
X372187Y79688D01*
X371957Y79947D01*
X371650Y80050D01*
G01X363083Y94950D02*
Y98050D01*
X364042D01*
X364348Y97895D01*
X364540Y97688D01*
X364617Y97275D01*
X364540Y96862D01*
X364310Y96603D01*
X364042Y96448D01*
X363083D01*
G01X364042D02*
X364617Y94950D01*
G01X366222Y97533D02*
X366452Y97843D01*
X366720Y97998D01*
X367027Y98050D01*
X367410Y97947D01*
X367678Y97688D01*
X367755Y97378D01*
X367717Y97068D01*
X367563Y96810D01*
X366797Y96293D01*
X366452Y95932D01*
X366222Y95415D01*
X366145Y94950D01*
X367755D01*
G01X370510D02*
Y98050D01*
X369092Y95828D01*
X371008D01*
G01X372422Y97533D02*
X372652Y97843D01*
X372920Y97998D01*
X373227Y98050D01*
X373610Y97947D01*
X373878Y97688D01*
X373955Y97378D01*
X373917Y97068D01*
X373763Y96810D01*
X372997Y96293D01*
X372652Y95932D01*
X372422Y95415D01*
X372345Y94950D01*
X373955D01*
G01X367193Y114292D02*
X366963Y114447D01*
X366695Y114550D01*
X366388D01*
X366043Y114395D01*
X365775Y114137D01*
X365583Y113827D01*
X365430Y113310D01*
X365392Y112845D01*
X365468Y112380D01*
X365583Y112070D01*
X365813Y111760D01*
X366082Y111553D01*
X366350Y111450D01*
X366618D01*
X366887Y111553D01*
X367117Y111708D01*
X367308Y111915D01*
G01X368722Y114033D02*
X368952Y114343D01*
X369220Y114498D01*
X369527Y114550D01*
X369910Y114447D01*
X370178Y114188D01*
X370255Y113878D01*
X370217Y113568D01*
X370063Y113310D01*
X369297Y112793D01*
X368952Y112432D01*
X368722Y111915D01*
X368645Y111450D01*
X370255D01*
G01X371898Y111812D02*
X372167Y111553D01*
X372473Y111450D01*
X372780Y111553D01*
X373048Y111863D01*
X373240Y112328D01*
X373317Y112793D01*
Y113362D01*
X373240Y113827D01*
X373048Y114240D01*
X372818Y114447D01*
X372550Y114550D01*
X372243Y114447D01*
X372013Y114240D01*
X371860Y113930D01*
X371783Y113517D01*
X371860Y113155D01*
X372052Y112793D01*
X372282Y112587D01*
X372550Y112535D01*
X372857Y112638D01*
X373087Y112897D01*
X373317Y113362D01*
G01X375650Y111450D02*
Y114550D01*
X375190Y113930D01*
G01Y111450D02*
X376110D01*
G01X376340Y136983D02*
X376090Y137143D01*
X375965Y137330D01*
X375923Y137543D01*
X376006Y137810D01*
X376215Y137997D01*
X376465Y138050D01*
X376715Y138023D01*
X376923Y137917D01*
X377340Y137383D01*
X377631Y137143D01*
X378048Y136983D01*
X378423Y136930D01*
Y138050D01*
G01Y145310D02*
X375923D01*
X377715Y144323D01*
Y145657D01*
G01X360133Y143050D02*
Y139950D01*
X361667D01*
G01X363157Y140570D02*
X363387Y140208D01*
X363693Y140002D01*
X364038Y139950D01*
X364345Y140002D01*
X364652Y140260D01*
X364843Y140570D01*
X364882Y140880D01*
X364805Y141242D01*
X364537Y141500D01*
X364268Y141603D01*
X363923D01*
G01X364268D02*
X364498Y141758D01*
X364690Y142017D01*
X364767Y142327D01*
X364690Y142637D01*
X364498Y142895D01*
X364153Y143050D01*
X363808Y142998D01*
X363463Y142792D01*
G01X367560Y139950D02*
Y143050D01*
X366142Y140828D01*
X368058D01*
G01X363208Y157693D02*
X363053Y157463D01*
X362950Y157195D01*
Y156888D01*
X363105Y156543D01*
X363363Y156275D01*
X363673Y156083D01*
X364190Y155930D01*
X364655Y155892D01*
X365120Y155968D01*
X365430Y156083D01*
X365740Y156313D01*
X365947Y156582D01*
X366050Y156850D01*
Y157118D01*
X365947Y157387D01*
X365792Y157617D01*
X365585Y157808D01*
G01X366050Y159950D02*
X362950D01*
X363570Y159490D01*
G01X366050D02*
Y160410D01*
G01X365430Y162207D02*
X365792Y162437D01*
X365998Y162743D01*
X366050Y163088D01*
X365998Y163395D01*
X365740Y163702D01*
X365430Y163893D01*
X365120Y163932D01*
X364758Y163855D01*
X364500Y163587D01*
X364397Y163318D01*
Y162973D01*
G01Y163318D02*
X364242Y163548D01*
X363983Y163740D01*
X363673Y163817D01*
X363363Y163740D01*
X363105Y163548D01*
X362950Y163203D01*
X363002Y162858D01*
X363208Y162513D01*
G01X366050Y166073D02*
X365378Y166150D01*
X364810Y166265D01*
X364293Y166418D01*
X363725Y166610D01*
X362950Y166917D01*
Y165383D01*
G01X378423Y160990D02*
X378381Y161177D01*
X378256Y161390D01*
X378048Y161523D01*
X377756Y161577D01*
X377465Y161523D01*
X377215Y161363D01*
X377090Y161123D01*
Y160857D01*
X377006Y160697D01*
X376798Y160563D01*
X376506Y160510D01*
X376215Y160590D01*
X376006Y160777D01*
X375923Y160990D01*
X376006Y161203D01*
X376215Y161390D01*
X376506Y161470D01*
X376798Y161417D01*
X377006Y161283D01*
X377090Y161123D01*
Y160857D01*
X377215Y160617D01*
X377465Y160457D01*
X377756Y160403D01*
X378048Y160457D01*
X378256Y160590D01*
X378381Y160803D01*
X378423Y160990D01*
G01X367500Y173583D02*
X364400D01*
Y174542D01*
X364555Y174848D01*
X364762Y175040D01*
X365175Y175117D01*
X365588Y175040D01*
X365847Y174810D01*
X366002Y174542D01*
Y173583D01*
G01Y174542D02*
X367500Y175117D01*
G01Y177450D02*
X364400D01*
X365020Y176990D01*
G01X367500D02*
Y177910D01*
G01X364400Y180550D02*
X364503Y180243D01*
X364762Y180013D01*
X365072Y179860D01*
X365485Y179745D01*
X365950Y179707D01*
X366415Y179745D01*
X366828Y179860D01*
X367138Y180013D01*
X367397Y180243D01*
X367500Y180550D01*
X367397Y180857D01*
X367138Y181087D01*
X366828Y181240D01*
X366415Y181355D01*
X365950Y181393D01*
X365485Y181355D01*
X365072Y181240D01*
X364762Y181087D01*
X364503Y180857D01*
X364400Y180550D01*
G01X367500Y184110D02*
X364400D01*
X366622Y182692D01*
Y184608D01*
G01X378423Y166890D02*
X375923D01*
X376423Y166570D01*
G01X378423D02*
Y167210D01*
G01X375923Y169090D02*
X376006Y168877D01*
X376215Y168717D01*
X376465Y168610D01*
X376798Y168530D01*
X377173Y168503D01*
X377548Y168530D01*
X377881Y168610D01*
X378131Y168717D01*
X378340Y168877D01*
X378423Y169090D01*
X378340Y169303D01*
X378131Y169463D01*
X377881Y169570D01*
X377548Y169650D01*
X377173Y169677D01*
X376798Y169650D01*
X376465Y169570D01*
X376215Y169463D01*
X376006Y169303D01*
X375923Y169090D01*
G01X378423Y181890D02*
X375923D01*
X376423Y181570D01*
G01X378423D02*
Y182210D01*
G01Y184410D02*
X375923D01*
X377715Y183423D01*
Y184757D01*
G01X370050Y174000D02*
X372550D01*
G01X370050Y173387D02*
Y174613D01*
G01X372550Y175667D02*
X370050D01*
Y176307D01*
X370175Y176520D01*
X370467Y176680D01*
X370800Y176733D01*
X371133Y176680D01*
X371383Y176547D01*
X371508Y176307D01*
Y175667D01*
G01X372550Y178720D02*
X370050D01*
X371842Y177733D01*
Y179067D01*
G01X372550Y180547D02*
X372008Y180600D01*
X371550Y180680D01*
X371133Y180787D01*
X370675Y180920D01*
X370050Y181133D01*
Y180067D01*
G01X364493Y197292D02*
X364680Y197583D01*
X364840Y197750D01*
X365053Y197833D01*
X365240Y197750D01*
X365373Y197583D01*
X365480Y197333D01*
X365507Y197042D01*
X365480Y196792D01*
X365373Y196542D01*
X365213Y196333D01*
X365027Y196250D01*
X364813Y196333D01*
X364627Y196583D01*
X364520Y196958D01*
X364493Y197375D01*
X364547Y197917D01*
X364627Y198208D01*
X364760Y198500D01*
X364947Y198708D01*
X365133Y198750D01*
X365320Y198667D01*
X365453Y198458D01*
G01X361913Y185450D02*
X362073Y185158D01*
X362287Y184992D01*
X362527Y184950D01*
X362740Y184992D01*
X362953Y185200D01*
X363087Y185450D01*
X363113Y185700D01*
X363060Y185992D01*
X362873Y186200D01*
X362687Y186283D01*
X362447D01*
G01X362687D02*
X362847Y186408D01*
X362980Y186617D01*
X363033Y186867D01*
X362980Y187117D01*
X362847Y187325D01*
X362607Y187450D01*
X362367Y187408D01*
X362127Y187242D01*
G01X378423Y197390D02*
X375923D01*
X376423Y197070D01*
G01X378423D02*
Y197710D01*
G01Y199590D02*
X378381Y199777D01*
X378256Y199990D01*
X378048Y200123D01*
X377756Y200177D01*
X377465Y200123D01*
X377215Y199963D01*
X377090Y199723D01*
Y199457D01*
X377006Y199297D01*
X376798Y199163D01*
X376506Y199110D01*
X376215Y199190D01*
X376006Y199377D01*
X375923Y199590D01*
X376006Y199803D01*
X376215Y199990D01*
X376506Y200070D01*
X376798Y200017D01*
X377006Y199883D01*
X377090Y199723D01*
Y199457D01*
X377215Y199217D01*
X377465Y199057D01*
X377756Y199003D01*
X378048Y199057D01*
X378256Y199190D01*
X378381Y199403D01*
X378423Y199590D01*
G01Y189890D02*
X375923D01*
X376423Y189570D01*
G01X378423D02*
Y190210D01*
G01X377381Y191583D02*
X377090Y191770D01*
X376923Y191930D01*
X376840Y192143D01*
X376923Y192330D01*
X377090Y192463D01*
X377340Y192570D01*
X377631Y192597D01*
X377881Y192570D01*
X378131Y192463D01*
X378340Y192303D01*
X378423Y192117D01*
X378340Y191903D01*
X378090Y191717D01*
X377715Y191610D01*
X377298Y191583D01*
X376756Y191637D01*
X376465Y191717D01*
X376173Y191850D01*
X375965Y192037D01*
X375923Y192223D01*
X376006Y192410D01*
X376215Y192543D01*
G01X364557Y204100D02*
Y201878D01*
X364710Y201413D01*
X365017Y201103D01*
X365400Y201000D01*
X365783Y201103D01*
X366090Y201413D01*
X366243Y201878D01*
Y204100D01*
G01X368500Y201000D02*
Y204100D01*
X368040Y203480D01*
G01Y201000D02*
X368960D01*
G01X371600D02*
Y204100D01*
X371140Y203480D01*
G01Y201000D02*
X372060D01*
G01X376340Y213383D02*
X376090Y213543D01*
X375965Y213730D01*
X375923Y213943D01*
X376006Y214210D01*
X376215Y214397D01*
X376465Y214450D01*
X376715Y214423D01*
X376923Y214317D01*
X377340Y213783D01*
X377631Y213543D01*
X378048Y213383D01*
X378423Y213330D01*
Y214450D01*
G01X376340Y215583D02*
X376090Y215743D01*
X375965Y215930D01*
X375923Y216143D01*
X376006Y216410D01*
X376215Y216597D01*
X376465Y216650D01*
X376715Y216623D01*
X376923Y216517D01*
X377340Y215983D01*
X377631Y215743D01*
X378048Y215583D01*
X378423Y215530D01*
Y216650D01*
G01X376340Y205383D02*
X376090Y205543D01*
X375965Y205730D01*
X375923Y205943D01*
X376006Y206210D01*
X376215Y206397D01*
X376465Y206450D01*
X376715Y206423D01*
X376923Y206317D01*
X377340Y205783D01*
X377631Y205543D01*
X378048Y205383D01*
X378423Y205330D01*
Y206450D01*
G01X375923Y208090D02*
X376006Y207877D01*
X376215Y207717D01*
X376465Y207610D01*
X376798Y207530D01*
X377173Y207503D01*
X377548Y207530D01*
X377881Y207610D01*
X378131Y207717D01*
X378340Y207877D01*
X378423Y208090D01*
X378340Y208303D01*
X378131Y208463D01*
X377881Y208570D01*
X377548Y208650D01*
X377173Y208677D01*
X376798Y208650D01*
X376465Y208570D01*
X376215Y208463D01*
X376006Y208303D01*
X375923Y208090D01*
G01X361633Y217050D02*
Y213950D01*
X363167D01*
G01X364657Y214570D02*
X364887Y214208D01*
X365193Y214002D01*
X365538Y213950D01*
X365845Y214002D01*
X366152Y214260D01*
X366343Y214570D01*
X366382Y214880D01*
X366305Y215242D01*
X366037Y215500D01*
X365768Y215603D01*
X365423D01*
G01X365768D02*
X365998Y215758D01*
X366190Y216017D01*
X366267Y216327D01*
X366190Y216637D01*
X365998Y216895D01*
X365653Y217050D01*
X365308Y216998D01*
X364963Y216792D01*
G01X367757Y214570D02*
X367987Y214208D01*
X368293Y214002D01*
X368638Y213950D01*
X368945Y214002D01*
X369252Y214260D01*
X369443Y214570D01*
X369482Y214880D01*
X369405Y215242D01*
X369137Y215500D01*
X368868Y215603D01*
X368523D01*
G01X368868D02*
X369098Y215758D01*
X369290Y216017D01*
X369367Y216327D01*
X369290Y216637D01*
X369098Y216895D01*
X368753Y217050D01*
X368408Y216998D01*
X368063Y216792D01*
G01X368708Y225693D02*
X368553Y225463D01*
X368450Y225195D01*
Y224888D01*
X368605Y224543D01*
X368863Y224275D01*
X369173Y224083D01*
X369690Y223930D01*
X370155Y223892D01*
X370620Y223968D01*
X370930Y224083D01*
X371240Y224313D01*
X371447Y224582D01*
X371550Y224850D01*
Y225118D01*
X371447Y225387D01*
X371292Y225617D01*
X371085Y225808D01*
G01X368967Y227222D02*
X368657Y227452D01*
X368502Y227720D01*
X368450Y228027D01*
X368553Y228410D01*
X368812Y228678D01*
X369122Y228755D01*
X369432Y228717D01*
X369690Y228563D01*
X370207Y227797D01*
X370568Y227452D01*
X371085Y227222D01*
X371550Y227145D01*
Y228755D01*
G01X371085Y230207D02*
X371343Y230437D01*
X371498Y230705D01*
X371550Y231050D01*
X371447Y231395D01*
X371240Y231663D01*
X370878Y231855D01*
X370465Y231893D01*
X370052Y231817D01*
X369793Y231625D01*
X369587Y231357D01*
X369535Y231088D01*
X369587Y230820D01*
X369793Y230475D01*
X368450Y230590D01*
Y231625D01*
G01Y234150D02*
X368553Y233843D01*
X368812Y233613D01*
X369122Y233460D01*
X369535Y233345D01*
X370000Y233307D01*
X370465Y233345D01*
X370878Y233460D01*
X371188Y233613D01*
X371447Y233843D01*
X371550Y234150D01*
X371447Y234457D01*
X371188Y234687D01*
X370878Y234840D01*
X370465Y234955D01*
X370000Y234993D01*
X369535Y234955D01*
X369122Y234840D01*
X368812Y234687D01*
X368553Y234457D01*
X368450Y234150D01*
G01X363387Y225742D02*
X363227Y225867D01*
X363040Y225950D01*
X362827D01*
X362587Y225825D01*
X362400Y225617D01*
X362267Y225367D01*
X362160Y224950D01*
X362133Y224575D01*
X362187Y224200D01*
X362267Y223950D01*
X362427Y223700D01*
X362613Y223533D01*
X362800Y223450D01*
X362987D01*
X363173Y223533D01*
X363333Y223658D01*
X363467Y223825D01*
G01X365320Y223450D02*
Y225950D01*
X364333Y224158D01*
X365667D01*
G01X367147Y223450D02*
X367200Y223992D01*
X367280Y224450D01*
X367387Y224867D01*
X367520Y225325D01*
X367733Y225950D01*
X366667D01*
G01X363387Y229742D02*
X363227Y229867D01*
X363040Y229950D01*
X362827D01*
X362587Y229825D01*
X362400Y229617D01*
X362267Y229367D01*
X362160Y228950D01*
X362133Y228575D01*
X362187Y228200D01*
X362267Y227950D01*
X362427Y227700D01*
X362613Y227533D01*
X362800Y227450D01*
X362987D01*
X363173Y227533D01*
X363333Y227658D01*
X363467Y227825D01*
G01X364413D02*
X364573Y227617D01*
X364760Y227492D01*
X365000Y227450D01*
X365240Y227533D01*
X365427Y227700D01*
X365560Y227992D01*
X365587Y228325D01*
X365533Y228658D01*
X365400Y228867D01*
X365213Y229033D01*
X365027Y229075D01*
X364840Y229033D01*
X364600Y228867D01*
X364680Y229950D01*
X365400D01*
G01X367200Y227450D02*
Y229950D01*
X366880Y229450D01*
G01Y227450D02*
X367520D01*
G01X377050Y224583D02*
X373950D01*
Y225542D01*
X374105Y225848D01*
X374312Y226040D01*
X374725Y226117D01*
X375138Y226040D01*
X375397Y225810D01*
X375552Y225542D01*
Y224583D01*
G01Y225542D02*
X377050Y226117D01*
G01Y228450D02*
X373950D01*
X374570Y227990D01*
G01X377050D02*
Y228910D01*
G01X375758Y230822D02*
X375397Y231090D01*
X375190Y231320D01*
X375087Y231627D01*
X375190Y231895D01*
X375397Y232087D01*
X375707Y232240D01*
X376068Y232278D01*
X376378Y232240D01*
X376688Y232087D01*
X376947Y231857D01*
X377050Y231588D01*
X376947Y231282D01*
X376637Y231013D01*
X376172Y230860D01*
X375655Y230822D01*
X374983Y230898D01*
X374622Y231013D01*
X374260Y231205D01*
X374002Y231473D01*
X373950Y231742D01*
X374053Y232010D01*
X374312Y232202D01*
G01X377050Y235110D02*
X373950D01*
X376172Y233692D01*
Y235608D01*
G01X360500Y248500D02*
Y254500D01*
G01X363820Y243950D02*
Y246450D01*
X362833Y244658D01*
X364167D01*
G01X376493Y246292D02*
X376680Y246583D01*
X376840Y246750D01*
X377053Y246833D01*
X377240Y246750D01*
X377373Y246583D01*
X377480Y246333D01*
X377507Y246042D01*
X377480Y245792D01*
X377373Y245542D01*
X377213Y245333D01*
X377027Y245250D01*
X376813Y245333D01*
X376627Y245583D01*
X376520Y245958D01*
X376493Y246375D01*
X376547Y246917D01*
X376627Y247208D01*
X376760Y247500D01*
X376947Y247708D01*
X377133Y247750D01*
X377320Y247667D01*
X377453Y247458D01*
G01X360913Y265250D02*
X361073Y264958D01*
X361287Y264792D01*
X361527Y264750D01*
X361740Y264792D01*
X361953Y265000D01*
X362087Y265250D01*
X362113Y265500D01*
X362060Y265792D01*
X361873Y266000D01*
X361687Y266083D01*
X361447D01*
G01X361687D02*
X361847Y266208D01*
X361980Y266417D01*
X362033Y266667D01*
X361980Y266917D01*
X361847Y267125D01*
X361607Y267250D01*
X361367Y267208D01*
X361127Y267042D01*
G01X363807Y272603D02*
X363960Y272758D01*
X364075Y273017D01*
X364152Y273378D01*
X364075Y273688D01*
X363922Y273895D01*
X363653Y274050D01*
X362618D01*
Y270950D01*
X363883D01*
X364152Y271157D01*
X364305Y271467D01*
X364382Y271828D01*
X364305Y272190D01*
X364075Y272500D01*
X363807Y272603D01*
X362618D01*
G01X362750Y283700D02*
X365250D01*
G01X362750Y283087D02*
Y284313D01*
G01X365250Y285367D02*
X362750D01*
Y286007D01*
X362875Y286220D01*
X363167Y286380D01*
X363500Y286433D01*
X363833Y286380D01*
X364083Y286247D01*
X364208Y286007D01*
Y285367D01*
G01X364875Y287513D02*
X365083Y287673D01*
X365208Y287860D01*
X365250Y288100D01*
X365167Y288340D01*
X365000Y288527D01*
X364708Y288660D01*
X364375Y288687D01*
X364042Y288633D01*
X363833Y288500D01*
X363667Y288313D01*
X363625Y288127D01*
X363667Y287940D01*
X363833Y287700D01*
X362750Y287780D01*
Y288500D01*
G01X364875Y289713D02*
X365083Y289873D01*
X365208Y290060D01*
X365250Y290300D01*
X365167Y290540D01*
X365000Y290727D01*
X364708Y290860D01*
X364375Y290887D01*
X364042Y290833D01*
X363833Y290700D01*
X363667Y290513D01*
X363625Y290327D01*
X363667Y290140D01*
X363833Y289900D01*
X362750Y289980D01*
Y290700D01*
G01X363000Y298000D02*
Y305000D01*
G01D02*
X364000D01*
G01X367500Y305500D02*
X377500D01*
G01X376083Y312450D02*
Y315550D01*
X377042D01*
X377348Y315395D01*
X377540Y315188D01*
X377617Y314775D01*
X377540Y314362D01*
X377310Y314103D01*
X377042Y313948D01*
X376083D01*
G01X377042D02*
X377617Y312450D01*
G01X379950D02*
Y315550D01*
X379490Y314930D01*
G01Y312450D02*
X380410D01*
G01X383510D02*
Y315550D01*
X382092Y313328D01*
X384008D01*
G01X386150Y315550D02*
X385843Y315447D01*
X385613Y315188D01*
X385460Y314878D01*
X385345Y314465D01*
X385307Y314000D01*
X385345Y313535D01*
X385460Y313122D01*
X385613Y312812D01*
X385843Y312553D01*
X386150Y312450D01*
X386457Y312553D01*
X386687Y312812D01*
X386840Y313122D01*
X386955Y313535D01*
X386993Y314000D01*
X386955Y314465D01*
X386840Y314878D01*
X386687Y315188D01*
X386457Y315447D01*
X386150Y315550D01*
G01X360657Y317750D02*
Y315528D01*
X360810Y315063D01*
X361117Y314753D01*
X361500Y314650D01*
X361883Y314753D01*
X362190Y315063D01*
X362343Y315528D01*
Y317750D01*
G01X363872Y317233D02*
X364102Y317543D01*
X364370Y317698D01*
X364677Y317750D01*
X365060Y317647D01*
X365328Y317388D01*
X365405Y317078D01*
X365367Y316768D01*
X365213Y316510D01*
X364447Y315993D01*
X364102Y315632D01*
X363872Y315115D01*
X363795Y314650D01*
X365405D01*
G01X366857Y315270D02*
X367087Y314908D01*
X367393Y314702D01*
X367738Y314650D01*
X368045Y314702D01*
X368352Y314960D01*
X368543Y315270D01*
X368582Y315580D01*
X368505Y315942D01*
X368237Y316200D01*
X367968Y316303D01*
X367623D01*
G01X367968D02*
X368198Y316458D01*
X368390Y316717D01*
X368467Y317027D01*
X368390Y317337D01*
X368198Y317595D01*
X367853Y317750D01*
X367508Y317698D01*
X367163Y317492D01*
G01X369050Y381633D02*
X365950D01*
Y382592D01*
X366105Y382898D01*
X366312Y383090D01*
X366725Y383167D01*
X367138Y383090D01*
X367397Y382860D01*
X367552Y382592D01*
Y381633D01*
G01Y382592D02*
X369050Y383167D01*
G01Y385500D02*
X365950D01*
X366570Y385040D01*
G01X369050D02*
Y385960D01*
G01Y388523D02*
X368378Y388600D01*
X367810Y388715D01*
X367293Y388868D01*
X366725Y389060D01*
X365950Y389367D01*
Y387833D01*
G01X376083Y390450D02*
Y393550D01*
X377042D01*
X377348Y393395D01*
X377540Y393188D01*
X377617Y392775D01*
X377540Y392362D01*
X377310Y392103D01*
X377042Y391948D01*
X376083D01*
G01X377042D02*
X377617Y390450D01*
G01X380410D02*
Y393550D01*
X378992Y391328D01*
X380908D01*
G01X383510Y390450D02*
Y393550D01*
X382092Y391328D01*
X384008D01*
G01X386150Y390450D02*
X386418Y390502D01*
X386725Y390657D01*
X386917Y390915D01*
X386993Y391277D01*
X386917Y391638D01*
X386687Y391948D01*
X386342Y392103D01*
X385958D01*
X385728Y392207D01*
X385537Y392465D01*
X385460Y392827D01*
X385575Y393188D01*
X385843Y393447D01*
X386150Y393550D01*
X386457Y393447D01*
X386725Y393188D01*
X386840Y392827D01*
X386763Y392465D01*
X386572Y392207D01*
X386342Y392103D01*
X385958D01*
X385613Y391948D01*
X385383Y391638D01*
X385307Y391277D01*
X385383Y390915D01*
X385575Y390657D01*
X385882Y390502D01*
X386150Y390450D01*
G01X376083Y386450D02*
Y389550D01*
X377042D01*
X377348Y389395D01*
X377540Y389188D01*
X377617Y388775D01*
X377540Y388362D01*
X377310Y388103D01*
X377042Y387948D01*
X376083D01*
G01X377042D02*
X377617Y386450D01*
G01X380410D02*
Y389550D01*
X378992Y387328D01*
X380908D01*
G01X383510Y386450D02*
Y389550D01*
X382092Y387328D01*
X384008D01*
G01X385498Y386812D02*
X385767Y386553D01*
X386073Y386450D01*
X386380Y386553D01*
X386648Y386863D01*
X386840Y387328D01*
X386917Y387793D01*
Y388362D01*
X386840Y388827D01*
X386648Y389240D01*
X386418Y389447D01*
X386150Y389550D01*
X385843Y389447D01*
X385613Y389240D01*
X385460Y388930D01*
X385383Y388517D01*
X385460Y388155D01*
X385652Y387793D01*
X385882Y387587D01*
X386150Y387535D01*
X386457Y387638D01*
X386687Y387897D01*
X386917Y388362D01*
G01X364043Y403992D02*
X363813Y404147D01*
X363545Y404250D01*
X363238D01*
X362893Y404095D01*
X362625Y403837D01*
X362433Y403527D01*
X362280Y403010D01*
X362242Y402545D01*
X362318Y402080D01*
X362433Y401770D01*
X362663Y401460D01*
X362932Y401253D01*
X363200Y401150D01*
X363468D01*
X363737Y401253D01*
X363967Y401408D01*
X364158Y401615D01*
G01X366760Y401150D02*
Y404250D01*
X365342Y402028D01*
X367258D01*
G01X368672Y402442D02*
X368940Y402803D01*
X369170Y403010D01*
X369477Y403113D01*
X369745Y403010D01*
X369937Y402803D01*
X370090Y402493D01*
X370128Y402132D01*
X370090Y401822D01*
X369937Y401512D01*
X369707Y401253D01*
X369438Y401150D01*
X369132Y401253D01*
X368863Y401563D01*
X368710Y402028D01*
X368672Y402545D01*
X368748Y403217D01*
X368863Y403578D01*
X369055Y403940D01*
X369323Y404198D01*
X369592Y404250D01*
X369860Y404147D01*
X370052Y403888D01*
G01X364043Y399492D02*
X363813Y399647D01*
X363545Y399750D01*
X363238D01*
X362893Y399595D01*
X362625Y399337D01*
X362433Y399027D01*
X362280Y398510D01*
X362242Y398045D01*
X362318Y397580D01*
X362433Y397270D01*
X362663Y396960D01*
X362932Y396753D01*
X363200Y396650D01*
X363468D01*
X363737Y396753D01*
X363967Y396908D01*
X364158Y397115D01*
G01X366760Y396650D02*
Y399750D01*
X365342Y397528D01*
X367258D01*
G01X368748Y397012D02*
X369017Y396753D01*
X369323Y396650D01*
X369630Y396753D01*
X369898Y397063D01*
X370090Y397528D01*
X370167Y397993D01*
Y398562D01*
X370090Y399027D01*
X369898Y399440D01*
X369668Y399647D01*
X369400Y399750D01*
X369093Y399647D01*
X368863Y399440D01*
X368710Y399130D01*
X368633Y398717D01*
X368710Y398355D01*
X368902Y397993D01*
X369132Y397787D01*
X369400Y397735D01*
X369707Y397838D01*
X369937Y398097D01*
X370167Y398562D01*
G01X362433Y405150D02*
Y408250D01*
X363392D01*
X363698Y408095D01*
X363890Y407888D01*
X363967Y407475D01*
X363890Y407062D01*
X363660Y406803D01*
X363392Y406648D01*
X362433D01*
G01X363392D02*
X363967Y405150D01*
G01X365457Y405615D02*
X365687Y405357D01*
X365955Y405202D01*
X366300Y405150D01*
X366645Y405253D01*
X366913Y405460D01*
X367105Y405822D01*
X367143Y406235D01*
X367067Y406648D01*
X366875Y406907D01*
X366607Y407113D01*
X366338Y407165D01*
X366070Y407113D01*
X365725Y406907D01*
X365840Y408250D01*
X366875D01*
G01X368672Y407733D02*
X368902Y408043D01*
X369170Y408198D01*
X369477Y408250D01*
X369860Y408147D01*
X370128Y407888D01*
X370205Y407578D01*
X370167Y407268D01*
X370013Y407010D01*
X369247Y406493D01*
X368902Y406132D01*
X368672Y405615D01*
X368595Y405150D01*
X370205D01*
G01X373350Y414550D02*
Y411450D01*
G01X372468Y414550D02*
X374232D01*
G01X375683Y411450D02*
Y414550D01*
X376603D01*
X376910Y414395D01*
X377140Y414033D01*
X377217Y413620D01*
X377140Y413207D01*
X376948Y412897D01*
X376603Y412742D01*
X375683D01*
G01X378707Y411915D02*
X378937Y411657D01*
X379205Y411502D01*
X379550Y411450D01*
X379895Y411553D01*
X380163Y411760D01*
X380355Y412122D01*
X380393Y412535D01*
X380317Y412948D01*
X380125Y413207D01*
X379857Y413413D01*
X379588Y413465D01*
X379320Y413413D01*
X378975Y413207D01*
X379090Y414550D01*
X380125D01*
G01X381998Y411812D02*
X382267Y411553D01*
X382573Y411450D01*
X382880Y411553D01*
X383148Y411863D01*
X383340Y412328D01*
X383417Y412793D01*
Y413362D01*
X383340Y413827D01*
X383148Y414240D01*
X382918Y414447D01*
X382650Y414550D01*
X382343Y414447D01*
X382113Y414240D01*
X381960Y413930D01*
X381883Y413517D01*
X381960Y413155D01*
X382152Y412793D01*
X382382Y412587D01*
X382650Y412535D01*
X382957Y412638D01*
X383187Y412897D01*
X383417Y413362D01*
G01X388717Y68797D02*
X385617D01*
X386237Y68337D01*
G01X388717D02*
Y69257D01*
G01X393450Y66000D02*
Y67395D01*
X392683Y69100D01*
G01X394217D02*
X393450Y67395D01*
G01X397010Y66000D02*
Y69100D01*
X395592Y66878D01*
X397508D01*
G01X391208Y103193D02*
X391053Y102963D01*
X390950Y102695D01*
Y102388D01*
X391105Y102043D01*
X391363Y101775D01*
X391673Y101583D01*
X392190Y101430D01*
X392655Y101392D01*
X393120Y101468D01*
X393430Y101583D01*
X393740Y101813D01*
X393947Y102082D01*
X394050Y102350D01*
Y102618D01*
X393947Y102887D01*
X393792Y103117D01*
X393585Y103308D01*
G01X391467Y104722D02*
X391157Y104952D01*
X391002Y105220D01*
X390950Y105527D01*
X391053Y105910D01*
X391312Y106178D01*
X391622Y106255D01*
X391932Y106217D01*
X392190Y106063D01*
X392707Y105297D01*
X393068Y104952D01*
X393585Y104722D01*
X394050Y104645D01*
Y106255D01*
G01X393585Y107707D02*
X393843Y107937D01*
X393998Y108205D01*
X394050Y108550D01*
X393947Y108895D01*
X393740Y109163D01*
X393378Y109355D01*
X392965Y109393D01*
X392552Y109317D01*
X392293Y109125D01*
X392087Y108857D01*
X392035Y108588D01*
X392087Y108320D01*
X392293Y107975D01*
X390950Y108090D01*
Y109125D01*
G01X394050Y112110D02*
X390950D01*
X393172Y110692D01*
Y112608D01*
G01X393050Y125833D02*
X390550Y126500D01*
X393050Y127167D01*
G01X392175Y126927D02*
Y126073D01*
G01X393700Y122963D02*
X393575Y123070D01*
X393366Y123150D01*
X393075Y123203D01*
X392825Y123150D01*
X392658Y123043D01*
X392533Y122857D01*
Y122137D01*
X395033D01*
Y123017D01*
X394866Y123203D01*
X394616Y123310D01*
X394325Y123363D01*
X394033Y123310D01*
X393783Y123150D01*
X393700Y122963D01*
Y122137D01*
G01X382750Y139413D02*
X383042Y139573D01*
X383208Y139787D01*
X383250Y140027D01*
X383208Y140240D01*
X383000Y140453D01*
X382750Y140587D01*
X382500Y140613D01*
X382208Y140560D01*
X382000Y140373D01*
X381917Y140187D01*
Y139947D01*
G01Y140187D02*
X381792Y140347D01*
X381583Y140480D01*
X381333Y140533D01*
X381083Y140480D01*
X380875Y140347D01*
X380750Y140107D01*
X380792Y139867D01*
X380958Y139627D01*
G01X383750Y134500D02*
X381250D01*
X381750Y134180D01*
G01X383750D02*
Y134820D01*
G01X378208Y151993D02*
X377917Y152180D01*
X377750Y152340D01*
X377667Y152553D01*
X377750Y152740D01*
X377917Y152873D01*
X378167Y152980D01*
X378458Y153007D01*
X378708Y152980D01*
X378958Y152873D01*
X379167Y152713D01*
X379250Y152527D01*
X379167Y152313D01*
X378917Y152127D01*
X378542Y152020D01*
X378125Y151993D01*
X377583Y152047D01*
X377292Y152127D01*
X377000Y152260D01*
X376792Y152447D01*
X376750Y152633D01*
X376833Y152820D01*
X377042Y152953D01*
G01X381923Y157437D02*
X381381Y157490D01*
X380923Y157570D01*
X380506Y157677D01*
X380048Y157810D01*
X379423Y158023D01*
Y156957D01*
G01X381548Y148903D02*
X381756Y149063D01*
X381881Y149250D01*
X381923Y149490D01*
X381840Y149730D01*
X381673Y149917D01*
X381381Y150050D01*
X381048Y150077D01*
X380715Y150023D01*
X380506Y149890D01*
X380340Y149703D01*
X380298Y149517D01*
X380340Y149330D01*
X380506Y149090D01*
X379423Y149170D01*
Y149890D01*
G01X382250Y179400D02*
X379750D01*
X380250Y179080D01*
G01X382250D02*
Y179720D01*
G01X381750Y181013D02*
X382042Y181173D01*
X382208Y181387D01*
X382250Y181627D01*
X382208Y181840D01*
X382000Y182053D01*
X381750Y182187D01*
X381500Y182213D01*
X381208Y182160D01*
X381000Y181973D01*
X380917Y181787D01*
Y181547D01*
G01Y181787D02*
X380792Y181947D01*
X380583Y182080D01*
X380333Y182133D01*
X380083Y182080D01*
X379875Y181947D01*
X379750Y181707D01*
X379792Y181467D01*
X379958Y181227D01*
G01X378750Y172400D02*
X376250D01*
X376750Y172080D01*
G01X378750D02*
Y172720D01*
G01X376667Y174093D02*
X376417Y174253D01*
X376292Y174440D01*
X376250Y174653D01*
X376333Y174920D01*
X376542Y175107D01*
X376792Y175160D01*
X377042Y175133D01*
X377250Y175027D01*
X377667Y174493D01*
X377958Y174253D01*
X378375Y174093D01*
X378750Y174040D01*
Y175160D01*
G01X381631Y164537D02*
X381840Y164723D01*
X381923Y164937D01*
X381840Y165150D01*
X381590Y165337D01*
X381215Y165470D01*
X380840Y165523D01*
X380381D01*
X380006Y165470D01*
X379673Y165337D01*
X379506Y165177D01*
X379423Y164990D01*
X379506Y164777D01*
X379673Y164617D01*
X379923Y164510D01*
X380256Y164457D01*
X380548Y164510D01*
X380840Y164643D01*
X381006Y164803D01*
X381048Y164990D01*
X380965Y165203D01*
X380756Y165363D01*
X380381Y165523D01*
G01X381923Y169890D02*
X379423D01*
X379923Y169570D01*
G01X381923D02*
Y170210D01*
G01Y172090D02*
X379423D01*
X379923Y171770D01*
G01X381923D02*
Y172410D01*
G01Y193890D02*
X379423D01*
X379923Y193570D01*
G01X381923D02*
Y194210D01*
G01Y196037D02*
X381381Y196090D01*
X380923Y196170D01*
X380506Y196277D01*
X380048Y196410D01*
X379423Y196623D01*
Y195557D01*
G01X380667Y211393D02*
X380417Y211553D01*
X380292Y211740D01*
X380250Y211953D01*
X380333Y212220D01*
X380542Y212407D01*
X380792Y212460D01*
X381042Y212433D01*
X381250Y212327D01*
X381667Y211793D01*
X381958Y211553D01*
X382375Y211393D01*
X382750Y211340D01*
Y212460D01*
G01Y214100D02*
X380250D01*
X380750Y213780D01*
G01X382750D02*
Y214420D01*
G01X382250Y200400D02*
X379750D01*
X380250Y200080D01*
G01X382250D02*
Y200720D01*
G01X381958Y202147D02*
X382167Y202333D01*
X382250Y202547D01*
X382167Y202760D01*
X381917Y202947D01*
X381542Y203080D01*
X381167Y203133D01*
X380708D01*
X380333Y203080D01*
X380000Y202947D01*
X379833Y202787D01*
X379750Y202600D01*
X379833Y202387D01*
X380000Y202227D01*
X380250Y202120D01*
X380583Y202067D01*
X380875Y202120D01*
X381167Y202253D01*
X381333Y202413D01*
X381375Y202600D01*
X381292Y202813D01*
X381083Y202973D01*
X380708Y203133D01*
G01X383250Y221600D02*
X385750D01*
G01X383250Y220987D02*
Y222213D01*
G01X385750Y223267D02*
X383250D01*
Y223907D01*
X383375Y224120D01*
X383667Y224280D01*
X384000Y224333D01*
X384333Y224280D01*
X384583Y224147D01*
X384708Y223907D01*
Y223267D01*
G01X385750Y226000D02*
X383250D01*
X383750Y225680D01*
G01X385750D02*
Y226320D01*
G01Y228200D02*
X385708Y228387D01*
X385583Y228600D01*
X385375Y228733D01*
X385083Y228787D01*
X384792Y228733D01*
X384542Y228573D01*
X384417Y228333D01*
Y228067D01*
X384333Y227907D01*
X384125Y227773D01*
X383833Y227720D01*
X383542Y227800D01*
X383333Y227987D01*
X383250Y228200D01*
X383333Y228413D01*
X383542Y228600D01*
X383833Y228680D01*
X384125Y228627D01*
X384333Y228493D01*
X384417Y228333D01*
Y228067D01*
X384542Y227827D01*
X384792Y227667D01*
X385083Y227613D01*
X385375Y227667D01*
X385583Y227800D01*
X385708Y228013D01*
X385750Y228200D01*
G01X383250Y230400D02*
X383333Y230187D01*
X383542Y230027D01*
X383792Y229920D01*
X384125Y229840D01*
X384500Y229813D01*
X384875Y229840D01*
X385208Y229920D01*
X385458Y230027D01*
X385667Y230187D01*
X385750Y230400D01*
X385667Y230613D01*
X385458Y230773D01*
X385208Y230880D01*
X384875Y230960D01*
X384500Y230987D01*
X384125Y230960D01*
X383792Y230880D01*
X383542Y230773D01*
X383333Y230613D01*
X383250Y230400D01*
G01X386750Y221700D02*
X389250D01*
G01X386750Y221087D02*
Y222313D01*
G01X389250Y223367D02*
X386750D01*
Y224007D01*
X386875Y224220D01*
X387167Y224380D01*
X387500Y224433D01*
X387833Y224380D01*
X388083Y224247D01*
X388208Y224007D01*
Y223367D01*
G01X389250Y226047D02*
X388708Y226100D01*
X388250Y226180D01*
X387833Y226287D01*
X387375Y226420D01*
X386750Y226633D01*
Y225567D01*
G01X389250Y228300D02*
X389208Y228487D01*
X389083Y228700D01*
X388875Y228833D01*
X388583Y228887D01*
X388292Y228833D01*
X388042Y228673D01*
X387917Y228433D01*
Y228167D01*
X387833Y228007D01*
X387625Y227873D01*
X387333Y227820D01*
X387042Y227900D01*
X386833Y228087D01*
X386750Y228300D01*
X386833Y228513D01*
X387042Y228700D01*
X387333Y228780D01*
X387625Y228727D01*
X387833Y228593D01*
X387917Y228433D01*
Y228167D01*
X388042Y227927D01*
X388292Y227767D01*
X388583Y227713D01*
X388875Y227767D01*
X389083Y227900D01*
X389208Y228113D01*
X389250Y228300D01*
G01X396050Y237083D02*
X392950D01*
Y238042D01*
X393105Y238348D01*
X393312Y238540D01*
X393725Y238617D01*
X394138Y238540D01*
X394397Y238310D01*
X394552Y238042D01*
Y237083D01*
G01Y238042D02*
X396050Y238617D01*
G01Y240950D02*
X392950D01*
X393570Y240490D01*
G01X396050D02*
Y241410D01*
G01Y243973D02*
X395378Y244050D01*
X394810Y244165D01*
X394293Y244318D01*
X393725Y244510D01*
X392950Y244817D01*
Y243283D01*
G01X393467Y246422D02*
X393157Y246652D01*
X393002Y246920D01*
X392950Y247227D01*
X393053Y247610D01*
X393312Y247878D01*
X393622Y247955D01*
X393932Y247917D01*
X394190Y247763D01*
X394707Y246997D01*
X395068Y246652D01*
X395585Y246422D01*
X396050Y246345D01*
Y247955D01*
G01X390550Y237083D02*
X387450D01*
Y238042D01*
X387605Y238348D01*
X387812Y238540D01*
X388225Y238617D01*
X388638Y238540D01*
X388897Y238310D01*
X389052Y238042D01*
Y237083D01*
G01Y238042D02*
X390550Y238617D01*
G01X387967Y240222D02*
X387657Y240452D01*
X387502Y240720D01*
X387450Y241027D01*
X387553Y241410D01*
X387812Y241678D01*
X388122Y241755D01*
X388432Y241717D01*
X388690Y241563D01*
X389207Y240797D01*
X389568Y240452D01*
X390085Y240222D01*
X390550Y240145D01*
Y241755D01*
G01Y244050D02*
X390498Y244318D01*
X390343Y244625D01*
X390085Y244817D01*
X389723Y244893D01*
X389362Y244817D01*
X389052Y244587D01*
X388897Y244242D01*
Y243858D01*
X388793Y243628D01*
X388535Y243437D01*
X388173Y243360D01*
X387812Y243475D01*
X387553Y243743D01*
X387450Y244050D01*
X387553Y244357D01*
X387812Y244625D01*
X388173Y244740D01*
X388535Y244663D01*
X388793Y244472D01*
X388897Y244242D01*
Y243858D01*
X389052Y243513D01*
X389362Y243283D01*
X389723Y243207D01*
X390085Y243283D01*
X390343Y243475D01*
X390498Y243782D01*
X390550Y244050D01*
G01X389930Y246307D02*
X390292Y246537D01*
X390498Y246843D01*
X390550Y247188D01*
X390498Y247495D01*
X390240Y247802D01*
X389930Y247993D01*
X389620Y248032D01*
X389258Y247955D01*
X389000Y247687D01*
X388897Y247418D01*
Y247073D01*
G01Y247418D02*
X388742Y247648D01*
X388483Y247840D01*
X388173Y247917D01*
X387863Y247840D01*
X387605Y247648D01*
X387450Y247303D01*
X387502Y246958D01*
X387708Y246613D01*
G01X384550Y237083D02*
X381450D01*
Y238042D01*
X381605Y238348D01*
X381812Y238540D01*
X382225Y238617D01*
X382638Y238540D01*
X382897Y238310D01*
X383052Y238042D01*
Y237083D01*
G01Y238042D02*
X384550Y238617D01*
G01X381967Y240222D02*
X381657Y240452D01*
X381502Y240720D01*
X381450Y241027D01*
X381553Y241410D01*
X381812Y241678D01*
X382122Y241755D01*
X382432Y241717D01*
X382690Y241563D01*
X383207Y240797D01*
X383568Y240452D01*
X384085Y240222D01*
X384550Y240145D01*
Y241755D01*
G01Y244050D02*
X384498Y244318D01*
X384343Y244625D01*
X384085Y244817D01*
X383723Y244893D01*
X383362Y244817D01*
X383052Y244587D01*
X382897Y244242D01*
Y243858D01*
X382793Y243628D01*
X382535Y243437D01*
X382173Y243360D01*
X381812Y243475D01*
X381553Y243743D01*
X381450Y244050D01*
X381553Y244357D01*
X381812Y244625D01*
X382173Y244740D01*
X382535Y244663D01*
X382793Y244472D01*
X382897Y244242D01*
Y243858D01*
X383052Y243513D01*
X383362Y243283D01*
X383723Y243207D01*
X384085Y243283D01*
X384343Y243475D01*
X384498Y243782D01*
X384550Y244050D01*
G01X384085Y246307D02*
X384343Y246537D01*
X384498Y246805D01*
X384550Y247150D01*
X384447Y247495D01*
X384240Y247763D01*
X383878Y247955D01*
X383465Y247993D01*
X383052Y247917D01*
X382793Y247725D01*
X382587Y247457D01*
X382535Y247188D01*
X382587Y246920D01*
X382793Y246575D01*
X381450Y246690D01*
Y247725D01*
G01X378500Y267500D02*
X378000D01*
G01X378500Y265000D02*
Y267500D01*
G01X389000Y265000D02*
X378500D01*
G01X389000Y279000D02*
Y265000D01*
G01X380057Y263550D02*
Y261328D01*
X380210Y260863D01*
X380517Y260553D01*
X380900Y260450D01*
X381283Y260553D01*
X381590Y260863D01*
X381743Y261328D01*
Y263550D01*
G01X383157Y261070D02*
X383387Y260708D01*
X383693Y260502D01*
X384038Y260450D01*
X384345Y260502D01*
X384652Y260760D01*
X384843Y261070D01*
X384882Y261380D01*
X384805Y261742D01*
X384537Y262000D01*
X384268Y262103D01*
X383923D01*
G01X384268D02*
X384498Y262258D01*
X384690Y262517D01*
X384767Y262827D01*
X384690Y263137D01*
X384498Y263395D01*
X384153Y263550D01*
X383808Y263498D01*
X383463Y263292D01*
G01X387560Y260450D02*
Y263550D01*
X386142Y261328D01*
X388058D01*
G01X382500Y282500D02*
X385000D01*
G01X382500Y290500D02*
Y282500D01*
G01X385000Y280500D02*
X388000D01*
G01X385000Y282500D02*
Y280500D01*
G01X382500Y304500D02*
Y294500D01*
G01X381000Y304500D02*
X382500D01*
G01X377500Y305500D02*
Y305000D01*
G01X383583Y319450D02*
Y322550D01*
X384542D01*
X384848Y322395D01*
X385040Y322188D01*
X385117Y321775D01*
X385040Y321362D01*
X384810Y321103D01*
X384542Y320948D01*
X383583D01*
G01X384542D02*
X385117Y319450D01*
G01X387910D02*
Y322550D01*
X386492Y320328D01*
X388408D01*
G01X389822Y320742D02*
X390090Y321103D01*
X390320Y321310D01*
X390627Y321413D01*
X390895Y321310D01*
X391087Y321103D01*
X391240Y320793D01*
X391278Y320432D01*
X391240Y320122D01*
X391087Y319812D01*
X390857Y319553D01*
X390588Y319450D01*
X390282Y319553D01*
X390013Y319863D01*
X389860Y320328D01*
X389822Y320845D01*
X389898Y321517D01*
X390013Y321878D01*
X390205Y322240D01*
X390473Y322498D01*
X390742Y322550D01*
X391010Y322447D01*
X391202Y322188D01*
G01X392922Y322033D02*
X393152Y322343D01*
X393420Y322498D01*
X393727Y322550D01*
X394110Y322447D01*
X394378Y322188D01*
X394455Y321878D01*
X394417Y321568D01*
X394263Y321310D01*
X393497Y320793D01*
X393152Y320432D01*
X392922Y319915D01*
X392845Y319450D01*
X394455D01*
G01X384083Y330450D02*
Y333550D01*
X385042D01*
X385348Y333395D01*
X385540Y333188D01*
X385617Y332775D01*
X385540Y332362D01*
X385310Y332103D01*
X385042Y331948D01*
X384083D01*
G01X385042D02*
X385617Y330450D01*
G01X388410D02*
Y333550D01*
X386992Y331328D01*
X388908D01*
G01X390322Y331742D02*
X390590Y332103D01*
X390820Y332310D01*
X391127Y332413D01*
X391395Y332310D01*
X391587Y332103D01*
X391740Y331793D01*
X391778Y331432D01*
X391740Y331122D01*
X391587Y330812D01*
X391357Y330553D01*
X391088Y330450D01*
X390782Y330553D01*
X390513Y330863D01*
X390360Y331328D01*
X390322Y331845D01*
X390398Y332517D01*
X390513Y332878D01*
X390705Y333240D01*
X390973Y333498D01*
X391242Y333550D01*
X391510Y333447D01*
X391702Y333188D01*
G01X394150Y330450D02*
Y333550D01*
X393690Y332930D01*
G01Y330450D02*
X394610D01*
G01X383920Y337150D02*
Y339650D01*
X382933Y337858D01*
X384267D01*
G01X391820Y334950D02*
Y337450D01*
X390833Y335658D01*
X392167D01*
G01X386050Y350083D02*
X382950D01*
Y351042D01*
X383105Y351348D01*
X383312Y351540D01*
X383725Y351617D01*
X384138Y351540D01*
X384397Y351310D01*
X384552Y351042D01*
Y350083D01*
G01Y351042D02*
X386050Y351617D01*
G01Y354410D02*
X382950D01*
X385172Y352992D01*
Y354908D01*
G01X384758Y356322D02*
X384397Y356590D01*
X384190Y356820D01*
X384087Y357127D01*
X384190Y357395D01*
X384397Y357587D01*
X384707Y357740D01*
X385068Y357778D01*
X385378Y357740D01*
X385688Y357587D01*
X385947Y357357D01*
X386050Y357088D01*
X385947Y356782D01*
X385637Y356513D01*
X385172Y356360D01*
X384655Y356322D01*
X383983Y356398D01*
X383622Y356513D01*
X383260Y356705D01*
X383002Y356973D01*
X382950Y357242D01*
X383053Y357510D01*
X383312Y357702D01*
G01X386050Y360610D02*
X382950D01*
X385172Y359192D01*
Y361108D01*
G01X390413Y346950D02*
X390573Y346658D01*
X390787Y346492D01*
X391027Y346450D01*
X391240Y346492D01*
X391453Y346700D01*
X391587Y346950D01*
X391613Y347200D01*
X391560Y347492D01*
X391373Y347700D01*
X391187Y347783D01*
X390947D01*
G01X391187D02*
X391347Y347908D01*
X391480Y348117D01*
X391533Y348367D01*
X391480Y348617D01*
X391347Y348825D01*
X391107Y348950D01*
X390867Y348908D01*
X390627Y348742D01*
G01X388450Y351057D02*
X390672D01*
X391137Y351210D01*
X391447Y351517D01*
X391550Y351900D01*
X391447Y352283D01*
X391137Y352590D01*
X390672Y352743D01*
X388450D01*
G01X390930Y354157D02*
X391292Y354387D01*
X391498Y354693D01*
X391550Y355038D01*
X391498Y355345D01*
X391240Y355652D01*
X390930Y355843D01*
X390620Y355882D01*
X390258Y355805D01*
X390000Y355537D01*
X389897Y355268D01*
Y354923D01*
G01Y355268D02*
X389742Y355498D01*
X389483Y355690D01*
X389173Y355767D01*
X388863Y355690D01*
X388605Y355498D01*
X388450Y355153D01*
X388502Y354808D01*
X388708Y354463D01*
G01X391188Y357448D02*
X391447Y357717D01*
X391550Y358023D01*
X391447Y358330D01*
X391137Y358598D01*
X390672Y358790D01*
X390207Y358867D01*
X389638D01*
X389173Y358790D01*
X388760Y358598D01*
X388553Y358368D01*
X388450Y358100D01*
X388553Y357793D01*
X388760Y357563D01*
X389070Y357410D01*
X389483Y357333D01*
X389845Y357410D01*
X390207Y357602D01*
X390413Y357832D01*
X390465Y358100D01*
X390362Y358407D01*
X390103Y358637D01*
X389638Y358867D01*
G01X391700Y388750D02*
Y386250D01*
G01X391087Y388750D02*
X392313D01*
G01X393367Y386250D02*
Y388750D01*
X394007D01*
X394220Y388625D01*
X394380Y388333D01*
X394433Y388000D01*
X394380Y387667D01*
X394247Y387417D01*
X394007Y387292D01*
X393367D01*
G01X396100Y386250D02*
Y388750D01*
X395780Y388250D01*
G01Y386250D02*
X396420D01*
G01X398620D02*
Y388750D01*
X397633Y386958D01*
X398967D01*
G01X378950Y420550D02*
Y417450D01*
G01X378068Y420550D02*
X379832D01*
G01X381283Y417450D02*
Y420550D01*
X382203D01*
X382510Y420395D01*
X382740Y420033D01*
X382817Y419620D01*
X382740Y419207D01*
X382548Y418897D01*
X382203Y418742D01*
X381283D01*
G01X384307Y418070D02*
X384537Y417708D01*
X384843Y417502D01*
X385188Y417450D01*
X385495Y417502D01*
X385802Y417760D01*
X385993Y418070D01*
X386032Y418380D01*
X385955Y418742D01*
X385687Y419000D01*
X385418Y419103D01*
X385073D01*
G01X385418D02*
X385648Y419258D01*
X385840Y419517D01*
X385917Y419827D01*
X385840Y420137D01*
X385648Y420395D01*
X385303Y420550D01*
X384958Y420498D01*
X384613Y420292D01*
G01X388250Y417450D02*
X388518Y417502D01*
X388825Y417657D01*
X389017Y417915D01*
X389093Y418277D01*
X389017Y418638D01*
X388787Y418948D01*
X388442Y419103D01*
X388058D01*
X387828Y419207D01*
X387637Y419465D01*
X387560Y419827D01*
X387675Y420188D01*
X387943Y420447D01*
X388250Y420550D01*
X388557Y420447D01*
X388825Y420188D01*
X388940Y419827D01*
X388863Y419465D01*
X388672Y419207D01*
X388442Y419103D01*
X388058D01*
X387713Y418948D01*
X387483Y418638D01*
X387407Y418277D01*
X387483Y417915D01*
X387675Y417657D01*
X387982Y417502D01*
X388250Y417450D01*
G01X408430Y67546D02*
X408792Y67776D01*
X408998Y68082D01*
X409050Y68427D01*
X408998Y68734D01*
X408740Y69041D01*
X408430Y69232D01*
X408120Y69271D01*
X407758Y69194D01*
X407500Y68926D01*
X407397Y68657D01*
Y68312D01*
G01Y68657D02*
X407242Y68887D01*
X406983Y69079D01*
X406673Y69156D01*
X406363Y69079D01*
X406105Y68887D01*
X405950Y68542D01*
X406002Y68197D01*
X406208Y67852D01*
G01X395208Y103193D02*
X395053Y102963D01*
X394950Y102695D01*
Y102388D01*
X395105Y102043D01*
X395363Y101775D01*
X395673Y101583D01*
X396190Y101430D01*
X396655Y101392D01*
X397120Y101468D01*
X397430Y101583D01*
X397740Y101813D01*
X397947Y102082D01*
X398050Y102350D01*
Y102618D01*
X397947Y102887D01*
X397792Y103117D01*
X397585Y103308D01*
G01X395467Y104722D02*
X395157Y104952D01*
X395002Y105220D01*
X394950Y105527D01*
X395053Y105910D01*
X395312Y106178D01*
X395622Y106255D01*
X395932Y106217D01*
X396190Y106063D01*
X396707Y105297D01*
X397068Y104952D01*
X397585Y104722D01*
X398050Y104645D01*
Y106255D01*
G01X397585Y107707D02*
X397843Y107937D01*
X397998Y108205D01*
X398050Y108550D01*
X397947Y108895D01*
X397740Y109163D01*
X397378Y109355D01*
X396965Y109393D01*
X396552Y109317D01*
X396293Y109125D01*
X396087Y108857D01*
X396035Y108588D01*
X396087Y108320D01*
X396293Y107975D01*
X394950Y108090D01*
Y109125D01*
G01X397430Y110807D02*
X397792Y111037D01*
X397998Y111343D01*
X398050Y111688D01*
X397998Y111995D01*
X397740Y112302D01*
X397430Y112493D01*
X397120Y112532D01*
X396758Y112455D01*
X396500Y112187D01*
X396397Y111918D01*
Y111573D01*
G01Y111918D02*
X396242Y112148D01*
X395983Y112340D01*
X395673Y112417D01*
X395363Y112340D01*
X395105Y112148D01*
X394950Y111803D01*
X395002Y111458D01*
X395208Y111113D01*
G01X397741Y125837D02*
X397616Y125677D01*
X397533Y125490D01*
Y125277D01*
X397658Y125037D01*
X397866Y124850D01*
X398116Y124717D01*
X398533Y124610D01*
X398908Y124583D01*
X399283Y124637D01*
X399533Y124717D01*
X399783Y124877D01*
X399950Y125063D01*
X400033Y125250D01*
Y125437D01*
X399950Y125623D01*
X399825Y125783D01*
X399658Y125917D01*
G01X413250Y121993D02*
X410750D01*
Y123007D01*
G01X411958Y122633D02*
Y121993D01*
G01X405033Y122163D02*
X402533D01*
Y122697D01*
X402658Y122910D01*
X402825Y123070D01*
X403075Y123203D01*
X403366Y123310D01*
X403783Y123337D01*
X404200Y123310D01*
X404491Y123203D01*
X404741Y123070D01*
X404908Y122910D01*
X405033Y122697D01*
Y122163D01*
G01X409533Y125783D02*
Y124717D01*
X407033D01*
Y125783D01*
G01X408241Y125357D02*
Y124717D01*
G01X400750Y222600D02*
X403250D01*
G01X400750Y221987D02*
Y223213D01*
G01X403250Y224267D02*
X400750D01*
Y224907D01*
X400875Y225120D01*
X401167Y225280D01*
X401500Y225333D01*
X401833Y225280D01*
X402083Y225147D01*
X402208Y224907D01*
Y224267D01*
G01X403250Y227000D02*
X400750D01*
X401250Y226680D01*
G01X403250D02*
Y227320D01*
G01Y229200D02*
X403208Y229387D01*
X403083Y229600D01*
X402875Y229733D01*
X402583Y229787D01*
X402292Y229733D01*
X402042Y229573D01*
X401917Y229333D01*
Y229067D01*
X401833Y228907D01*
X401625Y228773D01*
X401333Y228720D01*
X401042Y228800D01*
X400833Y228987D01*
X400750Y229200D01*
X400833Y229413D01*
X401042Y229600D01*
X401333Y229680D01*
X401625Y229627D01*
X401833Y229493D01*
X401917Y229333D01*
Y229067D01*
X402042Y228827D01*
X402292Y228667D01*
X402583Y228613D01*
X402875Y228667D01*
X403083Y228800D01*
X403208Y229013D01*
X403250Y229200D01*
G01X402208Y230893D02*
X401917Y231080D01*
X401750Y231240D01*
X401667Y231453D01*
X401750Y231640D01*
X401917Y231773D01*
X402167Y231880D01*
X402458Y231907D01*
X402708Y231880D01*
X402958Y231773D01*
X403167Y231613D01*
X403250Y231427D01*
X403167Y231213D01*
X402917Y231027D01*
X402542Y230920D01*
X402125Y230893D01*
X401583Y230947D01*
X401292Y231027D01*
X401000Y231160D01*
X400792Y231347D01*
X400750Y231533D01*
X400833Y231720D01*
X401042Y231853D01*
G01X408050Y236583D02*
X404950D01*
Y237542D01*
X405105Y237848D01*
X405312Y238040D01*
X405725Y238117D01*
X406138Y238040D01*
X406397Y237810D01*
X406552Y237542D01*
Y236583D01*
G01Y237542D02*
X408050Y238117D01*
G01X405467Y239722D02*
X405157Y239952D01*
X405002Y240220D01*
X404950Y240527D01*
X405053Y240910D01*
X405312Y241178D01*
X405622Y241255D01*
X405932Y241217D01*
X406190Y241063D01*
X406707Y240297D01*
X407068Y239952D01*
X407585Y239722D01*
X408050Y239645D01*
Y241255D01*
G01X407688Y242898D02*
X407947Y243167D01*
X408050Y243473D01*
X407947Y243780D01*
X407637Y244048D01*
X407172Y244240D01*
X406707Y244317D01*
X406138D01*
X405673Y244240D01*
X405260Y244048D01*
X405053Y243818D01*
X404950Y243550D01*
X405053Y243243D01*
X405260Y243013D01*
X405570Y242860D01*
X405983Y242783D01*
X406345Y242860D01*
X406707Y243052D01*
X406913Y243282D01*
X406965Y243550D01*
X406862Y243857D01*
X406603Y244087D01*
X406138Y244317D01*
G01X405467Y245922D02*
X405157Y246152D01*
X405002Y246420D01*
X404950Y246727D01*
X405053Y247110D01*
X405312Y247378D01*
X405622Y247455D01*
X405932Y247417D01*
X406190Y247263D01*
X406707Y246497D01*
X407068Y246152D01*
X407585Y245922D01*
X408050Y245845D01*
Y247455D01*
G01X402550Y237083D02*
X399450D01*
Y238042D01*
X399605Y238348D01*
X399812Y238540D01*
X400225Y238617D01*
X400638Y238540D01*
X400897Y238310D01*
X401052Y238042D01*
Y237083D01*
G01Y238042D02*
X402550Y238617D01*
G01Y240950D02*
X399450D01*
X400070Y240490D01*
G01X402550D02*
Y241410D01*
G01Y243973D02*
X401878Y244050D01*
X401310Y244165D01*
X400793Y244318D01*
X400225Y244510D01*
X399450Y244817D01*
Y243283D01*
G01Y247150D02*
X399553Y246843D01*
X399812Y246613D01*
X400122Y246460D01*
X400535Y246345D01*
X401000Y246307D01*
X401465Y246345D01*
X401878Y246460D01*
X402188Y246613D01*
X402447Y246843D01*
X402550Y247150D01*
X402447Y247457D01*
X402188Y247687D01*
X401878Y247840D01*
X401465Y247955D01*
X401000Y247993D01*
X400535Y247955D01*
X400122Y247840D01*
X399812Y247687D01*
X399553Y247457D01*
X399450Y247150D01*
G01X414050Y237083D02*
X410950D01*
Y238042D01*
X411105Y238348D01*
X411312Y238540D01*
X411725Y238617D01*
X412138Y238540D01*
X412397Y238310D01*
X412552Y238042D01*
Y237083D01*
G01Y238042D02*
X414050Y238617D01*
G01X413430Y240107D02*
X413792Y240337D01*
X413998Y240643D01*
X414050Y240988D01*
X413998Y241295D01*
X413740Y241602D01*
X413430Y241793D01*
X413120Y241832D01*
X412758Y241755D01*
X412500Y241487D01*
X412397Y241218D01*
Y240873D01*
G01Y241218D02*
X412242Y241448D01*
X411983Y241640D01*
X411673Y241717D01*
X411363Y241640D01*
X411105Y241448D01*
X410950Y241103D01*
X411002Y240758D01*
X411208Y240413D01*
G01X410950Y244050D02*
X411053Y243743D01*
X411312Y243513D01*
X411622Y243360D01*
X412035Y243245D01*
X412500Y243207D01*
X412965Y243245D01*
X413378Y243360D01*
X413688Y243513D01*
X413947Y243743D01*
X414050Y244050D01*
X413947Y244357D01*
X413688Y244587D01*
X413378Y244740D01*
X412965Y244855D01*
X412500Y244893D01*
X412035Y244855D01*
X411622Y244740D01*
X411312Y244587D01*
X411053Y244357D01*
X410950Y244050D01*
G01X414050Y247150D02*
X413998Y247418D01*
X413843Y247725D01*
X413585Y247917D01*
X413223Y247993D01*
X412862Y247917D01*
X412552Y247687D01*
X412397Y247342D01*
Y246958D01*
X412293Y246728D01*
X412035Y246537D01*
X411673Y246460D01*
X411312Y246575D01*
X411053Y246843D01*
X410950Y247150D01*
X411053Y247457D01*
X411312Y247725D01*
X411673Y247840D01*
X412035Y247763D01*
X412293Y247572D01*
X412397Y247342D01*
Y246958D01*
X412552Y246613D01*
X412862Y246383D01*
X413223Y246307D01*
X413585Y246383D01*
X413843Y246575D01*
X413998Y246882D01*
X414050Y247150D01*
G01X400583Y266950D02*
Y270050D01*
X401542D01*
X401848Y269895D01*
X402040Y269688D01*
X402117Y269275D01*
X402040Y268862D01*
X401810Y268603D01*
X401542Y268448D01*
X400583D01*
G01X401542D02*
X402117Y266950D01*
G01X404450D02*
Y270050D01*
X403990Y269430D01*
G01Y266950D02*
X404910D01*
G01X407473D02*
X407550Y267622D01*
X407665Y268190D01*
X407818Y268707D01*
X408010Y269275D01*
X408317Y270050D01*
X406783D01*
G01X410650Y266950D02*
X410918Y267002D01*
X411225Y267157D01*
X411417Y267415D01*
X411493Y267777D01*
X411417Y268138D01*
X411187Y268448D01*
X410842Y268603D01*
X410458D01*
X410228Y268707D01*
X410037Y268965D01*
X409960Y269327D01*
X410075Y269688D01*
X410343Y269947D01*
X410650Y270050D01*
X410957Y269947D01*
X411225Y269688D01*
X411340Y269327D01*
X411263Y268965D01*
X411072Y268707D01*
X410842Y268603D01*
X410458D01*
X410113Y268448D01*
X409883Y268138D01*
X409807Y267777D01*
X409883Y267415D01*
X410075Y267157D01*
X410382Y267002D01*
X410650Y266950D01*
G01X402193Y278292D02*
X401963Y278447D01*
X401695Y278550D01*
X401388D01*
X401043Y278395D01*
X400775Y278137D01*
X400583Y277827D01*
X400430Y277310D01*
X400392Y276845D01*
X400468Y276380D01*
X400583Y276070D01*
X400813Y275760D01*
X401082Y275553D01*
X401350Y275450D01*
X401618D01*
X401887Y275553D01*
X402117Y275708D01*
X402308Y275915D01*
G01X404450Y275450D02*
Y278550D01*
X403990Y277930D01*
G01Y275450D02*
X404910D01*
G01X406898Y275812D02*
X407167Y275553D01*
X407473Y275450D01*
X407780Y275553D01*
X408048Y275863D01*
X408240Y276328D01*
X408317Y276793D01*
Y277362D01*
X408240Y277827D01*
X408048Y278240D01*
X407818Y278447D01*
X407550Y278550D01*
X407243Y278447D01*
X407013Y278240D01*
X406860Y277930D01*
X406783Y277517D01*
X406860Y277155D01*
X407052Y276793D01*
X407282Y276587D01*
X407550Y276535D01*
X407857Y276638D01*
X408087Y276897D01*
X408317Y277362D01*
G01X409922Y278033D02*
X410152Y278343D01*
X410420Y278498D01*
X410727Y278550D01*
X411110Y278447D01*
X411378Y278188D01*
X411455Y277878D01*
X411417Y277568D01*
X411263Y277310D01*
X410497Y276793D01*
X410152Y276432D01*
X409922Y275915D01*
X409845Y275450D01*
X411455D01*
G01X400583Y271450D02*
Y274550D01*
X401542D01*
X401848Y274395D01*
X402040Y274188D01*
X402117Y273775D01*
X402040Y273362D01*
X401810Y273103D01*
X401542Y272948D01*
X400583D01*
G01X401542D02*
X402117Y271450D01*
G01X404450D02*
Y274550D01*
X403990Y273930D01*
G01Y271450D02*
X404910D01*
G01X407550D02*
X407818Y271502D01*
X408125Y271657D01*
X408317Y271915D01*
X408393Y272277D01*
X408317Y272638D01*
X408087Y272948D01*
X407742Y273103D01*
X407358D01*
X407128Y273207D01*
X406937Y273465D01*
X406860Y273827D01*
X406975Y274188D01*
X407243Y274447D01*
X407550Y274550D01*
X407857Y274447D01*
X408125Y274188D01*
X408240Y273827D01*
X408163Y273465D01*
X407972Y273207D01*
X407742Y273103D01*
X407358D01*
X407013Y272948D01*
X406783Y272638D01*
X406707Y272277D01*
X406783Y271915D01*
X406975Y271657D01*
X407282Y271502D01*
X407550Y271450D01*
G01X410650D02*
Y274550D01*
X410190Y273930D01*
G01Y271450D02*
X411110D01*
G01X396523Y282533D02*
X396781Y282763D01*
X396936Y283031D01*
X396988Y283376D01*
X396885Y283721D01*
X396678Y283989D01*
X396316Y284181D01*
X395903Y284219D01*
X395490Y284143D01*
X395231Y283951D01*
X395025Y283683D01*
X394973Y283414D01*
X395025Y283146D01*
X395231Y282801D01*
X393888Y282916D01*
Y283951D01*
G01X399950Y290557D02*
X402172D01*
X402637Y290710D01*
X402947Y291017D01*
X403050Y291400D01*
X402947Y291783D01*
X402637Y292090D01*
X402172Y292243D01*
X399950D01*
G01X400467Y293772D02*
X400157Y294002D01*
X400002Y294270D01*
X399950Y294577D01*
X400053Y294960D01*
X400312Y295228D01*
X400622Y295305D01*
X400932Y295267D01*
X401190Y295113D01*
X401707Y294347D01*
X402068Y294002D01*
X402585Y293772D01*
X403050Y293695D01*
Y295305D01*
G01X399950Y297600D02*
X400053Y297293D01*
X400312Y297063D01*
X400622Y296910D01*
X401035Y296795D01*
X401500Y296757D01*
X401965Y296795D01*
X402378Y296910D01*
X402688Y297063D01*
X402947Y297293D01*
X403050Y297600D01*
X402947Y297907D01*
X402688Y298137D01*
X402378Y298290D01*
X401965Y298405D01*
X401500Y298443D01*
X401035Y298405D01*
X400622Y298290D01*
X400312Y298137D01*
X400053Y297907D01*
X399950Y297600D01*
G01X399272Y303242D02*
X399540Y303603D01*
X399770Y303810D01*
X400077Y303913D01*
X400345Y303810D01*
X400537Y303603D01*
X400690Y303293D01*
X400728Y302932D01*
X400690Y302622D01*
X400537Y302312D01*
X400307Y302053D01*
X400038Y301950D01*
X399732Y302053D01*
X399463Y302363D01*
X399310Y302828D01*
X399272Y303345D01*
X399348Y304017D01*
X399463Y304378D01*
X399655Y304740D01*
X399923Y304998D01*
X400192Y305050D01*
X400460Y304947D01*
X400652Y304688D01*
G01X400708Y311193D02*
X400553Y310963D01*
X400450Y310695D01*
Y310388D01*
X400605Y310043D01*
X400863Y309775D01*
X401173Y309583D01*
X401690Y309430D01*
X402155Y309392D01*
X402620Y309468D01*
X402930Y309583D01*
X403240Y309813D01*
X403447Y310082D01*
X403550Y310350D01*
Y310618D01*
X403447Y310887D01*
X403292Y311117D01*
X403085Y311308D01*
G01X403550Y313450D02*
X400450D01*
X401070Y312990D01*
G01X403550D02*
Y313910D01*
G01Y316550D02*
X403498Y316818D01*
X403343Y317125D01*
X403085Y317317D01*
X402723Y317393D01*
X402362Y317317D01*
X402052Y317087D01*
X401897Y316742D01*
Y316358D01*
X401793Y316128D01*
X401535Y315937D01*
X401173Y315860D01*
X400812Y315975D01*
X400553Y316243D01*
X400450Y316550D01*
X400553Y316857D01*
X400812Y317125D01*
X401173Y317240D01*
X401535Y317163D01*
X401793Y316972D01*
X401897Y316742D01*
Y316358D01*
X402052Y316013D01*
X402362Y315783D01*
X402723Y315707D01*
X403085Y315783D01*
X403343Y315975D01*
X403498Y316282D01*
X403550Y316550D01*
G01Y320110D02*
X400450D01*
X402672Y318692D01*
Y320608D01*
G01X404708Y311193D02*
X404553Y310963D01*
X404450Y310695D01*
Y310388D01*
X404605Y310043D01*
X404863Y309775D01*
X405173Y309583D01*
X405690Y309430D01*
X406155Y309392D01*
X406620Y309468D01*
X406930Y309583D01*
X407240Y309813D01*
X407447Y310082D01*
X407550Y310350D01*
Y310618D01*
X407447Y310887D01*
X407292Y311117D01*
X407085Y311308D01*
G01X407550Y313450D02*
X404450D01*
X405070Y312990D01*
G01X407550D02*
Y313910D01*
G01X407188Y315898D02*
X407447Y316167D01*
X407550Y316473D01*
X407447Y316780D01*
X407137Y317048D01*
X406672Y317240D01*
X406207Y317317D01*
X405638D01*
X405173Y317240D01*
X404760Y317048D01*
X404553Y316818D01*
X404450Y316550D01*
X404553Y316243D01*
X404760Y316013D01*
X405070Y315860D01*
X405483Y315783D01*
X405845Y315860D01*
X406207Y316052D01*
X406413Y316282D01*
X406465Y316550D01*
X406362Y316857D01*
X406103Y317087D01*
X405638Y317317D01*
G01X404450Y319650D02*
X404553Y319343D01*
X404812Y319113D01*
X405122Y318960D01*
X405535Y318845D01*
X406000Y318807D01*
X406465Y318845D01*
X406878Y318960D01*
X407188Y319113D01*
X407447Y319343D01*
X407550Y319650D01*
X407447Y319957D01*
X407188Y320187D01*
X406878Y320340D01*
X406465Y320455D01*
X406000Y320493D01*
X405535Y320455D01*
X405122Y320340D01*
X404812Y320187D01*
X404553Y319957D01*
X404450Y319650D01*
G01X410900Y305600D02*
X411087Y305642D01*
X411300Y305767D01*
X411433Y305975D01*
X411487Y306267D01*
X411433Y306558D01*
X411273Y306808D01*
X411033Y306933D01*
X410767D01*
X410607Y307017D01*
X410473Y307225D01*
X410420Y307517D01*
X410500Y307808D01*
X410687Y308017D01*
X410900Y308100D01*
X411113Y308017D01*
X411300Y307808D01*
X411380Y307517D01*
X411327Y307225D01*
X411193Y307017D01*
X411033Y306933D01*
X410767D01*
X410527Y306808D01*
X410367Y306558D01*
X410313Y306267D01*
X410367Y305975D01*
X410500Y305767D01*
X410713Y305642D01*
X410900Y305600D01*
G01X406350Y334050D02*
Y330950D01*
G01X405468Y334050D02*
X407232D01*
G01X408683Y330950D02*
Y334050D01*
X409603D01*
X409910Y333895D01*
X410140Y333533D01*
X410217Y333120D01*
X410140Y332707D01*
X409948Y332397D01*
X409603Y332242D01*
X408683D01*
G01X412550Y330950D02*
Y334050D01*
X412090Y333430D01*
G01Y330950D02*
X413010D01*
G01X414807Y331570D02*
X415037Y331208D01*
X415343Y331002D01*
X415688Y330950D01*
X415995Y331002D01*
X416302Y331260D01*
X416493Y331570D01*
X416532Y331880D01*
X416455Y332242D01*
X416187Y332500D01*
X415918Y332603D01*
X415573D01*
G01X415918D02*
X416148Y332758D01*
X416340Y333017D01*
X416417Y333327D01*
X416340Y333637D01*
X416148Y333895D01*
X415803Y334050D01*
X415458Y333998D01*
X415113Y333792D01*
G01X403993Y335992D02*
X404180Y336283D01*
X404340Y336450D01*
X404553Y336533D01*
X404740Y336450D01*
X404873Y336283D01*
X404980Y336033D01*
X405007Y335742D01*
X404980Y335492D01*
X404873Y335242D01*
X404713Y335033D01*
X404527Y334950D01*
X404313Y335033D01*
X404127Y335283D01*
X404020Y335658D01*
X403993Y336075D01*
X404047Y336617D01*
X404127Y336908D01*
X404260Y337200D01*
X404447Y337408D01*
X404633Y337450D01*
X404820Y337367D01*
X404953Y337158D01*
G01X397000Y355950D02*
X397268Y356002D01*
X397575Y356157D01*
X397767Y356415D01*
X397843Y356777D01*
X397767Y357138D01*
X397537Y357448D01*
X397192Y357603D01*
X396808D01*
X396578Y357707D01*
X396387Y357965D01*
X396310Y358327D01*
X396425Y358688D01*
X396693Y358947D01*
X397000Y359050D01*
X397307Y358947D01*
X397575Y358688D01*
X397690Y358327D01*
X397613Y357965D01*
X397422Y357707D01*
X397192Y357603D01*
X396808D01*
X396463Y357448D01*
X396233Y357138D01*
X396157Y356777D01*
X396233Y356415D01*
X396425Y356157D01*
X396732Y356002D01*
X397000Y355950D01*
G01X406393Y385333D02*
X406553Y385583D01*
X406740Y385708D01*
X406953Y385750D01*
X407220Y385667D01*
X407407Y385458D01*
X407460Y385208D01*
X407433Y384958D01*
X407327Y384750D01*
X406793Y384333D01*
X406553Y384042D01*
X406393Y383625D01*
X406340Y383250D01*
X407460D01*
G01X408593Y385333D02*
X408753Y385583D01*
X408940Y385708D01*
X409153Y385750D01*
X409420Y385667D01*
X409607Y385458D01*
X409660Y385208D01*
X409633Y384958D01*
X409527Y384750D01*
X408993Y384333D01*
X408753Y384042D01*
X408593Y383625D01*
X408540Y383250D01*
X409660D01*
G01X410557Y382050D02*
Y379828D01*
X410710Y379363D01*
X411017Y379053D01*
X411400Y378950D01*
X411783Y379053D01*
X412090Y379363D01*
X412243Y379828D01*
Y382050D01*
G01X413657Y379570D02*
X413887Y379208D01*
X414193Y379002D01*
X414538Y378950D01*
X414845Y379002D01*
X415152Y379260D01*
X415343Y379570D01*
X415382Y379880D01*
X415305Y380242D01*
X415037Y380500D01*
X414768Y380603D01*
X414423D01*
G01X414768D02*
X414998Y380758D01*
X415190Y381017D01*
X415267Y381327D01*
X415190Y381637D01*
X414998Y381895D01*
X414653Y382050D01*
X414308Y381998D01*
X413963Y381792D01*
G01X417600Y382050D02*
X417293Y381947D01*
X417063Y381688D01*
X416910Y381378D01*
X416795Y380965D01*
X416757Y380500D01*
X416795Y380035D01*
X416910Y379622D01*
X417063Y379312D01*
X417293Y379053D01*
X417600Y378950D01*
X417907Y379053D01*
X418137Y379312D01*
X418290Y379622D01*
X418405Y380035D01*
X418443Y380500D01*
X418405Y380965D01*
X418290Y381378D01*
X418137Y381688D01*
X417907Y381947D01*
X417600Y382050D01*
G01X396893Y394833D02*
X397053Y395083D01*
X397240Y395208D01*
X397453Y395250D01*
X397720Y395167D01*
X397907Y394958D01*
X397960Y394708D01*
X397933Y394458D01*
X397827Y394250D01*
X397293Y393833D01*
X397053Y393542D01*
X396893Y393125D01*
X396840Y392750D01*
X397960D01*
G01X399600D02*
Y395250D01*
X399280Y394750D01*
G01Y392750D02*
X399920D01*
G01X396900Y403750D02*
Y406250D01*
X396580Y405750D01*
G01Y403750D02*
X397220D01*
G01X398513Y404125D02*
X398673Y403917D01*
X398860Y403792D01*
X399100Y403750D01*
X399340Y403833D01*
X399527Y404000D01*
X399660Y404292D01*
X399687Y404625D01*
X399633Y404958D01*
X399500Y405167D01*
X399313Y405333D01*
X399127Y405375D01*
X398940Y405333D01*
X398700Y405167D01*
X398780Y406250D01*
X399500D01*
G01X405400Y414250D02*
Y416750D01*
X405080Y416250D01*
G01Y414250D02*
X405720D01*
G01X407920D02*
Y416750D01*
X406933Y414958D01*
X408267D01*
G01X425083Y61950D02*
Y65050D01*
X426042D01*
X426348Y64895D01*
X426540Y64688D01*
X426617Y64275D01*
X426540Y63862D01*
X426310Y63603D01*
X426042Y63448D01*
X425083D01*
G01X426042D02*
X426617Y61950D01*
G01X428222Y64533D02*
X428452Y64843D01*
X428720Y64998D01*
X429027Y65050D01*
X429410Y64947D01*
X429678Y64688D01*
X429755Y64378D01*
X429717Y64068D01*
X429563Y63810D01*
X428797Y63293D01*
X428452Y62932D01*
X428222Y62415D01*
X428145Y61950D01*
X429755D01*
G01X431207Y62570D02*
X431437Y62208D01*
X431743Y62002D01*
X432088Y61950D01*
X432395Y62002D01*
X432702Y62260D01*
X432893Y62570D01*
X432932Y62880D01*
X432855Y63242D01*
X432587Y63500D01*
X432318Y63603D01*
X431973D01*
G01X432318D02*
X432548Y63758D01*
X432740Y64017D01*
X432817Y64327D01*
X432740Y64637D01*
X432548Y64895D01*
X432203Y65050D01*
X431858Y64998D01*
X431513Y64792D01*
G01X434498Y62312D02*
X434767Y62053D01*
X435073Y61950D01*
X435380Y62053D01*
X435648Y62363D01*
X435840Y62828D01*
X435917Y63293D01*
Y63862D01*
X435840Y64327D01*
X435648Y64740D01*
X435418Y64947D01*
X435150Y65050D01*
X434843Y64947D01*
X434613Y64740D01*
X434460Y64430D01*
X434383Y64017D01*
X434460Y63655D01*
X434652Y63293D01*
X434882Y63087D01*
X435150Y63035D01*
X435457Y63138D01*
X435687Y63397D01*
X435917Y63862D01*
G01X418950Y65350D02*
X422050D01*
G01X418950Y64468D02*
Y66232D01*
G01X422050Y67683D02*
X418950D01*
Y68603D01*
X419105Y68910D01*
X419467Y69140D01*
X419880Y69217D01*
X420293Y69140D01*
X420603Y68948D01*
X420758Y68603D01*
Y67683D01*
G01X422050Y72010D02*
X418950D01*
X421172Y70592D01*
Y72508D01*
G01X421688Y73998D02*
X421947Y74267D01*
X422050Y74573D01*
X421947Y74880D01*
X421637Y75148D01*
X421172Y75340D01*
X420707Y75417D01*
X420138D01*
X419673Y75340D01*
X419260Y75148D01*
X419053Y74918D01*
X418950Y74650D01*
X419053Y74343D01*
X419260Y74113D01*
X419570Y73960D01*
X419983Y73883D01*
X420345Y73960D01*
X420707Y74152D01*
X420913Y74382D01*
X420965Y74650D01*
X420862Y74957D01*
X420603Y75187D01*
X420138Y75417D01*
G01X424000Y78450D02*
Y81550D01*
X423540Y80930D01*
G01Y78450D02*
X424460D01*
G01X420550Y95083D02*
X417450D01*
Y96042D01*
X417605Y96348D01*
X417812Y96540D01*
X418225Y96617D01*
X418638Y96540D01*
X418897Y96310D01*
X419052Y96042D01*
Y95083D01*
G01Y96042D02*
X420550Y96617D01*
G01X417967Y98222D02*
X417657Y98452D01*
X417502Y98720D01*
X417450Y99027D01*
X417553Y99410D01*
X417812Y99678D01*
X418122Y99755D01*
X418432Y99717D01*
X418690Y99563D01*
X419207Y98797D01*
X419568Y98452D01*
X420085Y98222D01*
X420550Y98145D01*
Y99755D01*
G01X419930Y101207D02*
X420292Y101437D01*
X420498Y101743D01*
X420550Y102088D01*
X420498Y102395D01*
X420240Y102702D01*
X419930Y102893D01*
X419620Y102932D01*
X419258Y102855D01*
X419000Y102587D01*
X418897Y102318D01*
Y101973D01*
G01Y102318D02*
X418742Y102548D01*
X418483Y102740D01*
X418173Y102817D01*
X417863Y102740D01*
X417605Y102548D01*
X417450Y102203D01*
X417502Y101858D01*
X417708Y101513D01*
G01X420085Y104307D02*
X420343Y104537D01*
X420498Y104805D01*
X420550Y105150D01*
X420447Y105495D01*
X420240Y105763D01*
X419878Y105955D01*
X419465Y105993D01*
X419052Y105917D01*
X418793Y105725D01*
X418587Y105457D01*
X418535Y105188D01*
X418587Y104920D01*
X418793Y104575D01*
X417450Y104690D01*
Y105725D01*
G01X428050Y103583D02*
X424950D01*
Y104542D01*
X425105Y104848D01*
X425312Y105040D01*
X425725Y105117D01*
X426138Y105040D01*
X426397Y104810D01*
X426552Y104542D01*
Y103583D01*
G01Y104542D02*
X428050Y105117D01*
G01X427430Y106607D02*
X427792Y106837D01*
X427998Y107143D01*
X428050Y107488D01*
X427998Y107795D01*
X427740Y108102D01*
X427430Y108293D01*
X427120Y108332D01*
X426758Y108255D01*
X426500Y107987D01*
X426397Y107718D01*
Y107373D01*
G01Y107718D02*
X426242Y107948D01*
X425983Y108140D01*
X425673Y108217D01*
X425363Y108140D01*
X425105Y107948D01*
X424950Y107603D01*
X425002Y107258D01*
X425208Y106913D01*
G01X426758Y109822D02*
X426397Y110090D01*
X426190Y110320D01*
X426087Y110627D01*
X426190Y110895D01*
X426397Y111087D01*
X426707Y111240D01*
X427068Y111278D01*
X427378Y111240D01*
X427688Y111087D01*
X427947Y110857D01*
X428050Y110588D01*
X427947Y110282D01*
X427637Y110013D01*
X427172Y109860D01*
X426655Y109822D01*
X425983Y109898D01*
X425622Y110013D01*
X425260Y110205D01*
X425002Y110473D01*
X424950Y110742D01*
X425053Y111010D01*
X425312Y111202D01*
G01X424950Y113650D02*
X425053Y113343D01*
X425312Y113113D01*
X425622Y112960D01*
X426035Y112845D01*
X426500Y112807D01*
X426965Y112845D01*
X427378Y112960D01*
X427688Y113113D01*
X427947Y113343D01*
X428050Y113650D01*
X427947Y113957D01*
X427688Y114187D01*
X427378Y114340D01*
X426965Y114455D01*
X426500Y114493D01*
X426035Y114455D01*
X425622Y114340D01*
X425312Y114187D01*
X425053Y113957D01*
X424950Y113650D01*
G01X421250Y112100D02*
X423750D01*
G01X421250Y111487D02*
Y112713D01*
G01X423750Y113767D02*
X421250D01*
Y114407D01*
X421375Y114620D01*
X421667Y114780D01*
X422000Y114833D01*
X422333Y114780D01*
X422583Y114647D01*
X422708Y114407D01*
Y113767D01*
G01X421667Y115993D02*
X421417Y116153D01*
X421292Y116340D01*
X421250Y116553D01*
X421333Y116820D01*
X421542Y117007D01*
X421792Y117060D01*
X422042Y117033D01*
X422250Y116927D01*
X422667Y116393D01*
X422958Y116153D01*
X423375Y115993D01*
X423750Y115940D01*
Y117060D01*
G01X421250Y118700D02*
X421333Y118487D01*
X421542Y118327D01*
X421792Y118220D01*
X422125Y118140D01*
X422500Y118113D01*
X422875Y118140D01*
X423208Y118220D01*
X423458Y118327D01*
X423667Y118487D01*
X423750Y118700D01*
X423667Y118913D01*
X423458Y119073D01*
X423208Y119180D01*
X422875Y119260D01*
X422500Y119287D01*
X422125Y119260D01*
X421792Y119180D01*
X421542Y119073D01*
X421333Y118913D01*
X421250Y118700D01*
G01Y120900D02*
X421333Y120687D01*
X421542Y120527D01*
X421792Y120420D01*
X422125Y120340D01*
X422500Y120313D01*
X422875Y120340D01*
X423208Y120420D01*
X423458Y120527D01*
X423667Y120687D01*
X423750Y120900D01*
X423667Y121113D01*
X423458Y121273D01*
X423208Y121380D01*
X422875Y121460D01*
X422500Y121487D01*
X422125Y121460D01*
X421792Y121380D01*
X421542Y121273D01*
X421333Y121113D01*
X421250Y120900D01*
G01X413750Y111600D02*
X416250D01*
G01X413750Y110987D02*
Y112213D01*
G01X416250Y113267D02*
X413750D01*
Y113907D01*
X413875Y114120D01*
X414167Y114280D01*
X414500Y114333D01*
X414833Y114280D01*
X415083Y114147D01*
X415208Y113907D01*
Y113267D01*
G01X416250Y116000D02*
X413750D01*
X414250Y115680D01*
G01X416250D02*
Y116320D01*
G01X415958Y117747D02*
X416167Y117933D01*
X416250Y118147D01*
X416167Y118360D01*
X415917Y118547D01*
X415542Y118680D01*
X415167Y118733D01*
X414708D01*
X414333Y118680D01*
X414000Y118547D01*
X413833Y118387D01*
X413750Y118200D01*
X413833Y117987D01*
X414000Y117827D01*
X414250Y117720D01*
X414583Y117667D01*
X414875Y117720D01*
X415167Y117853D01*
X415333Y118013D01*
X415375Y118200D01*
X415292Y118413D01*
X415083Y118573D01*
X414708Y118733D01*
G01X415208Y119893D02*
X414917Y120080D01*
X414750Y120240D01*
X414667Y120453D01*
X414750Y120640D01*
X414917Y120773D01*
X415167Y120880D01*
X415458Y120907D01*
X415708Y120880D01*
X415958Y120773D01*
X416167Y120613D01*
X416250Y120427D01*
X416167Y120213D01*
X415917Y120027D01*
X415542Y119920D01*
X415125Y119893D01*
X414583Y119947D01*
X414292Y120027D01*
X414000Y120160D01*
X413792Y120347D01*
X413750Y120533D01*
X413833Y120720D01*
X414042Y120853D01*
G01X416283Y125410D02*
Y125943D01*
X417033D01*
X417283Y125783D01*
X417450Y125597D01*
X417533Y125330D01*
X417450Y125063D01*
X417283Y124877D01*
X417033Y124717D01*
X416741Y124610D01*
X416408Y124557D01*
X416116D01*
X415866Y124610D01*
X415575Y124717D01*
X415325Y124877D01*
X415158Y125037D01*
X415033Y125250D01*
Y125437D01*
X415116Y125650D01*
X415283Y125810D01*
G01X424533Y124717D02*
X424783Y124850D01*
X424950Y125010D01*
X425033Y125197D01*
X424950Y125410D01*
X424783Y125570D01*
X424533Y125730D01*
X424200Y125783D01*
X422533D01*
G01X428033Y122163D02*
X425533D01*
G01Y123177D02*
X427075Y122163D01*
G01X428033Y123337D02*
X426366Y122617D01*
G01X421533Y122190D02*
X419033D01*
G01Y123310D02*
X421533D01*
G01X420283D02*
Y122190D01*
G01X427100Y120250D02*
Y117750D01*
G01X426487Y120250D02*
X427713D01*
G01X428767Y117750D02*
Y120250D01*
X429407D01*
X429620Y120125D01*
X429780Y119833D01*
X429833Y119500D01*
X429780Y119167D01*
X429647Y118917D01*
X429407Y118792D01*
X428767D01*
G01X430993Y119833D02*
X431153Y120083D01*
X431340Y120208D01*
X431553Y120250D01*
X431820Y120167D01*
X432007Y119958D01*
X432060Y119708D01*
X432033Y119458D01*
X431927Y119250D01*
X431393Y118833D01*
X431153Y118542D01*
X430993Y118125D01*
X430940Y117750D01*
X432060D01*
G01X433700Y120250D02*
X433487Y120167D01*
X433327Y119958D01*
X433220Y119708D01*
X433140Y119375D01*
X433113Y119000D01*
X433140Y118625D01*
X433220Y118292D01*
X433327Y118042D01*
X433487Y117833D01*
X433700Y117750D01*
X433913Y117833D01*
X434073Y118042D01*
X434180Y118292D01*
X434260Y118625D01*
X434287Y119000D01*
X434260Y119375D01*
X434180Y119708D01*
X434073Y119958D01*
X433913Y120167D01*
X433700Y120250D01*
G01X436220Y117750D02*
Y120250D01*
X435233Y118458D01*
X436567D01*
G01X428250Y222100D02*
X430750D01*
G01X428250Y221487D02*
Y222713D01*
G01X430750Y223767D02*
X428250D01*
Y224407D01*
X428375Y224620D01*
X428667Y224780D01*
X429000Y224833D01*
X429333Y224780D01*
X429583Y224647D01*
X429708Y224407D01*
Y223767D01*
G01X430750Y226500D02*
X428250D01*
X428750Y226180D01*
G01X430750D02*
Y226820D01*
G01Y228700D02*
X430708Y228887D01*
X430583Y229100D01*
X430375Y229233D01*
X430083Y229287D01*
X429792Y229233D01*
X429542Y229073D01*
X429417Y228833D01*
Y228567D01*
X429333Y228407D01*
X429125Y228273D01*
X428833Y228220D01*
X428542Y228300D01*
X428333Y228487D01*
X428250Y228700D01*
X428333Y228913D01*
X428542Y229100D01*
X428833Y229180D01*
X429125Y229127D01*
X429333Y228993D01*
X429417Y228833D01*
Y228567D01*
X429542Y228327D01*
X429792Y228167D01*
X430083Y228113D01*
X430375Y228167D01*
X430583Y228300D01*
X430708Y228513D01*
X430750Y228700D01*
G01X430250Y230313D02*
X430542Y230473D01*
X430708Y230687D01*
X430750Y230927D01*
X430708Y231140D01*
X430500Y231353D01*
X430250Y231487D01*
X430000Y231513D01*
X429708Y231460D01*
X429500Y231273D01*
X429417Y231087D01*
Y230847D01*
G01Y231087D02*
X429292Y231247D01*
X429083Y231380D01*
X428833Y231433D01*
X428583Y231380D01*
X428375Y231247D01*
X428250Y231007D01*
X428292Y230767D01*
X428458Y230527D01*
G01X431050Y247583D02*
X427950D01*
Y248542D01*
X428105Y248848D01*
X428312Y249040D01*
X428725Y249117D01*
X429138Y249040D01*
X429397Y248810D01*
X429552Y248542D01*
Y247583D01*
G01Y248542D02*
X431050Y249117D01*
G01X430430Y250607D02*
X430792Y250837D01*
X430998Y251143D01*
X431050Y251488D01*
X430998Y251795D01*
X430740Y252102D01*
X430430Y252293D01*
X430120Y252332D01*
X429758Y252255D01*
X429500Y251987D01*
X429397Y251718D01*
Y251373D01*
G01Y251718D02*
X429242Y251948D01*
X428983Y252140D01*
X428673Y252217D01*
X428363Y252140D01*
X428105Y251948D01*
X427950Y251603D01*
X428002Y251258D01*
X428208Y250913D01*
G01X428467Y253822D02*
X428157Y254052D01*
X428002Y254320D01*
X427950Y254627D01*
X428053Y255010D01*
X428312Y255278D01*
X428622Y255355D01*
X428932Y255317D01*
X429190Y255163D01*
X429707Y254397D01*
X430068Y254052D01*
X430585Y253822D01*
X431050Y253745D01*
Y255355D01*
G01X430585Y256807D02*
X430843Y257037D01*
X430998Y257305D01*
X431050Y257650D01*
X430947Y257995D01*
X430740Y258263D01*
X430378Y258455D01*
X429965Y258493D01*
X429552Y258417D01*
X429293Y258225D01*
X429087Y257957D01*
X429035Y257688D01*
X429087Y257420D01*
X429293Y257075D01*
X427950Y257190D01*
Y258225D01*
G01X427050Y247583D02*
X423950D01*
Y248542D01*
X424105Y248848D01*
X424312Y249040D01*
X424725Y249117D01*
X425138Y249040D01*
X425397Y248810D01*
X425552Y248542D01*
Y247583D01*
G01Y248542D02*
X427050Y249117D01*
G01X426430Y250607D02*
X426792Y250837D01*
X426998Y251143D01*
X427050Y251488D01*
X426998Y251795D01*
X426740Y252102D01*
X426430Y252293D01*
X426120Y252332D01*
X425758Y252255D01*
X425500Y251987D01*
X425397Y251718D01*
Y251373D01*
G01Y251718D02*
X425242Y251948D01*
X424983Y252140D01*
X424673Y252217D01*
X424363Y252140D01*
X424105Y251948D01*
X423950Y251603D01*
X424002Y251258D01*
X424208Y250913D01*
G01X424467Y253822D02*
X424157Y254052D01*
X424002Y254320D01*
X423950Y254627D01*
X424053Y255010D01*
X424312Y255278D01*
X424622Y255355D01*
X424932Y255317D01*
X425190Y255163D01*
X425707Y254397D01*
X426068Y254052D01*
X426585Y253822D01*
X427050Y253745D01*
Y255355D01*
G01Y257573D02*
X426378Y257650D01*
X425810Y257765D01*
X425293Y257918D01*
X424725Y258110D01*
X423950Y258417D01*
Y256883D01*
G01X414293Y266492D02*
X414063Y266647D01*
X413795Y266750D01*
X413488D01*
X413143Y266595D01*
X412875Y266337D01*
X412683Y266027D01*
X412530Y265510D01*
X412492Y265045D01*
X412568Y264580D01*
X412683Y264270D01*
X412913Y263960D01*
X413182Y263753D01*
X413450Y263650D01*
X413718D01*
X413987Y263753D01*
X414217Y263908D01*
X414408Y264115D01*
G01X415822Y266233D02*
X416052Y266543D01*
X416320Y266698D01*
X416627Y266750D01*
X417010Y266647D01*
X417278Y266388D01*
X417355Y266078D01*
X417317Y265768D01*
X417163Y265510D01*
X416397Y264993D01*
X416052Y264632D01*
X415822Y264115D01*
X415745Y263650D01*
X417355D01*
G01X418807Y264270D02*
X419037Y263908D01*
X419343Y263702D01*
X419688Y263650D01*
X419995Y263702D01*
X420302Y263960D01*
X420493Y264270D01*
X420532Y264580D01*
X420455Y264942D01*
X420187Y265200D01*
X419918Y265303D01*
X419573D01*
G01X419918D02*
X420148Y265458D01*
X420340Y265717D01*
X420417Y266027D01*
X420340Y266337D01*
X420148Y266595D01*
X419803Y266750D01*
X419458Y266698D01*
X419113Y266492D01*
G01X422673Y263650D02*
X422750Y264322D01*
X422865Y264890D01*
X423018Y265407D01*
X423210Y265975D01*
X423517Y266750D01*
X421983D01*
G01X414193Y270842D02*
X413963Y270997D01*
X413695Y271100D01*
X413388D01*
X413043Y270945D01*
X412775Y270687D01*
X412583Y270377D01*
X412430Y269860D01*
X412392Y269395D01*
X412468Y268930D01*
X412583Y268620D01*
X412813Y268310D01*
X413082Y268103D01*
X413350Y268000D01*
X413618D01*
X413887Y268103D01*
X414117Y268258D01*
X414308Y268465D01*
G01X415722Y270583D02*
X415952Y270893D01*
X416220Y271048D01*
X416527Y271100D01*
X416910Y270997D01*
X417178Y270738D01*
X417255Y270428D01*
X417217Y270118D01*
X417063Y269860D01*
X416297Y269343D01*
X415952Y268982D01*
X415722Y268465D01*
X415645Y268000D01*
X417255D01*
G01X420010D02*
Y271100D01*
X418592Y268878D01*
X420508D01*
G01X422650Y271100D02*
X422343Y270997D01*
X422113Y270738D01*
X421960Y270428D01*
X421845Y270015D01*
X421807Y269550D01*
X421845Y269085D01*
X421960Y268672D01*
X422113Y268362D01*
X422343Y268103D01*
X422650Y268000D01*
X422957Y268103D01*
X423187Y268362D01*
X423340Y268672D01*
X423455Y269085D01*
X423493Y269550D01*
X423455Y270015D01*
X423340Y270428D01*
X423187Y270738D01*
X422957Y270997D01*
X422650Y271100D01*
G01X426350Y270050D02*
Y266950D01*
G01X425468Y270050D02*
X427232D01*
G01X428683Y266950D02*
Y270050D01*
X429603D01*
X429910Y269895D01*
X430140Y269533D01*
X430217Y269120D01*
X430140Y268707D01*
X429948Y268397D01*
X429603Y268242D01*
X428683D01*
G01X431707Y267415D02*
X431937Y267157D01*
X432205Y267002D01*
X432550Y266950D01*
X432895Y267053D01*
X433163Y267260D01*
X433355Y267622D01*
X433393Y268035D01*
X433317Y268448D01*
X433125Y268707D01*
X432857Y268913D01*
X432588Y268965D01*
X432320Y268913D01*
X431975Y268707D01*
X432090Y270050D01*
X433125D01*
G01X434807Y267570D02*
X435037Y267208D01*
X435343Y267002D01*
X435688Y266950D01*
X435995Y267002D01*
X436302Y267260D01*
X436493Y267570D01*
X436532Y267880D01*
X436455Y268242D01*
X436187Y268500D01*
X435918Y268603D01*
X435573D01*
G01X435918D02*
X436148Y268758D01*
X436340Y269017D01*
X436417Y269327D01*
X436340Y269637D01*
X436148Y269895D01*
X435803Y270050D01*
X435458Y269998D01*
X435113Y269792D01*
G01X414193Y275342D02*
X413963Y275497D01*
X413695Y275600D01*
X413388D01*
X413043Y275445D01*
X412775Y275187D01*
X412583Y274877D01*
X412430Y274360D01*
X412392Y273895D01*
X412468Y273430D01*
X412583Y273120D01*
X412813Y272810D01*
X413082Y272603D01*
X413350Y272500D01*
X413618D01*
X413887Y272603D01*
X414117Y272758D01*
X414308Y272965D01*
G01X415722Y275083D02*
X415952Y275393D01*
X416220Y275548D01*
X416527Y275600D01*
X416910Y275497D01*
X417178Y275238D01*
X417255Y274928D01*
X417217Y274618D01*
X417063Y274360D01*
X416297Y273843D01*
X415952Y273482D01*
X415722Y272965D01*
X415645Y272500D01*
X417255D01*
G01X418707Y273120D02*
X418937Y272758D01*
X419243Y272552D01*
X419588Y272500D01*
X419895Y272552D01*
X420202Y272810D01*
X420393Y273120D01*
X420432Y273430D01*
X420355Y273792D01*
X420087Y274050D01*
X419818Y274153D01*
X419473D01*
G01X419818D02*
X420048Y274308D01*
X420240Y274567D01*
X420317Y274877D01*
X420240Y275187D01*
X420048Y275445D01*
X419703Y275600D01*
X419358Y275548D01*
X419013Y275342D01*
G01X422650Y272500D02*
X422918Y272552D01*
X423225Y272707D01*
X423417Y272965D01*
X423493Y273327D01*
X423417Y273688D01*
X423187Y273998D01*
X422842Y274153D01*
X422458D01*
X422228Y274257D01*
X422037Y274515D01*
X421960Y274877D01*
X422075Y275238D01*
X422343Y275497D01*
X422650Y275600D01*
X422957Y275497D01*
X423225Y275238D01*
X423340Y274877D01*
X423263Y274515D01*
X423072Y274257D01*
X422842Y274153D01*
X422458D01*
X422113Y273998D01*
X421883Y273688D01*
X421807Y273327D01*
X421883Y272965D01*
X422075Y272707D01*
X422382Y272552D01*
X422650Y272500D01*
G01X425400Y277250D02*
Y279750D01*
X425080Y279250D01*
G01Y277250D02*
X425720D01*
G01X427093Y279333D02*
X427253Y279583D01*
X427440Y279708D01*
X427653Y279750D01*
X427920Y279667D01*
X428107Y279458D01*
X428160Y279208D01*
X428133Y278958D01*
X428027Y278750D01*
X427493Y278333D01*
X427253Y278042D01*
X427093Y277625D01*
X427040Y277250D01*
X428160D01*
G01X424447Y294450D02*
X424500Y294992D01*
X424580Y295450D01*
X424687Y295867D01*
X424820Y296325D01*
X425033Y296950D01*
X423967D01*
G01X422057Y303550D02*
Y301328D01*
X422210Y300863D01*
X422517Y300553D01*
X422900Y300450D01*
X423283Y300553D01*
X423590Y300863D01*
X423743Y301328D01*
Y303550D01*
G01X425157Y301070D02*
X425387Y300708D01*
X425693Y300502D01*
X426038Y300450D01*
X426345Y300502D01*
X426652Y300760D01*
X426843Y301070D01*
X426882Y301380D01*
X426805Y301742D01*
X426537Y302000D01*
X426268Y302103D01*
X425923D01*
G01X426268D02*
X426498Y302258D01*
X426690Y302517D01*
X426767Y302827D01*
X426690Y303137D01*
X426498Y303395D01*
X426153Y303550D01*
X425808Y303498D01*
X425463Y303292D01*
G01X429100Y300450D02*
X429368Y300502D01*
X429675Y300657D01*
X429867Y300915D01*
X429943Y301277D01*
X429867Y301638D01*
X429637Y301948D01*
X429292Y302103D01*
X428908D01*
X428678Y302207D01*
X428487Y302465D01*
X428410Y302827D01*
X428525Y303188D01*
X428793Y303447D01*
X429100Y303550D01*
X429407Y303447D01*
X429675Y303188D01*
X429790Y302827D01*
X429713Y302465D01*
X429522Y302207D01*
X429292Y302103D01*
X428908D01*
X428563Y301948D01*
X428333Y301638D01*
X428257Y301277D01*
X428333Y300915D01*
X428525Y300657D01*
X428832Y300502D01*
X429100Y300450D01*
G01X427550Y334083D02*
X424450D01*
Y335042D01*
X424605Y335348D01*
X424812Y335540D01*
X425225Y335617D01*
X425638Y335540D01*
X425897Y335310D01*
X426052Y335042D01*
Y334083D01*
G01Y335042D02*
X427550Y335617D01*
G01Y338410D02*
X424450D01*
X426672Y336992D01*
Y338908D01*
G01X426258Y340322D02*
X425897Y340590D01*
X425690Y340820D01*
X425587Y341127D01*
X425690Y341395D01*
X425897Y341587D01*
X426207Y341740D01*
X426568Y341778D01*
X426878Y341740D01*
X427188Y341587D01*
X427447Y341357D01*
X427550Y341088D01*
X427447Y340782D01*
X427137Y340513D01*
X426672Y340360D01*
X426155Y340322D01*
X425483Y340398D01*
X425122Y340513D01*
X424760Y340705D01*
X424502Y340973D01*
X424450Y341242D01*
X424553Y341510D01*
X424812Y341702D01*
G01X427085Y343307D02*
X427343Y343537D01*
X427498Y343805D01*
X427550Y344150D01*
X427447Y344495D01*
X427240Y344763D01*
X426878Y344955D01*
X426465Y344993D01*
X426052Y344917D01*
X425793Y344725D01*
X425587Y344457D01*
X425535Y344188D01*
X425587Y343920D01*
X425793Y343575D01*
X424450Y343690D01*
Y344725D01*
G01X412820Y335250D02*
Y337750D01*
X411833Y335958D01*
X413167D01*
G01X428450Y334057D02*
X430672D01*
X431137Y334210D01*
X431447Y334517D01*
X431550Y334900D01*
X431447Y335283D01*
X431137Y335590D01*
X430672Y335743D01*
X428450D01*
G01X431550Y338460D02*
X428450D01*
X430672Y337042D01*
Y338958D01*
G01X428450Y341100D02*
X428553Y340793D01*
X428812Y340563D01*
X429122Y340410D01*
X429535Y340295D01*
X430000Y340257D01*
X430465Y340295D01*
X430878Y340410D01*
X431188Y340563D01*
X431447Y340793D01*
X431550Y341100D01*
X431447Y341407D01*
X431188Y341637D01*
X430878Y341790D01*
X430465Y341905D01*
X430000Y341943D01*
X429535Y341905D01*
X429122Y341790D01*
X428812Y341637D01*
X428553Y341407D01*
X428450Y341100D01*
G01X421993Y336292D02*
X422180Y336583D01*
X422340Y336750D01*
X422553Y336833D01*
X422740Y336750D01*
X422873Y336583D01*
X422980Y336333D01*
X423007Y336042D01*
X422980Y335792D01*
X422873Y335542D01*
X422713Y335333D01*
X422527Y335250D01*
X422313Y335333D01*
X422127Y335583D01*
X422020Y335958D01*
X421993Y336375D01*
X422047Y336917D01*
X422127Y337208D01*
X422260Y337500D01*
X422447Y337708D01*
X422633Y337750D01*
X422820Y337667D01*
X422953Y337458D01*
G01X412413Y351750D02*
X412573Y351458D01*
X412787Y351292D01*
X413027Y351250D01*
X413240Y351292D01*
X413453Y351500D01*
X413587Y351750D01*
X413613Y352000D01*
X413560Y352292D01*
X413373Y352500D01*
X413187Y352583D01*
X412947D01*
G01X413187D02*
X413347Y352708D01*
X413480Y352917D01*
X413533Y353167D01*
X413480Y353417D01*
X413347Y353625D01*
X413107Y353750D01*
X412867Y353708D01*
X412627Y353542D01*
G01X420893Y384833D02*
X421053Y385083D01*
X421240Y385208D01*
X421453Y385250D01*
X421720Y385167D01*
X421907Y384958D01*
X421960Y384708D01*
X421933Y384458D01*
X421827Y384250D01*
X421293Y383833D01*
X421053Y383542D01*
X420893Y383125D01*
X420840Y382750D01*
X421960D01*
G01X423600D02*
X423787Y382792D01*
X424000Y382917D01*
X424133Y383125D01*
X424187Y383417D01*
X424133Y383708D01*
X423973Y383958D01*
X423733Y384083D01*
X423467D01*
X423307Y384167D01*
X423173Y384375D01*
X423120Y384667D01*
X423200Y384958D01*
X423387Y385167D01*
X423600Y385250D01*
X423813Y385167D01*
X424000Y384958D01*
X424080Y384667D01*
X424027Y384375D01*
X423893Y384167D01*
X423733Y384083D01*
X423467D01*
X423227Y383958D01*
X423067Y383708D01*
X423013Y383417D01*
X423067Y383125D01*
X423200Y382917D01*
X423413Y382792D01*
X423600Y382750D01*
G01X427200Y383750D02*
Y381250D01*
G01X426587Y383750D02*
X427813D01*
G01X428867Y381250D02*
Y383750D01*
X429507D01*
X429720Y383625D01*
X429880Y383333D01*
X429933Y383000D01*
X429880Y382667D01*
X429747Y382417D01*
X429507Y382292D01*
X428867D01*
G01X431093Y383333D02*
X431253Y383583D01*
X431440Y383708D01*
X431653Y383750D01*
X431920Y383667D01*
X432107Y383458D01*
X432160Y383208D01*
X432133Y382958D01*
X432027Y382750D01*
X431493Y382333D01*
X431253Y382042D01*
X431093Y381625D01*
X431040Y381250D01*
X432160D01*
G01X433213Y381625D02*
X433373Y381417D01*
X433560Y381292D01*
X433800Y381250D01*
X434040Y381333D01*
X434227Y381500D01*
X434360Y381792D01*
X434387Y382125D01*
X434333Y382458D01*
X434200Y382667D01*
X434013Y382833D01*
X433827Y382875D01*
X433640Y382833D01*
X433400Y382667D01*
X433480Y383750D01*
X434200D01*
G01X416557Y421050D02*
Y418828D01*
X416710Y418363D01*
X417017Y418053D01*
X417400Y417950D01*
X417783Y418053D01*
X418090Y418363D01*
X418243Y418828D01*
Y421050D01*
G01X419657Y418570D02*
X419887Y418208D01*
X420193Y418002D01*
X420538Y417950D01*
X420845Y418002D01*
X421152Y418260D01*
X421343Y418570D01*
X421382Y418880D01*
X421305Y419242D01*
X421037Y419500D01*
X420768Y419603D01*
X420423D01*
G01X420768D02*
X420998Y419758D01*
X421190Y420017D01*
X421267Y420327D01*
X421190Y420637D01*
X420998Y420895D01*
X420653Y421050D01*
X420308Y420998D01*
X419963Y420792D01*
G01X422757Y418570D02*
X422987Y418208D01*
X423293Y418002D01*
X423638Y417950D01*
X423945Y418002D01*
X424252Y418260D01*
X424443Y418570D01*
X424482Y418880D01*
X424405Y419242D01*
X424137Y419500D01*
X423868Y419603D01*
X423523D01*
G01X423868D02*
X424098Y419758D01*
X424290Y420017D01*
X424367Y420327D01*
X424290Y420637D01*
X424098Y420895D01*
X423753Y421050D01*
X423408Y420998D01*
X423063Y420792D01*
G01X420500Y413750D02*
X420687Y413792D01*
X420900Y413917D01*
X421033Y414125D01*
X421087Y414417D01*
X421033Y414708D01*
X420873Y414958D01*
X420633Y415083D01*
X420367D01*
X420207Y415167D01*
X420073Y415375D01*
X420020Y415667D01*
X420100Y415958D01*
X420287Y416167D01*
X420500Y416250D01*
X420713Y416167D01*
X420900Y415958D01*
X420980Y415667D01*
X420927Y415375D01*
X420793Y415167D01*
X420633Y415083D01*
X420367D01*
X420127Y414958D01*
X419967Y414708D01*
X419913Y414417D01*
X419967Y414125D01*
X420100Y413917D01*
X420313Y413792D01*
X420500Y413750D01*
G01X434950Y57450D02*
Y58845D01*
X434183Y60550D01*
G01X435717D02*
X434950Y58845D01*
G01X437207Y58070D02*
X437437Y57708D01*
X437743Y57502D01*
X438088Y57450D01*
X438395Y57502D01*
X438702Y57760D01*
X438893Y58070D01*
X438932Y58380D01*
X438855Y58742D01*
X438587Y59000D01*
X438318Y59103D01*
X437973D01*
G01X438318D02*
X438548Y59258D01*
X438740Y59517D01*
X438817Y59827D01*
X438740Y60137D01*
X438548Y60395D01*
X438203Y60550D01*
X437858Y60498D01*
X437513Y60292D01*
G01X434208Y67693D02*
X434053Y67463D01*
X433950Y67195D01*
Y66888D01*
X434105Y66543D01*
X434363Y66275D01*
X434673Y66083D01*
X435190Y65930D01*
X435655Y65892D01*
X436120Y65968D01*
X436430Y66083D01*
X436740Y66313D01*
X436947Y66582D01*
X437050Y66850D01*
Y67118D01*
X436947Y67387D01*
X436792Y67617D01*
X436585Y67808D01*
G01X434467Y69222D02*
X434157Y69452D01*
X434002Y69720D01*
X433950Y70027D01*
X434053Y70410D01*
X434312Y70678D01*
X434622Y70755D01*
X434932Y70717D01*
X435190Y70563D01*
X435707Y69797D01*
X436068Y69452D01*
X436585Y69222D01*
X437050Y69145D01*
Y70755D01*
G01X436585Y72207D02*
X436843Y72437D01*
X436998Y72705D01*
X437050Y73050D01*
X436947Y73395D01*
X436740Y73663D01*
X436378Y73855D01*
X435965Y73893D01*
X435552Y73817D01*
X435293Y73625D01*
X435087Y73357D01*
X435035Y73088D01*
X435087Y72820D01*
X435293Y72475D01*
X433950Y72590D01*
Y73625D01*
G01X434467Y75422D02*
X434157Y75652D01*
X434002Y75920D01*
X433950Y76227D01*
X434053Y76610D01*
X434312Y76878D01*
X434622Y76955D01*
X434932Y76917D01*
X435190Y76763D01*
X435707Y75997D01*
X436068Y75652D01*
X436585Y75422D01*
X437050Y75345D01*
Y76955D01*
G01X438708Y68193D02*
X438553Y67963D01*
X438450Y67695D01*
Y67388D01*
X438605Y67043D01*
X438863Y66775D01*
X439173Y66583D01*
X439690Y66430D01*
X440155Y66392D01*
X440620Y66468D01*
X440930Y66583D01*
X441240Y66813D01*
X441447Y67082D01*
X441550Y67350D01*
Y67618D01*
X441447Y67887D01*
X441292Y68117D01*
X441085Y68308D01*
G01X438967Y69722D02*
X438657Y69952D01*
X438502Y70220D01*
X438450Y70527D01*
X438553Y70910D01*
X438812Y71178D01*
X439122Y71255D01*
X439432Y71217D01*
X439690Y71063D01*
X440207Y70297D01*
X440568Y69952D01*
X441085Y69722D01*
X441550Y69645D01*
Y71255D01*
G01X441085Y72707D02*
X441343Y72937D01*
X441498Y73205D01*
X441550Y73550D01*
X441447Y73895D01*
X441240Y74163D01*
X440878Y74355D01*
X440465Y74393D01*
X440052Y74317D01*
X439793Y74125D01*
X439587Y73857D01*
X439535Y73588D01*
X439587Y73320D01*
X439793Y72975D01*
X438450Y73090D01*
Y74125D01*
G01X441550Y76650D02*
X438450D01*
X439070Y76190D01*
G01X441550D02*
Y77110D01*
G01X437583Y61950D02*
Y65050D01*
X438542D01*
X438848Y64895D01*
X439040Y64688D01*
X439117Y64275D01*
X439040Y63862D01*
X438810Y63603D01*
X438542Y63448D01*
X437583D01*
G01X438542D02*
X439117Y61950D01*
G01X440722Y64533D02*
X440952Y64843D01*
X441220Y64998D01*
X441527Y65050D01*
X441910Y64947D01*
X442178Y64688D01*
X442255Y64378D01*
X442217Y64068D01*
X442063Y63810D01*
X441297Y63293D01*
X440952Y62932D01*
X440722Y62415D01*
X440645Y61950D01*
X442255D01*
G01X445010D02*
Y65050D01*
X443592Y62828D01*
X445508D01*
G01X447650Y61950D02*
Y65050D01*
X447190Y64430D01*
G01Y61950D02*
X448110D01*
G01X429033Y124717D02*
X431533D01*
Y125783D01*
G01X434533Y122057D02*
X432033D01*
X434116Y122750D01*
X432033Y123443D01*
X434533D01*
G01X439033Y124637D02*
X436533D01*
X439033Y125863D01*
X436533D01*
G01X441533Y122217D02*
X439033D01*
Y122857D01*
X439158Y123070D01*
X439450Y123230D01*
X439783Y123283D01*
X440116Y123230D01*
X440366Y123097D01*
X440491Y122857D01*
Y122217D01*
G01X446033Y124717D02*
X443533D01*
Y125383D01*
X443658Y125597D01*
X443825Y125730D01*
X444158Y125783D01*
X444491Y125730D01*
X444700Y125570D01*
X444825Y125383D01*
Y124717D01*
G01Y125383D02*
X446033Y125783D01*
G01X447550Y226583D02*
X444450D01*
Y227542D01*
X444605Y227848D01*
X444812Y228040D01*
X445225Y228117D01*
X445638Y228040D01*
X445897Y227810D01*
X446052Y227542D01*
Y226583D01*
G01Y227542D02*
X447550Y228117D01*
G01X444967Y229722D02*
X444657Y229952D01*
X444502Y230220D01*
X444450Y230527D01*
X444553Y230910D01*
X444812Y231178D01*
X445122Y231255D01*
X445432Y231217D01*
X445690Y231063D01*
X446207Y230297D01*
X446568Y229952D01*
X447085Y229722D01*
X447550Y229645D01*
Y231255D01*
G01X446930Y232707D02*
X447292Y232937D01*
X447498Y233243D01*
X447550Y233588D01*
X447498Y233895D01*
X447240Y234202D01*
X446930Y234393D01*
X446620Y234432D01*
X446258Y234355D01*
X446000Y234087D01*
X445897Y233818D01*
Y233473D01*
G01Y233818D02*
X445742Y234048D01*
X445483Y234240D01*
X445173Y234317D01*
X444863Y234240D01*
X444605Y234048D01*
X444450Y233703D01*
X444502Y233358D01*
X444708Y233013D01*
G01X447550Y236650D02*
X447498Y236918D01*
X447343Y237225D01*
X447085Y237417D01*
X446723Y237493D01*
X446362Y237417D01*
X446052Y237187D01*
X445897Y236842D01*
Y236458D01*
X445793Y236228D01*
X445535Y236037D01*
X445173Y235960D01*
X444812Y236075D01*
X444553Y236343D01*
X444450Y236650D01*
X444553Y236957D01*
X444812Y237225D01*
X445173Y237340D01*
X445535Y237263D01*
X445793Y237072D01*
X445897Y236842D01*
Y236458D01*
X446052Y236113D01*
X446362Y235883D01*
X446723Y235807D01*
X447085Y235883D01*
X447343Y236075D01*
X447498Y236382D01*
X447550Y236650D01*
G01X441057Y224550D02*
Y222328D01*
X441210Y221863D01*
X441517Y221553D01*
X441900Y221450D01*
X442283Y221553D01*
X442590Y221863D01*
X442743Y222328D01*
Y224550D01*
G01X444272Y224033D02*
X444502Y224343D01*
X444770Y224498D01*
X445077Y224550D01*
X445460Y224447D01*
X445728Y224188D01*
X445805Y223878D01*
X445767Y223568D01*
X445613Y223310D01*
X444847Y222793D01*
X444502Y222432D01*
X444272Y221915D01*
X444195Y221450D01*
X445805D01*
G01X448560D02*
Y224550D01*
X447142Y222328D01*
X449058D01*
G01X435250Y222100D02*
X437750D01*
G01X435250Y221487D02*
Y222713D01*
G01X437750Y223767D02*
X435250D01*
Y224407D01*
X435375Y224620D01*
X435667Y224780D01*
X436000Y224833D01*
X436333Y224780D01*
X436583Y224647D01*
X436708Y224407D01*
Y223767D01*
G01X437750Y226500D02*
X435250D01*
X435750Y226180D01*
G01X437750D02*
Y226820D01*
G01Y228700D02*
X437708Y228887D01*
X437583Y229100D01*
X437375Y229233D01*
X437083Y229287D01*
X436792Y229233D01*
X436542Y229073D01*
X436417Y228833D01*
Y228567D01*
X436333Y228407D01*
X436125Y228273D01*
X435833Y228220D01*
X435542Y228300D01*
X435333Y228487D01*
X435250Y228700D01*
X435333Y228913D01*
X435542Y229100D01*
X435833Y229180D01*
X436125Y229127D01*
X436333Y228993D01*
X436417Y228833D01*
Y228567D01*
X436542Y228327D01*
X436792Y228167D01*
X437083Y228113D01*
X437375Y228167D01*
X437583Y228300D01*
X437708Y228513D01*
X437750Y228700D01*
G01Y230900D02*
X437708Y231087D01*
X437583Y231300D01*
X437375Y231433D01*
X437083Y231487D01*
X436792Y231433D01*
X436542Y231273D01*
X436417Y231033D01*
Y230767D01*
X436333Y230607D01*
X436125Y230473D01*
X435833Y230420D01*
X435542Y230500D01*
X435333Y230687D01*
X435250Y230900D01*
X435333Y231113D01*
X435542Y231300D01*
X435833Y231380D01*
X436125Y231327D01*
X436333Y231193D01*
X436417Y231033D01*
Y230767D01*
X436542Y230527D01*
X436792Y230367D01*
X437083Y230313D01*
X437375Y230367D01*
X437583Y230500D01*
X437708Y230713D01*
X437750Y230900D01*
G01X431750Y222100D02*
X434250D01*
G01X431750Y221487D02*
Y222713D01*
G01X434250Y223767D02*
X431750D01*
Y224407D01*
X431875Y224620D01*
X432167Y224780D01*
X432500Y224833D01*
X432833Y224780D01*
X433083Y224647D01*
X433208Y224407D01*
Y223767D01*
G01X434250Y226500D02*
X431750D01*
X432250Y226180D01*
G01X434250D02*
Y226820D01*
G01Y228700D02*
X434208Y228887D01*
X434083Y229100D01*
X433875Y229233D01*
X433583Y229287D01*
X433292Y229233D01*
X433042Y229073D01*
X432917Y228833D01*
Y228567D01*
X432833Y228407D01*
X432625Y228273D01*
X432333Y228220D01*
X432042Y228300D01*
X431833Y228487D01*
X431750Y228700D01*
X431833Y228913D01*
X432042Y229100D01*
X432333Y229180D01*
X432625Y229127D01*
X432833Y228993D01*
X432917Y228833D01*
Y228567D01*
X433042Y228327D01*
X433292Y228167D01*
X433583Y228113D01*
X433875Y228167D01*
X434083Y228300D01*
X434208Y228513D01*
X434250Y228700D01*
G01Y230847D02*
X433708Y230900D01*
X433250Y230980D01*
X432833Y231087D01*
X432375Y231220D01*
X431750Y231433D01*
Y230367D01*
G01X432750Y233100D02*
X435250D01*
G01X432750Y232487D02*
Y233713D01*
G01X435250Y234767D02*
X432750D01*
Y235407D01*
X432875Y235620D01*
X433167Y235780D01*
X433500Y235833D01*
X433833Y235780D01*
X434083Y235647D01*
X434208Y235407D01*
Y234767D01*
G01X435250Y237500D02*
X432750D01*
X433250Y237180D01*
G01X435250D02*
Y237820D01*
G01Y239700D02*
X435208Y239887D01*
X435083Y240100D01*
X434875Y240233D01*
X434583Y240287D01*
X434292Y240233D01*
X434042Y240073D01*
X433917Y239833D01*
Y239567D01*
X433833Y239407D01*
X433625Y239273D01*
X433333Y239220D01*
X433042Y239300D01*
X432833Y239487D01*
X432750Y239700D01*
X432833Y239913D01*
X433042Y240100D01*
X433333Y240180D01*
X433625Y240127D01*
X433833Y239993D01*
X433917Y239833D01*
Y239567D01*
X434042Y239327D01*
X434292Y239167D01*
X434583Y239113D01*
X434875Y239167D01*
X435083Y239300D01*
X435208Y239513D01*
X435250Y239700D01*
G01X434875Y241313D02*
X435083Y241473D01*
X435208Y241660D01*
X435250Y241900D01*
X435167Y242140D01*
X435000Y242327D01*
X434708Y242460D01*
X434375Y242487D01*
X434042Y242433D01*
X433833Y242300D01*
X433667Y242113D01*
X433625Y241927D01*
X433667Y241740D01*
X433833Y241500D01*
X432750Y241580D01*
Y242300D01*
G01X429250Y233100D02*
X431750D01*
G01X429250Y232487D02*
Y233713D01*
G01X431750Y234767D02*
X429250D01*
Y235407D01*
X429375Y235620D01*
X429667Y235780D01*
X430000Y235833D01*
X430333Y235780D01*
X430583Y235647D01*
X430708Y235407D01*
Y234767D01*
G01X431750Y237500D02*
X429250D01*
X429750Y237180D01*
G01X431750D02*
Y237820D01*
G01Y239700D02*
X431708Y239887D01*
X431583Y240100D01*
X431375Y240233D01*
X431083Y240287D01*
X430792Y240233D01*
X430542Y240073D01*
X430417Y239833D01*
Y239567D01*
X430333Y239407D01*
X430125Y239273D01*
X429833Y239220D01*
X429542Y239300D01*
X429333Y239487D01*
X429250Y239700D01*
X429333Y239913D01*
X429542Y240100D01*
X429833Y240180D01*
X430125Y240127D01*
X430333Y239993D01*
X430417Y239833D01*
Y239567D01*
X430542Y239327D01*
X430792Y239167D01*
X431083Y239113D01*
X431375Y239167D01*
X431583Y239300D01*
X431708Y239513D01*
X431750Y239700D01*
G01Y242220D02*
X429250D01*
X431042Y241233D01*
Y242567D01*
G01X442550Y251583D02*
X439450D01*
Y252542D01*
X439605Y252848D01*
X439812Y253040D01*
X440225Y253117D01*
X440638Y253040D01*
X440897Y252810D01*
X441052Y252542D01*
Y251583D01*
G01Y252542D02*
X442550Y253117D01*
G01X439967Y254722D02*
X439657Y254952D01*
X439502Y255220D01*
X439450Y255527D01*
X439553Y255910D01*
X439812Y256178D01*
X440122Y256255D01*
X440432Y256217D01*
X440690Y256063D01*
X441207Y255297D01*
X441568Y254952D01*
X442085Y254722D01*
X442550Y254645D01*
Y256255D01*
G01Y258550D02*
X439450D01*
X440070Y258090D01*
G01X442550D02*
Y259010D01*
G01X441930Y260807D02*
X442292Y261037D01*
X442498Y261343D01*
X442550Y261688D01*
X442498Y261995D01*
X442240Y262302D01*
X441930Y262493D01*
X441620Y262532D01*
X441258Y262455D01*
X441000Y262187D01*
X440897Y261918D01*
Y261573D01*
G01Y261918D02*
X440742Y262148D01*
X440483Y262340D01*
X440173Y262417D01*
X439863Y262340D01*
X439605Y262148D01*
X439450Y261803D01*
X439502Y261458D01*
X439708Y261113D01*
G01X447050Y251583D02*
X443950D01*
Y252542D01*
X444105Y252848D01*
X444312Y253040D01*
X444725Y253117D01*
X445138Y253040D01*
X445397Y252810D01*
X445552Y252542D01*
Y251583D01*
G01Y252542D02*
X447050Y253117D01*
G01X444467Y254722D02*
X444157Y254952D01*
X444002Y255220D01*
X443950Y255527D01*
X444053Y255910D01*
X444312Y256178D01*
X444622Y256255D01*
X444932Y256217D01*
X445190Y256063D01*
X445707Y255297D01*
X446068Y254952D01*
X446585Y254722D01*
X447050Y254645D01*
Y256255D01*
G01Y258550D02*
X443950D01*
X444570Y258090D01*
G01X447050D02*
Y259010D01*
G01Y262110D02*
X443950D01*
X446172Y260692D01*
Y262608D01*
G01X430057Y299050D02*
Y296828D01*
X430210Y296363D01*
X430517Y296053D01*
X430900Y295950D01*
X431283Y296053D01*
X431590Y296363D01*
X431743Y296828D01*
Y299050D01*
G01X433272Y298533D02*
X433502Y298843D01*
X433770Y298998D01*
X434077Y299050D01*
X434460Y298947D01*
X434728Y298688D01*
X434805Y298378D01*
X434767Y298068D01*
X434613Y297810D01*
X433847Y297293D01*
X433502Y296932D01*
X433272Y296415D01*
X433195Y295950D01*
X434805D01*
G01X436372Y298533D02*
X436602Y298843D01*
X436870Y298998D01*
X437177Y299050D01*
X437560Y298947D01*
X437828Y298688D01*
X437905Y298378D01*
X437867Y298068D01*
X437713Y297810D01*
X436947Y297293D01*
X436602Y296932D01*
X436372Y296415D01*
X436295Y295950D01*
X437905D01*
G01X436050Y331083D02*
X432950D01*
Y332042D01*
X433105Y332348D01*
X433312Y332540D01*
X433725Y332617D01*
X434138Y332540D01*
X434397Y332310D01*
X434552Y332042D01*
Y331083D01*
G01Y332042D02*
X436050Y332617D01*
G01Y335410D02*
X432950D01*
X435172Y333992D01*
Y335908D01*
G01X436050Y338510D02*
X432950D01*
X435172Y337092D01*
Y339008D01*
G01X435430Y340307D02*
X435792Y340537D01*
X435998Y340843D01*
X436050Y341188D01*
X435998Y341495D01*
X435740Y341802D01*
X435430Y341993D01*
X435120Y342032D01*
X434758Y341955D01*
X434500Y341687D01*
X434397Y341418D01*
Y341073D01*
G01Y341418D02*
X434242Y341648D01*
X433983Y341840D01*
X433673Y341917D01*
X433363Y341840D01*
X433105Y341648D01*
X432950Y341303D01*
X433002Y340958D01*
X433208Y340613D01*
G01X447750Y324900D02*
X445250D01*
X445750Y324580D01*
G01X447750D02*
Y325220D01*
G01X446708Y326593D02*
X446417Y326780D01*
X446250Y326940D01*
X446167Y327153D01*
X446250Y327340D01*
X446417Y327473D01*
X446667Y327580D01*
X446958Y327607D01*
X447208Y327580D01*
X447458Y327473D01*
X447667Y327313D01*
X447750Y327127D01*
X447667Y326913D01*
X447417Y326727D01*
X447042Y326620D01*
X446625Y326593D01*
X446083Y326647D01*
X445792Y326727D01*
X445500Y326860D01*
X445292Y327047D01*
X445250Y327233D01*
X445333Y327420D01*
X445542Y327553D01*
G01X433348Y355312D02*
X433617Y355053D01*
X433923Y354950D01*
X434230Y355053D01*
X434498Y355363D01*
X434690Y355828D01*
X434767Y356293D01*
Y356862D01*
X434690Y357327D01*
X434498Y357740D01*
X434268Y357947D01*
X434000Y358050D01*
X433693Y357947D01*
X433463Y357740D01*
X433310Y357430D01*
X433233Y357017D01*
X433310Y356655D01*
X433502Y356293D01*
X433732Y356087D01*
X434000Y356035D01*
X434307Y356138D01*
X434537Y356397D01*
X434767Y356862D01*
G01X446208Y385243D02*
X446053Y385013D01*
X445950Y384745D01*
Y384438D01*
X446105Y384093D01*
X446363Y383825D01*
X446673Y383633D01*
X447190Y383480D01*
X447655Y383442D01*
X448120Y383518D01*
X448430Y383633D01*
X448740Y383863D01*
X448947Y384132D01*
X449050Y384400D01*
Y384668D01*
X448947Y384937D01*
X448792Y385167D01*
X448585Y385358D01*
G01X449050Y387500D02*
X448998Y387768D01*
X448843Y388075D01*
X448585Y388267D01*
X448223Y388343D01*
X447862Y388267D01*
X447552Y388037D01*
X447397Y387692D01*
Y387308D01*
X447293Y387078D01*
X447035Y386887D01*
X446673Y386810D01*
X446312Y386925D01*
X446053Y387193D01*
X445950Y387500D01*
X446053Y387807D01*
X446312Y388075D01*
X446673Y388190D01*
X447035Y388113D01*
X447293Y387922D01*
X447397Y387692D01*
Y387308D01*
X447552Y386963D01*
X447862Y386733D01*
X448223Y386657D01*
X448585Y386733D01*
X448843Y386925D01*
X448998Y387232D01*
X449050Y387500D01*
G01Y390600D02*
X445950D01*
X446570Y390140D01*
G01X449050D02*
Y391060D01*
G01X432400Y376250D02*
Y378750D01*
X432080Y378250D01*
G01Y376250D02*
X432720D01*
G01X434093Y377292D02*
X434280Y377583D01*
X434440Y377750D01*
X434653Y377833D01*
X434840Y377750D01*
X434973Y377583D01*
X435080Y377333D01*
X435107Y377042D01*
X435080Y376792D01*
X434973Y376542D01*
X434813Y376333D01*
X434627Y376250D01*
X434413Y376333D01*
X434227Y376583D01*
X434120Y376958D01*
X434093Y377375D01*
X434147Y377917D01*
X434227Y378208D01*
X434360Y378500D01*
X434547Y378708D01*
X434733Y378750D01*
X434920Y378667D01*
X435053Y378458D01*
G01X446193Y410292D02*
X445963Y410447D01*
X445695Y410550D01*
X445388D01*
X445043Y410395D01*
X444775Y410137D01*
X444583Y409827D01*
X444430Y409310D01*
X444392Y408845D01*
X444468Y408380D01*
X444583Y408070D01*
X444813Y407760D01*
X445082Y407553D01*
X445350Y407450D01*
X445618D01*
X445887Y407553D01*
X446117Y407708D01*
X446308Y407915D01*
G01X447607Y408070D02*
X447837Y407708D01*
X448143Y407502D01*
X448488Y407450D01*
X448795Y407502D01*
X449102Y407760D01*
X449293Y408070D01*
X449332Y408380D01*
X449255Y408742D01*
X448987Y409000D01*
X448718Y409103D01*
X448373D01*
G01X448718D02*
X448948Y409258D01*
X449140Y409517D01*
X449217Y409827D01*
X449140Y410137D01*
X448948Y410395D01*
X448603Y410550D01*
X448258Y410498D01*
X447913Y410292D01*
G01X451550Y407450D02*
Y410550D01*
X451090Y409930D01*
G01Y407450D02*
X452010D01*
G01X455110D02*
Y410550D01*
X453692Y408328D01*
X455608D01*
G01X445083Y402450D02*
Y405550D01*
X446042D01*
X446348Y405395D01*
X446540Y405188D01*
X446617Y404775D01*
X446540Y404362D01*
X446310Y404103D01*
X446042Y403948D01*
X445083D01*
G01X446042D02*
X446617Y402450D01*
G01X448107Y403070D02*
X448337Y402708D01*
X448643Y402502D01*
X448988Y402450D01*
X449295Y402502D01*
X449602Y402760D01*
X449793Y403070D01*
X449832Y403380D01*
X449755Y403742D01*
X449487Y404000D01*
X449218Y404103D01*
X448873D01*
G01X449218D02*
X449448Y404258D01*
X449640Y404517D01*
X449717Y404827D01*
X449640Y405137D01*
X449448Y405395D01*
X449103Y405550D01*
X448758Y405498D01*
X448413Y405292D01*
G01X451322Y405033D02*
X451552Y405343D01*
X451820Y405498D01*
X452127Y405550D01*
X452510Y405447D01*
X452778Y405188D01*
X452855Y404878D01*
X452817Y404568D01*
X452663Y404310D01*
X451897Y403793D01*
X451552Y403432D01*
X451322Y402915D01*
X451245Y402450D01*
X452855D01*
G01X455610D02*
Y405550D01*
X454192Y403328D01*
X456108D01*
G01X445083Y398450D02*
Y401550D01*
X446042D01*
X446348Y401395D01*
X446540Y401188D01*
X446617Y400775D01*
X446540Y400362D01*
X446310Y400103D01*
X446042Y399948D01*
X445083D01*
G01X446042D02*
X446617Y398450D01*
G01X448107Y399070D02*
X448337Y398708D01*
X448643Y398502D01*
X448988Y398450D01*
X449295Y398502D01*
X449602Y398760D01*
X449793Y399070D01*
X449832Y399380D01*
X449755Y399742D01*
X449487Y400000D01*
X449218Y400103D01*
X448873D01*
G01X449218D02*
X449448Y400258D01*
X449640Y400517D01*
X449717Y400827D01*
X449640Y401137D01*
X449448Y401395D01*
X449103Y401550D01*
X448758Y401498D01*
X448413Y401292D01*
G01X451322Y401033D02*
X451552Y401343D01*
X451820Y401498D01*
X452127Y401550D01*
X452510Y401447D01*
X452778Y401188D01*
X452855Y400878D01*
X452817Y400568D01*
X452663Y400310D01*
X451897Y399793D01*
X451552Y399432D01*
X451322Y398915D01*
X451245Y398450D01*
X452855D01*
G01X455150Y401550D02*
X454843Y401447D01*
X454613Y401188D01*
X454460Y400878D01*
X454345Y400465D01*
X454307Y400000D01*
X454345Y399535D01*
X454460Y399122D01*
X454613Y398812D01*
X454843Y398553D01*
X455150Y398450D01*
X455457Y398553D01*
X455687Y398812D01*
X455840Y399122D01*
X455955Y399535D01*
X455993Y400000D01*
X455955Y400465D01*
X455840Y400878D01*
X455687Y401188D01*
X455457Y401447D01*
X455150Y401550D01*
G01X429447Y406450D02*
X429500Y406992D01*
X429580Y407450D01*
X429687Y407867D01*
X429820Y408325D01*
X430033Y408950D01*
X428967D01*
G01X444583Y412450D02*
Y415550D01*
X445542D01*
X445848Y415395D01*
X446040Y415188D01*
X446117Y414775D01*
X446040Y414362D01*
X445810Y414103D01*
X445542Y413948D01*
X444583D01*
G01X445542D02*
X446117Y412450D01*
G01X447607Y413070D02*
X447837Y412708D01*
X448143Y412502D01*
X448488Y412450D01*
X448795Y412502D01*
X449102Y412760D01*
X449293Y413070D01*
X449332Y413380D01*
X449255Y413742D01*
X448987Y414000D01*
X448718Y414103D01*
X448373D01*
G01X448718D02*
X448948Y414258D01*
X449140Y414517D01*
X449217Y414827D01*
X449140Y415137D01*
X448948Y415395D01*
X448603Y415550D01*
X448258Y415498D01*
X447913Y415292D01*
G01X450822Y415033D02*
X451052Y415343D01*
X451320Y415498D01*
X451627Y415550D01*
X452010Y415447D01*
X452278Y415188D01*
X452355Y414878D01*
X452317Y414568D01*
X452163Y414310D01*
X451397Y413793D01*
X451052Y413432D01*
X450822Y412915D01*
X450745Y412450D01*
X452355D01*
G01X453807Y413070D02*
X454037Y412708D01*
X454343Y412502D01*
X454688Y412450D01*
X454995Y412502D01*
X455302Y412760D01*
X455493Y413070D01*
X455532Y413380D01*
X455455Y413742D01*
X455187Y414000D01*
X454918Y414103D01*
X454573D01*
G01X454918D02*
X455148Y414258D01*
X455340Y414517D01*
X455417Y414827D01*
X455340Y415137D01*
X455148Y415395D01*
X454803Y415550D01*
X454458Y415498D01*
X454113Y415292D01*
G01X444583Y417950D02*
Y421050D01*
X445542D01*
X445848Y420895D01*
X446040Y420688D01*
X446117Y420275D01*
X446040Y419862D01*
X445810Y419603D01*
X445542Y419448D01*
X444583D01*
G01X445542D02*
X446117Y417950D01*
G01X447607Y418570D02*
X447837Y418208D01*
X448143Y418002D01*
X448488Y417950D01*
X448795Y418002D01*
X449102Y418260D01*
X449293Y418570D01*
X449332Y418880D01*
X449255Y419242D01*
X448987Y419500D01*
X448718Y419603D01*
X448373D01*
G01X448718D02*
X448948Y419758D01*
X449140Y420017D01*
X449217Y420327D01*
X449140Y420637D01*
X448948Y420895D01*
X448603Y421050D01*
X448258Y420998D01*
X447913Y420792D01*
G01X450822Y419242D02*
X451090Y419603D01*
X451320Y419810D01*
X451627Y419913D01*
X451895Y419810D01*
X452087Y419603D01*
X452240Y419293D01*
X452278Y418932D01*
X452240Y418622D01*
X452087Y418312D01*
X451857Y418053D01*
X451588Y417950D01*
X451282Y418053D01*
X451013Y418363D01*
X450860Y418828D01*
X450822Y419345D01*
X450898Y420017D01*
X451013Y420378D01*
X451205Y420740D01*
X451473Y420998D01*
X451742Y421050D01*
X452010Y420947D01*
X452202Y420688D01*
G01X455110Y417950D02*
Y421050D01*
X453692Y418828D01*
X455608D01*
G01X444583Y421950D02*
Y425050D01*
X445542D01*
X445848Y424895D01*
X446040Y424688D01*
X446117Y424275D01*
X446040Y423862D01*
X445810Y423603D01*
X445542Y423448D01*
X444583D01*
G01X445542D02*
X446117Y421950D01*
G01X447607Y422570D02*
X447837Y422208D01*
X448143Y422002D01*
X448488Y421950D01*
X448795Y422002D01*
X449102Y422260D01*
X449293Y422570D01*
X449332Y422880D01*
X449255Y423242D01*
X448987Y423500D01*
X448718Y423603D01*
X448373D01*
G01X448718D02*
X448948Y423758D01*
X449140Y424017D01*
X449217Y424327D01*
X449140Y424637D01*
X448948Y424895D01*
X448603Y425050D01*
X448258Y424998D01*
X447913Y424792D01*
G01X450822Y423242D02*
X451090Y423603D01*
X451320Y423810D01*
X451627Y423913D01*
X451895Y423810D01*
X452087Y423603D01*
X452240Y423293D01*
X452278Y422932D01*
X452240Y422622D01*
X452087Y422312D01*
X451857Y422053D01*
X451588Y421950D01*
X451282Y422053D01*
X451013Y422363D01*
X450860Y422828D01*
X450822Y423345D01*
X450898Y424017D01*
X451013Y424378D01*
X451205Y424740D01*
X451473Y424998D01*
X451742Y425050D01*
X452010Y424947D01*
X452202Y424688D01*
G01X453922Y423242D02*
X454190Y423603D01*
X454420Y423810D01*
X454727Y423913D01*
X454995Y423810D01*
X455187Y423603D01*
X455340Y423293D01*
X455378Y422932D01*
X455340Y422622D01*
X455187Y422312D01*
X454957Y422053D01*
X454688Y421950D01*
X454382Y422053D01*
X454113Y422363D01*
X453960Y422828D01*
X453922Y423345D01*
X453998Y424017D01*
X454113Y424378D01*
X454305Y424740D01*
X454573Y424998D01*
X454842Y425050D01*
X455110Y424947D01*
X455302Y424688D01*
G01X455083Y81450D02*
Y84550D01*
X456042D01*
X456348Y84395D01*
X456540Y84188D01*
X456617Y83775D01*
X456540Y83362D01*
X456310Y83103D01*
X456042Y82948D01*
X455083D01*
G01X456042D02*
X456617Y81450D01*
G01X459410D02*
Y84550D01*
X457992Y82328D01*
X459908D01*
G01X461973Y81450D02*
X462050Y82122D01*
X462165Y82690D01*
X462318Y83207D01*
X462510Y83775D01*
X462817Y84550D01*
X461283D01*
G01X465610Y81450D02*
Y84550D01*
X464192Y82328D01*
X466108D01*
G01X455083Y87950D02*
Y91050D01*
X456042D01*
X456348Y90895D01*
X456540Y90688D01*
X456617Y90275D01*
X456540Y89862D01*
X456310Y89603D01*
X456042Y89448D01*
X455083D01*
G01X456042D02*
X456617Y87950D01*
G01X459410D02*
Y91050D01*
X457992Y88828D01*
X459908D01*
G01X462050Y87950D02*
X462318Y88002D01*
X462625Y88157D01*
X462817Y88415D01*
X462893Y88777D01*
X462817Y89138D01*
X462587Y89448D01*
X462242Y89603D01*
X461858D01*
X461628Y89707D01*
X461437Y89965D01*
X461360Y90327D01*
X461475Y90688D01*
X461743Y90947D01*
X462050Y91050D01*
X462357Y90947D01*
X462625Y90688D01*
X462740Y90327D01*
X462663Y89965D01*
X462472Y89707D01*
X462242Y89603D01*
X461858D01*
X461513Y89448D01*
X461283Y89138D01*
X461207Y88777D01*
X461283Y88415D01*
X461475Y88157D01*
X461782Y88002D01*
X462050Y87950D01*
G01X464422Y89242D02*
X464690Y89603D01*
X464920Y89810D01*
X465227Y89913D01*
X465495Y89810D01*
X465687Y89603D01*
X465840Y89293D01*
X465878Y88932D01*
X465840Y88622D01*
X465687Y88312D01*
X465457Y88053D01*
X465188Y87950D01*
X464882Y88053D01*
X464613Y88363D01*
X464460Y88828D01*
X464422Y89345D01*
X464498Y90017D01*
X464613Y90378D01*
X464805Y90740D01*
X465073Y90998D01*
X465342Y91050D01*
X465610Y90947D01*
X465802Y90688D01*
G01X448657Y79570D02*
X448887Y79208D01*
X449193Y79002D01*
X449538Y78950D01*
X449845Y79002D01*
X450152Y79260D01*
X450343Y79570D01*
X450382Y79880D01*
X450305Y80242D01*
X450037Y80500D01*
X449768Y80603D01*
X449423D01*
G01X449768D02*
X449998Y80758D01*
X450190Y81017D01*
X450267Y81327D01*
X450190Y81637D01*
X449998Y81895D01*
X449653Y82050D01*
X449308Y81998D01*
X448963Y81792D01*
G01X453050Y98583D02*
X449950D01*
Y99542D01*
X450105Y99848D01*
X450312Y100040D01*
X450725Y100117D01*
X451138Y100040D01*
X451397Y99810D01*
X451552Y99542D01*
Y98583D01*
G01Y99542D02*
X453050Y100117D01*
G01X452430Y101607D02*
X452792Y101837D01*
X452998Y102143D01*
X453050Y102488D01*
X452998Y102795D01*
X452740Y103102D01*
X452430Y103293D01*
X452120Y103332D01*
X451758Y103255D01*
X451500Y102987D01*
X451397Y102718D01*
Y102373D01*
G01Y102718D02*
X451242Y102948D01*
X450983Y103140D01*
X450673Y103217D01*
X450363Y103140D01*
X450105Y102948D01*
X449950Y102603D01*
X450002Y102258D01*
X450208Y101913D01*
G01X452585Y104707D02*
X452843Y104937D01*
X452998Y105205D01*
X453050Y105550D01*
X452947Y105895D01*
X452740Y106163D01*
X452378Y106355D01*
X451965Y106393D01*
X451552Y106317D01*
X451293Y106125D01*
X451087Y105857D01*
X451035Y105588D01*
X451087Y105320D01*
X451293Y104975D01*
X449950Y105090D01*
Y106125D01*
G01X452688Y107998D02*
X452947Y108267D01*
X453050Y108573D01*
X452947Y108880D01*
X452637Y109148D01*
X452172Y109340D01*
X451707Y109417D01*
X451138D01*
X450673Y109340D01*
X450260Y109148D01*
X450053Y108918D01*
X449950Y108650D01*
X450053Y108343D01*
X450260Y108113D01*
X450570Y107960D01*
X450983Y107883D01*
X451345Y107960D01*
X451707Y108152D01*
X451913Y108382D01*
X451965Y108650D01*
X451862Y108957D01*
X451603Y109187D01*
X451138Y109417D01*
G01X463050Y99583D02*
X459950D01*
Y100542D01*
X460105Y100848D01*
X460312Y101040D01*
X460725Y101117D01*
X461138Y101040D01*
X461397Y100810D01*
X461552Y100542D01*
Y99583D01*
G01Y100542D02*
X463050Y101117D01*
G01Y103910D02*
X459950D01*
X462172Y102492D01*
Y104408D01*
G01X462430Y105707D02*
X462792Y105937D01*
X462998Y106243D01*
X463050Y106588D01*
X462998Y106895D01*
X462740Y107202D01*
X462430Y107393D01*
X462120Y107432D01*
X461758Y107355D01*
X461500Y107087D01*
X461397Y106818D01*
Y106473D01*
G01Y106818D02*
X461242Y107048D01*
X460983Y107240D01*
X460673Y107317D01*
X460363Y107240D01*
X460105Y107048D01*
X459950Y106703D01*
X460002Y106358D01*
X460208Y106013D01*
G01X463050Y109650D02*
X462998Y109918D01*
X462843Y110225D01*
X462585Y110417D01*
X462223Y110493D01*
X461862Y110417D01*
X461552Y110187D01*
X461397Y109842D01*
Y109458D01*
X461293Y109228D01*
X461035Y109037D01*
X460673Y108960D01*
X460312Y109075D01*
X460053Y109343D01*
X459950Y109650D01*
X460053Y109957D01*
X460312Y110225D01*
X460673Y110340D01*
X461035Y110263D01*
X461293Y110072D01*
X461397Y109842D01*
Y109458D01*
X461552Y109113D01*
X461862Y108883D01*
X462223Y108807D01*
X462585Y108883D01*
X462843Y109075D01*
X462998Y109382D01*
X463050Y109650D01*
G01X459050Y99583D02*
X455950D01*
Y100542D01*
X456105Y100848D01*
X456312Y101040D01*
X456725Y101117D01*
X457138Y101040D01*
X457397Y100810D01*
X457552Y100542D01*
Y99583D01*
G01Y100542D02*
X459050Y101117D01*
G01Y103910D02*
X455950D01*
X458172Y102492D01*
Y104408D01*
G01X458430Y105707D02*
X458792Y105937D01*
X458998Y106243D01*
X459050Y106588D01*
X458998Y106895D01*
X458740Y107202D01*
X458430Y107393D01*
X458120Y107432D01*
X457758Y107355D01*
X457500Y107087D01*
X457397Y106818D01*
Y106473D01*
G01Y106818D02*
X457242Y107048D01*
X456983Y107240D01*
X456673Y107317D01*
X456363Y107240D01*
X456105Y107048D01*
X455950Y106703D01*
X456002Y106358D01*
X456208Y106013D01*
G01X458688Y108998D02*
X458947Y109267D01*
X459050Y109573D01*
X458947Y109880D01*
X458637Y110148D01*
X458172Y110340D01*
X457707Y110417D01*
X457138D01*
X456673Y110340D01*
X456260Y110148D01*
X456053Y109918D01*
X455950Y109650D01*
X456053Y109343D01*
X456260Y109113D01*
X456570Y108960D01*
X456983Y108883D01*
X457345Y108960D01*
X457707Y109152D01*
X457913Y109382D01*
X457965Y109650D01*
X457862Y109957D01*
X457603Y110187D01*
X457138Y110417D01*
G01X455083Y95450D02*
Y98550D01*
X456042D01*
X456348Y98395D01*
X456540Y98188D01*
X456617Y97775D01*
X456540Y97362D01*
X456310Y97103D01*
X456042Y96948D01*
X455083D01*
G01X456042D02*
X456617Y95450D01*
G01X459410D02*
Y98550D01*
X457992Y96328D01*
X459908D01*
G01X462050Y95450D02*
X462318Y95502D01*
X462625Y95657D01*
X462817Y95915D01*
X462893Y96277D01*
X462817Y96638D01*
X462587Y96948D01*
X462242Y97103D01*
X461858D01*
X461628Y97207D01*
X461437Y97465D01*
X461360Y97827D01*
X461475Y98188D01*
X461743Y98447D01*
X462050Y98550D01*
X462357Y98447D01*
X462625Y98188D01*
X462740Y97827D01*
X462663Y97465D01*
X462472Y97207D01*
X462242Y97103D01*
X461858D01*
X461513Y96948D01*
X461283Y96638D01*
X461207Y96277D01*
X461283Y95915D01*
X461475Y95657D01*
X461782Y95502D01*
X462050Y95450D01*
G01X464307Y95915D02*
X464537Y95657D01*
X464805Y95502D01*
X465150Y95450D01*
X465495Y95553D01*
X465763Y95760D01*
X465955Y96122D01*
X465993Y96535D01*
X465917Y96948D01*
X465725Y97207D01*
X465457Y97413D01*
X465188Y97465D01*
X464920Y97413D01*
X464575Y97207D01*
X464690Y98550D01*
X465725D01*
G01X450033Y124663D02*
X451825D01*
X452200Y124770D01*
X452450Y124983D01*
X452533Y125250D01*
X452450Y125517D01*
X452200Y125730D01*
X451825Y125837D01*
X450033D01*
G01X446533Y122750D02*
X449033D01*
G01X446533Y122137D02*
Y123363D01*
G01X463533Y122750D02*
X462408D01*
X461033Y122217D01*
G01Y123283D02*
X462408Y122750D01*
G01X458033Y124450D02*
X460533Y124823D01*
X458033Y125250D01*
X460533Y125677D01*
X458033Y126050D01*
G01X454033Y122083D02*
X456533Y122750D01*
X454033Y123417D01*
G01X450708Y267193D02*
X450553Y266963D01*
X450450Y266695D01*
Y266388D01*
X450605Y266043D01*
X450863Y265775D01*
X451173Y265583D01*
X451690Y265430D01*
X452155Y265392D01*
X452620Y265468D01*
X452930Y265583D01*
X453240Y265813D01*
X453447Y266082D01*
X453550Y266350D01*
Y266618D01*
X453447Y266887D01*
X453292Y267117D01*
X453085Y267308D01*
G01X450967Y268722D02*
X450657Y268952D01*
X450502Y269220D01*
X450450Y269527D01*
X450553Y269910D01*
X450812Y270178D01*
X451122Y270255D01*
X451432Y270217D01*
X451690Y270063D01*
X452207Y269297D01*
X452568Y268952D01*
X453085Y268722D01*
X453550Y268645D01*
Y270255D01*
G01X452930Y271707D02*
X453292Y271937D01*
X453498Y272243D01*
X453550Y272588D01*
X453498Y272895D01*
X453240Y273202D01*
X452930Y273393D01*
X452620Y273432D01*
X452258Y273355D01*
X452000Y273087D01*
X451897Y272818D01*
Y272473D01*
G01Y272818D02*
X451742Y273048D01*
X451483Y273240D01*
X451173Y273317D01*
X450863Y273240D01*
X450605Y273048D01*
X450450Y272703D01*
X450502Y272358D01*
X450708Y272013D01*
G01X452930Y274807D02*
X453292Y275037D01*
X453498Y275343D01*
X453550Y275688D01*
X453498Y275995D01*
X453240Y276302D01*
X452930Y276493D01*
X452620Y276532D01*
X452258Y276455D01*
X452000Y276187D01*
X451897Y275918D01*
Y275573D01*
G01Y275918D02*
X451742Y276148D01*
X451483Y276340D01*
X451173Y276417D01*
X450863Y276340D01*
X450605Y276148D01*
X450450Y275803D01*
X450502Y275458D01*
X450708Y275113D01*
G01X455708Y268193D02*
X455553Y267963D01*
X455450Y267695D01*
Y267388D01*
X455605Y267043D01*
X455863Y266775D01*
X456173Y266583D01*
X456690Y266430D01*
X457155Y266392D01*
X457620Y266468D01*
X457930Y266583D01*
X458240Y266813D01*
X458447Y267082D01*
X458550Y267350D01*
Y267618D01*
X458447Y267887D01*
X458292Y268117D01*
X458085Y268308D01*
G01X455967Y269722D02*
X455657Y269952D01*
X455502Y270220D01*
X455450Y270527D01*
X455553Y270910D01*
X455812Y271178D01*
X456122Y271255D01*
X456432Y271217D01*
X456690Y271063D01*
X457207Y270297D01*
X457568Y269952D01*
X458085Y269722D01*
X458550Y269645D01*
Y271255D01*
G01X457930Y272707D02*
X458292Y272937D01*
X458498Y273243D01*
X458550Y273588D01*
X458498Y273895D01*
X458240Y274202D01*
X457930Y274393D01*
X457620Y274432D01*
X457258Y274355D01*
X457000Y274087D01*
X456897Y273818D01*
Y273473D01*
G01Y273818D02*
X456742Y274048D01*
X456483Y274240D01*
X456173Y274317D01*
X455863Y274240D01*
X455605Y274048D01*
X455450Y273703D01*
X455502Y273358D01*
X455708Y273013D01*
G01X455967Y275922D02*
X455657Y276152D01*
X455502Y276420D01*
X455450Y276727D01*
X455553Y277110D01*
X455812Y277378D01*
X456122Y277455D01*
X456432Y277417D01*
X456690Y277263D01*
X457207Y276497D01*
X457568Y276152D01*
X458085Y275922D01*
X458550Y275845D01*
Y277455D01*
G01X462550Y251583D02*
X459450D01*
Y252542D01*
X459605Y252848D01*
X459812Y253040D01*
X460225Y253117D01*
X460638Y253040D01*
X460897Y252810D01*
X461052Y252542D01*
Y251583D01*
G01Y252542D02*
X462550Y253117D01*
G01Y255910D02*
X459450D01*
X461672Y254492D01*
Y256408D01*
G01X461930Y257707D02*
X462292Y257937D01*
X462498Y258243D01*
X462550Y258588D01*
X462498Y258895D01*
X462240Y259202D01*
X461930Y259393D01*
X461620Y259432D01*
X461258Y259355D01*
X461000Y259087D01*
X460897Y258818D01*
Y258473D01*
G01Y258818D02*
X460742Y259048D01*
X460483Y259240D01*
X460173Y259317D01*
X459863Y259240D01*
X459605Y259048D01*
X459450Y258703D01*
X459502Y258358D01*
X459708Y258013D01*
G01X462085Y260807D02*
X462343Y261037D01*
X462498Y261305D01*
X462550Y261650D01*
X462447Y261995D01*
X462240Y262263D01*
X461878Y262455D01*
X461465Y262493D01*
X461052Y262417D01*
X460793Y262225D01*
X460587Y261957D01*
X460535Y261688D01*
X460587Y261420D01*
X460793Y261075D01*
X459450Y261190D01*
Y262225D01*
G01X451050Y251583D02*
X447950D01*
Y252542D01*
X448105Y252848D01*
X448312Y253040D01*
X448725Y253117D01*
X449138Y253040D01*
X449397Y252810D01*
X449552Y252542D01*
Y251583D01*
G01Y252542D02*
X451050Y253117D01*
G01X448467Y254722D02*
X448157Y254952D01*
X448002Y255220D01*
X447950Y255527D01*
X448053Y255910D01*
X448312Y256178D01*
X448622Y256255D01*
X448932Y256217D01*
X449190Y256063D01*
X449707Y255297D01*
X450068Y254952D01*
X450585Y254722D01*
X451050Y254645D01*
Y256255D01*
G01X450430Y257707D02*
X450792Y257937D01*
X450998Y258243D01*
X451050Y258588D01*
X450998Y258895D01*
X450740Y259202D01*
X450430Y259393D01*
X450120Y259432D01*
X449758Y259355D01*
X449500Y259087D01*
X449397Y258818D01*
Y258473D01*
G01Y258818D02*
X449242Y259048D01*
X448983Y259240D01*
X448673Y259317D01*
X448363Y259240D01*
X448105Y259048D01*
X447950Y258703D01*
X448002Y258358D01*
X448208Y258013D01*
G01X451050Y262110D02*
X447950D01*
X450172Y260692D01*
Y262608D01*
G01X455550Y251583D02*
X452450D01*
Y252542D01*
X452605Y252848D01*
X452812Y253040D01*
X453225Y253117D01*
X453638Y253040D01*
X453897Y252810D01*
X454052Y252542D01*
Y251583D01*
G01Y252542D02*
X455550Y253117D01*
G01X454930Y254607D02*
X455292Y254837D01*
X455498Y255143D01*
X455550Y255488D01*
X455498Y255795D01*
X455240Y256102D01*
X454930Y256293D01*
X454620Y256332D01*
X454258Y256255D01*
X454000Y255987D01*
X453897Y255718D01*
Y255373D01*
G01Y255718D02*
X453742Y255948D01*
X453483Y256140D01*
X453173Y256217D01*
X452863Y256140D01*
X452605Y255948D01*
X452450Y255603D01*
X452502Y255258D01*
X452708Y254913D01*
G01X454930Y257707D02*
X455292Y257937D01*
X455498Y258243D01*
X455550Y258588D01*
X455498Y258895D01*
X455240Y259202D01*
X454930Y259393D01*
X454620Y259432D01*
X454258Y259355D01*
X454000Y259087D01*
X453897Y258818D01*
Y258473D01*
G01Y258818D02*
X453742Y259048D01*
X453483Y259240D01*
X453173Y259317D01*
X452863Y259240D01*
X452605Y259048D01*
X452450Y258703D01*
X452502Y258358D01*
X452708Y258013D01*
G01X455188Y260998D02*
X455447Y261267D01*
X455550Y261573D01*
X455447Y261880D01*
X455137Y262148D01*
X454672Y262340D01*
X454207Y262417D01*
X453638D01*
X453173Y262340D01*
X452760Y262148D01*
X452553Y261918D01*
X452450Y261650D01*
X452553Y261343D01*
X452760Y261113D01*
X453070Y260960D01*
X453483Y260883D01*
X453845Y260960D01*
X454207Y261152D01*
X454413Y261382D01*
X454465Y261650D01*
X454362Y261957D01*
X454103Y262187D01*
X453638Y262417D01*
G01X463693Y289292D02*
X463463Y289447D01*
X463195Y289550D01*
X462888D01*
X462543Y289395D01*
X462275Y289137D01*
X462083Y288827D01*
X461930Y288310D01*
X461892Y287845D01*
X461968Y287380D01*
X462083Y287070D01*
X462313Y286760D01*
X462582Y286553D01*
X462850Y286450D01*
X463118D01*
X463387Y286553D01*
X463617Y286708D01*
X463808Y286915D01*
G01X465222Y289033D02*
X465452Y289343D01*
X465720Y289498D01*
X466027Y289550D01*
X466410Y289447D01*
X466678Y289188D01*
X466755Y288878D01*
X466717Y288568D01*
X466563Y288310D01*
X465797Y287793D01*
X465452Y287432D01*
X465222Y286915D01*
X465145Y286450D01*
X466755D01*
G01X468207Y287070D02*
X468437Y286708D01*
X468743Y286502D01*
X469088Y286450D01*
X469395Y286502D01*
X469702Y286760D01*
X469893Y287070D01*
X469932Y287380D01*
X469855Y287742D01*
X469587Y288000D01*
X469318Y288103D01*
X468973D01*
G01X469318D02*
X469548Y288258D01*
X469740Y288517D01*
X469817Y288827D01*
X469740Y289137D01*
X469548Y289395D01*
X469203Y289550D01*
X468858Y289498D01*
X468513Y289292D01*
G01X471307Y286915D02*
X471537Y286657D01*
X471805Y286502D01*
X472150Y286450D01*
X472495Y286553D01*
X472763Y286760D01*
X472955Y287122D01*
X472993Y287535D01*
X472917Y287948D01*
X472725Y288207D01*
X472457Y288413D01*
X472188Y288465D01*
X471920Y288413D01*
X471575Y288207D01*
X471690Y289550D01*
X472725D01*
G01X462583Y282450D02*
Y285550D01*
X463542D01*
X463848Y285395D01*
X464040Y285188D01*
X464117Y284775D01*
X464040Y284362D01*
X463810Y284103D01*
X463542Y283948D01*
X462583D01*
G01X463542D02*
X464117Y282450D01*
G01X465722Y285033D02*
X465952Y285343D01*
X466220Y285498D01*
X466527Y285550D01*
X466910Y285447D01*
X467178Y285188D01*
X467255Y284878D01*
X467217Y284568D01*
X467063Y284310D01*
X466297Y283793D01*
X465952Y283432D01*
X465722Y282915D01*
X465645Y282450D01*
X467255D01*
G01X468707Y283070D02*
X468937Y282708D01*
X469243Y282502D01*
X469588Y282450D01*
X469895Y282502D01*
X470202Y282760D01*
X470393Y283070D01*
X470432Y283380D01*
X470355Y283742D01*
X470087Y284000D01*
X469818Y284103D01*
X469473D01*
G01X469818D02*
X470048Y284258D01*
X470240Y284517D01*
X470317Y284827D01*
X470240Y285137D01*
X470048Y285395D01*
X469703Y285550D01*
X469358Y285498D01*
X469013Y285292D01*
G01X472573Y282450D02*
X472650Y283122D01*
X472765Y283690D01*
X472918Y284207D01*
X473110Y284775D01*
X473417Y285550D01*
X471883D01*
G01X463693Y294292D02*
X463463Y294447D01*
X463195Y294550D01*
X462888D01*
X462543Y294395D01*
X462275Y294137D01*
X462083Y293827D01*
X461930Y293310D01*
X461892Y292845D01*
X461968Y292380D01*
X462083Y292070D01*
X462313Y291760D01*
X462582Y291553D01*
X462850Y291450D01*
X463118D01*
X463387Y291553D01*
X463617Y291708D01*
X463808Y291915D01*
G01X465222Y294033D02*
X465452Y294343D01*
X465720Y294498D01*
X466027Y294550D01*
X466410Y294447D01*
X466678Y294188D01*
X466755Y293878D01*
X466717Y293568D01*
X466563Y293310D01*
X465797Y292793D01*
X465452Y292432D01*
X465222Y291915D01*
X465145Y291450D01*
X466755D01*
G01X468207Y292070D02*
X468437Y291708D01*
X468743Y291502D01*
X469088Y291450D01*
X469395Y291502D01*
X469702Y291760D01*
X469893Y292070D01*
X469932Y292380D01*
X469855Y292742D01*
X469587Y293000D01*
X469318Y293103D01*
X468973D01*
G01X469318D02*
X469548Y293258D01*
X469740Y293517D01*
X469817Y293827D01*
X469740Y294137D01*
X469548Y294395D01*
X469203Y294550D01*
X468858Y294498D01*
X468513Y294292D01*
G01X471422Y292742D02*
X471690Y293103D01*
X471920Y293310D01*
X472227Y293413D01*
X472495Y293310D01*
X472687Y293103D01*
X472840Y292793D01*
X472878Y292432D01*
X472840Y292122D01*
X472687Y291812D01*
X472457Y291553D01*
X472188Y291450D01*
X471882Y291553D01*
X471613Y291863D01*
X471460Y292328D01*
X471422Y292845D01*
X471498Y293517D01*
X471613Y293878D01*
X471805Y294240D01*
X472073Y294498D01*
X472342Y294550D01*
X472610Y294447D01*
X472802Y294188D01*
G01X462583Y299950D02*
Y303050D01*
X463542D01*
X463848Y302895D01*
X464040Y302688D01*
X464117Y302275D01*
X464040Y301862D01*
X463810Y301603D01*
X463542Y301448D01*
X462583D01*
G01X463542D02*
X464117Y299950D01*
G01X466450D02*
Y303050D01*
X465990Y302430D01*
G01Y299950D02*
X466910D01*
G01X470010D02*
Y303050D01*
X468592Y300828D01*
X470508D01*
G01X471807Y300570D02*
X472037Y300208D01*
X472343Y300002D01*
X472688Y299950D01*
X472995Y300002D01*
X473302Y300260D01*
X473493Y300570D01*
X473532Y300880D01*
X473455Y301242D01*
X473187Y301500D01*
X472918Y301603D01*
X472573D01*
G01X472918D02*
X473148Y301758D01*
X473340Y302017D01*
X473417Y302327D01*
X473340Y302637D01*
X473148Y302895D01*
X472803Y303050D01*
X472458Y302998D01*
X472113Y302792D01*
G01X447493Y292292D02*
X447680Y292583D01*
X447840Y292750D01*
X448053Y292833D01*
X448240Y292750D01*
X448373Y292583D01*
X448480Y292333D01*
X448507Y292042D01*
X448480Y291792D01*
X448373Y291542D01*
X448213Y291333D01*
X448027Y291250D01*
X447813Y291333D01*
X447627Y291583D01*
X447520Y291958D01*
X447493Y292375D01*
X447547Y292917D01*
X447627Y293208D01*
X447760Y293500D01*
X447947Y293708D01*
X448133Y293750D01*
X448320Y293667D01*
X448453Y293458D01*
G01X449583Y315950D02*
Y319050D01*
X450542D01*
X450848Y318895D01*
X451040Y318688D01*
X451117Y318275D01*
X451040Y317862D01*
X450810Y317603D01*
X450542Y317448D01*
X449583D01*
G01X450542D02*
X451117Y315950D01*
G01X453910D02*
Y319050D01*
X452492Y316828D01*
X454408D01*
G01X455707Y316415D02*
X455937Y316157D01*
X456205Y316002D01*
X456550Y315950D01*
X456895Y316053D01*
X457163Y316260D01*
X457355Y316622D01*
X457393Y317035D01*
X457317Y317448D01*
X457125Y317707D01*
X456857Y317913D01*
X456588Y317965D01*
X456320Y317913D01*
X455975Y317707D01*
X456090Y319050D01*
X457125D01*
G01X458998Y316312D02*
X459267Y316053D01*
X459573Y315950D01*
X459880Y316053D01*
X460148Y316363D01*
X460340Y316828D01*
X460417Y317293D01*
Y317862D01*
X460340Y318327D01*
X460148Y318740D01*
X459918Y318947D01*
X459650Y319050D01*
X459343Y318947D01*
X459113Y318740D01*
X458960Y318430D01*
X458883Y318017D01*
X458960Y317655D01*
X459152Y317293D01*
X459382Y317087D01*
X459650Y317035D01*
X459957Y317138D01*
X460187Y317397D01*
X460417Y317862D01*
G01X446347Y305392D02*
X446533Y305183D01*
X446747Y305100D01*
X446960Y305183D01*
X447147Y305433D01*
X447280Y305808D01*
X447333Y306183D01*
Y306642D01*
X447280Y307017D01*
X447147Y307350D01*
X446987Y307517D01*
X446800Y307600D01*
X446587Y307517D01*
X446427Y307350D01*
X446320Y307100D01*
X446267Y306767D01*
X446320Y306475D01*
X446453Y306183D01*
X446613Y306017D01*
X446800Y305975D01*
X447013Y306058D01*
X447173Y306267D01*
X447333Y306642D01*
G01X454743Y332792D02*
X454513Y332947D01*
X454245Y333050D01*
X453938D01*
X453593Y332895D01*
X453325Y332637D01*
X453133Y332327D01*
X452980Y331810D01*
X452942Y331345D01*
X453018Y330880D01*
X453133Y330570D01*
X453363Y330260D01*
X453632Y330053D01*
X453900Y329950D01*
X454168D01*
X454437Y330053D01*
X454667Y330208D01*
X454858Y330415D01*
G01X456348Y330312D02*
X456617Y330053D01*
X456923Y329950D01*
X457230Y330053D01*
X457498Y330363D01*
X457690Y330828D01*
X457767Y331293D01*
Y331862D01*
X457690Y332327D01*
X457498Y332740D01*
X457268Y332947D01*
X457000Y333050D01*
X456693Y332947D01*
X456463Y332740D01*
X456310Y332430D01*
X456233Y332017D01*
X456310Y331655D01*
X456502Y331293D01*
X456732Y331087D01*
X457000Y331035D01*
X457307Y331138D01*
X457537Y331397D01*
X457767Y331862D01*
G01X460023Y329950D02*
X460100Y330622D01*
X460215Y331190D01*
X460368Y331707D01*
X460560Y332275D01*
X460867Y333050D01*
X459333D01*
G01X460350Y352050D02*
Y348950D01*
G01X459468Y352050D02*
X461232D01*
G01X462683Y348950D02*
Y352050D01*
X463603D01*
X463910Y351895D01*
X464140Y351533D01*
X464217Y351120D01*
X464140Y350707D01*
X463948Y350397D01*
X463603Y350242D01*
X462683D01*
G01X466550Y348950D02*
Y352050D01*
X466090Y351430D01*
G01Y348950D02*
X467010D01*
G01X468807Y349415D02*
X469037Y349157D01*
X469305Y349002D01*
X469650Y348950D01*
X469995Y349053D01*
X470263Y349260D01*
X470455Y349622D01*
X470493Y350035D01*
X470417Y350448D01*
X470225Y350707D01*
X469957Y350913D01*
X469688Y350965D01*
X469420Y350913D01*
X469075Y350707D01*
X469190Y352050D01*
X470225D01*
G01X449272Y348033D02*
X449502Y348343D01*
X449770Y348498D01*
X450077Y348550D01*
X450460Y348447D01*
X450728Y348188D01*
X450805Y347878D01*
X450767Y347568D01*
X450613Y347310D01*
X449847Y346793D01*
X449502Y346432D01*
X449272Y345915D01*
X449195Y345450D01*
X450805D01*
G01X452450Y356450D02*
X452143Y356502D01*
X451875Y356708D01*
X451645Y357018D01*
X451492Y357380D01*
X451415Y357793D01*
Y358207D01*
X451492Y358620D01*
X451645Y358982D01*
X451875Y359292D01*
X452143Y359498D01*
X452450Y359550D01*
X452757Y359498D01*
X453025Y359292D01*
X453255Y358982D01*
X453408Y358620D01*
X453485Y358207D01*
Y357793D01*
X453408Y357380D01*
X453255Y357018D01*
X453025Y356708D01*
X452757Y356502D01*
X452450Y356450D01*
G01X452757Y357277D02*
X453217Y356450D01*
G01X455550D02*
Y359550D01*
X455090Y358930D01*
G01Y356450D02*
X456010D01*
G01X447583Y372950D02*
Y376050D01*
X448542D01*
X448848Y375895D01*
X449040Y375688D01*
X449117Y375275D01*
X449040Y374862D01*
X448810Y374603D01*
X448542Y374448D01*
X447583D01*
G01X448542D02*
X449117Y372950D01*
G01X451910D02*
Y376050D01*
X450492Y373828D01*
X452408D01*
G01X453707Y373415D02*
X453937Y373157D01*
X454205Y373002D01*
X454550Y372950D01*
X454895Y373053D01*
X455163Y373260D01*
X455355Y373622D01*
X455393Y374035D01*
X455317Y374448D01*
X455125Y374707D01*
X454857Y374913D01*
X454588Y374965D01*
X454320Y374913D01*
X453975Y374707D01*
X454090Y376050D01*
X455125D01*
G01X456807Y373570D02*
X457037Y373208D01*
X457343Y373002D01*
X457688Y372950D01*
X457995Y373002D01*
X458302Y373260D01*
X458493Y373570D01*
X458532Y373880D01*
X458455Y374242D01*
X458187Y374500D01*
X457918Y374603D01*
X457573D01*
G01X457918D02*
X458148Y374758D01*
X458340Y375017D01*
X458417Y375327D01*
X458340Y375637D01*
X458148Y375895D01*
X457803Y376050D01*
X457458Y375998D01*
X457113Y375792D01*
G01X447583Y368950D02*
Y372050D01*
X448542D01*
X448848Y371895D01*
X449040Y371688D01*
X449117Y371275D01*
X449040Y370862D01*
X448810Y370603D01*
X448542Y370448D01*
X447583D01*
G01X448542D02*
X449117Y368950D01*
G01X451910D02*
Y372050D01*
X450492Y369828D01*
X452408D01*
G01X453707Y369415D02*
X453937Y369157D01*
X454205Y369002D01*
X454550Y368950D01*
X454895Y369053D01*
X455163Y369260D01*
X455355Y369622D01*
X455393Y370035D01*
X455317Y370448D01*
X455125Y370707D01*
X454857Y370913D01*
X454588Y370965D01*
X454320Y370913D01*
X453975Y370707D01*
X454090Y372050D01*
X455125D01*
G01X456922Y371533D02*
X457152Y371843D01*
X457420Y371998D01*
X457727Y372050D01*
X458110Y371947D01*
X458378Y371688D01*
X458455Y371378D01*
X458417Y371068D01*
X458263Y370810D01*
X457497Y370293D01*
X457152Y369932D01*
X456922Y369415D01*
X456845Y368950D01*
X458455D01*
G01X449243Y379792D02*
X449013Y379947D01*
X448745Y380050D01*
X448438D01*
X448093Y379895D01*
X447825Y379637D01*
X447633Y379327D01*
X447480Y378810D01*
X447442Y378345D01*
X447518Y377880D01*
X447633Y377570D01*
X447863Y377260D01*
X448132Y377053D01*
X448400Y376950D01*
X448668D01*
X448937Y377053D01*
X449167Y377208D01*
X449358Y377415D01*
G01X451500Y376950D02*
X451768Y377002D01*
X452075Y377157D01*
X452267Y377415D01*
X452343Y377777D01*
X452267Y378138D01*
X452037Y378448D01*
X451692Y378603D01*
X451308D01*
X451078Y378707D01*
X450887Y378965D01*
X450810Y379327D01*
X450925Y379688D01*
X451193Y379947D01*
X451500Y380050D01*
X451807Y379947D01*
X452075Y379688D01*
X452190Y379327D01*
X452113Y378965D01*
X451922Y378707D01*
X451692Y378603D01*
X451308D01*
X450963Y378448D01*
X450733Y378138D01*
X450657Y377777D01*
X450733Y377415D01*
X450925Y377157D01*
X451232Y377002D01*
X451500Y376950D01*
G01X453948Y377312D02*
X454217Y377053D01*
X454523Y376950D01*
X454830Y377053D01*
X455098Y377363D01*
X455290Y377828D01*
X455367Y378293D01*
Y378862D01*
X455290Y379327D01*
X455098Y379740D01*
X454868Y379947D01*
X454600Y380050D01*
X454293Y379947D01*
X454063Y379740D01*
X453910Y379430D01*
X453833Y379017D01*
X453910Y378655D01*
X454102Y378293D01*
X454332Y378087D01*
X454600Y378035D01*
X454907Y378138D01*
X455137Y378397D01*
X455367Y378862D01*
G01X458633Y382050D02*
Y378950D01*
X460167D01*
G01X462500D02*
Y382050D01*
X462040Y381430D01*
G01Y378950D02*
X462960D01*
G01X464872Y380242D02*
X465140Y380603D01*
X465370Y380810D01*
X465677Y380913D01*
X465945Y380810D01*
X466137Y380603D01*
X466290Y380293D01*
X466328Y379932D01*
X466290Y379622D01*
X466137Y379312D01*
X465907Y379053D01*
X465638Y378950D01*
X465332Y379053D01*
X465063Y379363D01*
X464910Y379828D01*
X464872Y380345D01*
X464948Y381017D01*
X465063Y381378D01*
X465255Y381740D01*
X465523Y381998D01*
X465792Y382050D01*
X466060Y381947D01*
X466252Y381688D01*
G01X460743Y400792D02*
X460513Y400947D01*
X460245Y401050D01*
X459938D01*
X459593Y400895D01*
X459325Y400637D01*
X459133Y400327D01*
X458980Y399810D01*
X458942Y399345D01*
X459018Y398880D01*
X459133Y398570D01*
X459363Y398260D01*
X459632Y398053D01*
X459900Y397950D01*
X460168D01*
X460437Y398053D01*
X460667Y398208D01*
X460858Y398415D01*
G01X462923Y397950D02*
X463000Y398622D01*
X463115Y399190D01*
X463268Y399707D01*
X463460Y400275D01*
X463767Y401050D01*
X462233D01*
G01X465448Y398312D02*
X465717Y398053D01*
X466023Y397950D01*
X466330Y398053D01*
X466598Y398363D01*
X466790Y398828D01*
X466867Y399293D01*
Y399862D01*
X466790Y400327D01*
X466598Y400740D01*
X466368Y400947D01*
X466100Y401050D01*
X465793Y400947D01*
X465563Y400740D01*
X465410Y400430D01*
X465333Y400017D01*
X465410Y399655D01*
X465602Y399293D01*
X465832Y399087D01*
X466100Y399035D01*
X466407Y399138D01*
X466637Y399397D01*
X466867Y399862D01*
G01X465583Y72450D02*
Y75550D01*
X466542D01*
X466848Y75395D01*
X467040Y75188D01*
X467117Y74775D01*
X467040Y74362D01*
X466810Y74103D01*
X466542Y73948D01*
X465583D01*
G01X466542D02*
X467117Y72450D01*
G01X469910D02*
Y75550D01*
X468492Y73328D01*
X470408D01*
G01X472473Y72450D02*
X472550Y73122D01*
X472665Y73690D01*
X472818Y74207D01*
X473010Y74775D01*
X473317Y75550D01*
X471783D01*
G01X474807Y72915D02*
X475037Y72657D01*
X475305Y72502D01*
X475650Y72450D01*
X475995Y72553D01*
X476263Y72760D01*
X476455Y73122D01*
X476493Y73535D01*
X476417Y73948D01*
X476225Y74207D01*
X475957Y74413D01*
X475688Y74465D01*
X475420Y74413D01*
X475075Y74207D01*
X475190Y75550D01*
X476225D01*
G01X474250Y100100D02*
X476750D01*
G01X474250Y99487D02*
Y100713D01*
G01X476750Y101767D02*
X474250D01*
Y102407D01*
X474375Y102620D01*
X474667Y102780D01*
X475000Y102833D01*
X475333Y102780D01*
X475583Y102647D01*
X475708Y102407D01*
Y101767D01*
G01X474667Y103993D02*
X474417Y104153D01*
X474292Y104340D01*
X474250Y104553D01*
X474333Y104820D01*
X474542Y105007D01*
X474792Y105060D01*
X475042Y105033D01*
X475250Y104927D01*
X475667Y104393D01*
X475958Y104153D01*
X476375Y103993D01*
X476750Y103940D01*
Y105060D01*
G01X474250Y106700D02*
X474333Y106487D01*
X474542Y106327D01*
X474792Y106220D01*
X475125Y106140D01*
X475500Y106113D01*
X475875Y106140D01*
X476208Y106220D01*
X476458Y106327D01*
X476667Y106487D01*
X476750Y106700D01*
X476667Y106913D01*
X476458Y107073D01*
X476208Y107180D01*
X475875Y107260D01*
X475500Y107287D01*
X475125Y107260D01*
X474792Y107180D01*
X474542Y107073D01*
X474333Y106913D01*
X474250Y106700D01*
G01X476250Y108313D02*
X476542Y108473D01*
X476708Y108687D01*
X476750Y108927D01*
X476708Y109140D01*
X476500Y109353D01*
X476250Y109487D01*
X476000Y109513D01*
X475708Y109460D01*
X475500Y109273D01*
X475417Y109087D01*
Y108847D01*
G01Y109087D02*
X475292Y109247D01*
X475083Y109380D01*
X474833Y109433D01*
X474583Y109380D01*
X474375Y109247D01*
X474250Y109007D01*
X474292Y108767D01*
X474458Y108527D01*
G01X470250Y100100D02*
X472750D01*
G01X470250Y99487D02*
Y100713D01*
G01X472750Y101767D02*
X470250D01*
Y102407D01*
X470375Y102620D01*
X470667Y102780D01*
X471000Y102833D01*
X471333Y102780D01*
X471583Y102647D01*
X471708Y102407D01*
Y101767D01*
G01X470667Y103993D02*
X470417Y104153D01*
X470292Y104340D01*
X470250Y104553D01*
X470333Y104820D01*
X470542Y105007D01*
X470792Y105060D01*
X471042Y105033D01*
X471250Y104927D01*
X471667Y104393D01*
X471958Y104153D01*
X472375Y103993D01*
X472750Y103940D01*
Y105060D01*
G01X470250Y106700D02*
X470333Y106487D01*
X470542Y106327D01*
X470792Y106220D01*
X471125Y106140D01*
X471500Y106113D01*
X471875Y106140D01*
X472208Y106220D01*
X472458Y106327D01*
X472667Y106487D01*
X472750Y106700D01*
X472667Y106913D01*
X472458Y107073D01*
X472208Y107180D01*
X471875Y107260D01*
X471500Y107287D01*
X471125Y107260D01*
X470792Y107180D01*
X470542Y107073D01*
X470333Y106913D01*
X470250Y106700D01*
G01X470667Y108393D02*
X470417Y108553D01*
X470292Y108740D01*
X470250Y108953D01*
X470333Y109220D01*
X470542Y109407D01*
X470792Y109460D01*
X471042Y109433D01*
X471250Y109327D01*
X471667Y108793D01*
X471958Y108553D01*
X472375Y108393D01*
X472750Y108340D01*
Y109460D01*
G01X481100Y106250D02*
Y103750D01*
G01X480487Y106250D02*
X481713D01*
G01X482767Y103750D02*
Y106250D01*
X483407D01*
X483620Y106125D01*
X483780Y105833D01*
X483833Y105500D01*
X483780Y105167D01*
X483647Y104917D01*
X483407Y104792D01*
X482767D01*
G01X485500Y103750D02*
Y106250D01*
X485180Y105750D01*
G01Y103750D02*
X485820D01*
G01X487247Y104042D02*
X487433Y103833D01*
X487647Y103750D01*
X487860Y103833D01*
X488047Y104083D01*
X488180Y104458D01*
X488233Y104833D01*
Y105292D01*
X488180Y105667D01*
X488047Y106000D01*
X487887Y106167D01*
X487700Y106250D01*
X487487Y106167D01*
X487327Y106000D01*
X487220Y105750D01*
X487167Y105417D01*
X487220Y105125D01*
X487353Y104833D01*
X487513Y104667D01*
X487700Y104625D01*
X487913Y104708D01*
X488073Y104917D01*
X488233Y105292D01*
G01X490220Y103750D02*
Y106250D01*
X489233Y104458D01*
X490567D01*
G01X479500Y100450D02*
Y97950D01*
G01X478887Y100450D02*
X480113D01*
G01X481167Y97950D02*
Y100450D01*
X481807D01*
X482020Y100325D01*
X482180Y100033D01*
X482233Y99700D01*
X482180Y99367D01*
X482047Y99117D01*
X481807Y98992D01*
X481167D01*
G01X483900Y97950D02*
Y100450D01*
X483580Y99950D01*
G01Y97950D02*
X484220D01*
G01X485593Y100033D02*
X485753Y100283D01*
X485940Y100408D01*
X486153Y100450D01*
X486420Y100367D01*
X486607Y100158D01*
X486660Y99908D01*
X486633Y99658D01*
X486527Y99450D01*
X485993Y99033D01*
X485753Y98742D01*
X485593Y98325D01*
X485540Y97950D01*
X486660D01*
G01X468533Y121242D02*
X465433Y122200D01*
X468533Y123158D01*
G01X467448Y122813D02*
Y121587D01*
G01X468533Y124342D02*
X465433Y125300D01*
X468533Y126258D01*
G01X467448Y125913D02*
Y124687D01*
G01X473523Y121913D02*
X471023Y122580D01*
X473523Y123247D01*
G01X472648Y123007D02*
Y122153D01*
G01X472190Y124993D02*
X472065Y125100D01*
X471856Y125180D01*
X471565Y125233D01*
X471315Y125180D01*
X471148Y125073D01*
X471023Y124887D01*
Y124167D01*
X473523D01*
Y125047D01*
X473356Y125233D01*
X473106Y125340D01*
X472815Y125393D01*
X472523Y125340D01*
X472273Y125180D01*
X472190Y124993D01*
Y124167D01*
G01X481100Y121250D02*
Y118750D01*
G01X480487Y121250D02*
X481713D01*
G01X482767Y118750D02*
Y121250D01*
X483407D01*
X483620Y121125D01*
X483780Y120833D01*
X483833Y120500D01*
X483780Y120167D01*
X483647Y119917D01*
X483407Y119792D01*
X482767D01*
G01X484993Y120833D02*
X485153Y121083D01*
X485340Y121208D01*
X485553Y121250D01*
X485820Y121167D01*
X486007Y120958D01*
X486060Y120708D01*
X486033Y120458D01*
X485927Y120250D01*
X485393Y119833D01*
X485153Y119542D01*
X484993Y119125D01*
X484940Y118750D01*
X486060D01*
G01X487700Y121250D02*
X487487Y121167D01*
X487327Y120958D01*
X487220Y120708D01*
X487140Y120375D01*
X487113Y120000D01*
X487140Y119625D01*
X487220Y119292D01*
X487327Y119042D01*
X487487Y118833D01*
X487700Y118750D01*
X487913Y118833D01*
X488073Y119042D01*
X488180Y119292D01*
X488260Y119625D01*
X488287Y120000D01*
X488260Y120375D01*
X488180Y120708D01*
X488073Y120958D01*
X487913Y121167D01*
X487700Y121250D01*
G01X489900Y118750D02*
Y121250D01*
X489580Y120750D01*
G01Y118750D02*
X490220D01*
G01X477600Y116750D02*
Y114250D01*
G01X476987Y116750D02*
X478213D01*
G01X479267Y114250D02*
Y116750D01*
X479907D01*
X480120Y116625D01*
X480280Y116333D01*
X480333Y116000D01*
X480280Y115667D01*
X480147Y115417D01*
X479907Y115292D01*
X479267D01*
G01X482000Y114250D02*
Y116750D01*
X481680Y116250D01*
G01Y114250D02*
X482320D01*
G01X483747Y114542D02*
X483933Y114333D01*
X484147Y114250D01*
X484360Y114333D01*
X484547Y114583D01*
X484680Y114958D01*
X484733Y115333D01*
Y115792D01*
X484680Y116167D01*
X484547Y116500D01*
X484387Y116667D01*
X484200Y116750D01*
X483987Y116667D01*
X483827Y116500D01*
X483720Y116250D01*
X483667Y115917D01*
X483720Y115625D01*
X483853Y115333D01*
X484013Y115167D01*
X484200Y115125D01*
X484413Y115208D01*
X484573Y115417D01*
X484733Y115792D01*
G01X485813Y114750D02*
X485973Y114458D01*
X486187Y114292D01*
X486427Y114250D01*
X486640Y114292D01*
X486853Y114500D01*
X486987Y114750D01*
X487013Y115000D01*
X486960Y115292D01*
X486773Y115500D01*
X486587Y115583D01*
X486347D01*
G01X486587D02*
X486747Y115708D01*
X486880Y115917D01*
X486933Y116167D01*
X486880Y116417D01*
X486747Y116625D01*
X486507Y116750D01*
X486267Y116708D01*
X486027Y116542D01*
G01X480750Y151600D02*
X483250D01*
G01X480750Y150987D02*
Y152213D01*
G01X483250Y153267D02*
X480750D01*
Y153907D01*
X480875Y154120D01*
X481167Y154280D01*
X481500Y154333D01*
X481833Y154280D01*
X482083Y154147D01*
X482208Y153907D01*
Y153267D01*
G01X483250Y156000D02*
X480750D01*
X481250Y155680D01*
G01X483250D02*
Y156320D01*
G01X482750Y157613D02*
X483042Y157773D01*
X483208Y157987D01*
X483250Y158227D01*
X483208Y158440D01*
X483000Y158653D01*
X482750Y158787D01*
X482500Y158813D01*
X482208Y158760D01*
X482000Y158573D01*
X481917Y158387D01*
Y158147D01*
G01Y158387D02*
X481792Y158547D01*
X481583Y158680D01*
X481333Y158733D01*
X481083Y158680D01*
X480875Y158547D01*
X480750Y158307D01*
X480792Y158067D01*
X480958Y157827D01*
G01X482208Y159893D02*
X481917Y160080D01*
X481750Y160240D01*
X481667Y160453D01*
X481750Y160640D01*
X481917Y160773D01*
X482167Y160880D01*
X482458Y160907D01*
X482708Y160880D01*
X482958Y160773D01*
X483167Y160613D01*
X483250Y160427D01*
X483167Y160213D01*
X482917Y160027D01*
X482542Y159920D01*
X482125Y159893D01*
X481583Y159947D01*
X481292Y160027D01*
X481000Y160160D01*
X480792Y160347D01*
X480750Y160533D01*
X480833Y160720D01*
X481042Y160853D01*
G01X479950Y216850D02*
X483050D01*
G01X479950Y215968D02*
Y217732D01*
G01X483050Y219183D02*
X479950D01*
Y220103D01*
X480105Y220410D01*
X480467Y220640D01*
X480880Y220717D01*
X481293Y220640D01*
X481603Y220448D01*
X481758Y220103D01*
Y219183D01*
G01X483050Y223510D02*
X479950D01*
X482172Y222092D01*
Y224008D01*
G01X482585Y225307D02*
X482843Y225537D01*
X482998Y225805D01*
X483050Y226150D01*
X482947Y226495D01*
X482740Y226763D01*
X482378Y226955D01*
X481965Y226993D01*
X481552Y226917D01*
X481293Y226725D01*
X481087Y226457D01*
X481035Y226188D01*
X481087Y225920D01*
X481293Y225575D01*
X479950Y225690D01*
Y226725D01*
G01X471550Y226083D02*
X468450D01*
Y227042D01*
X468605Y227348D01*
X468812Y227540D01*
X469225Y227617D01*
X469638Y227540D01*
X469897Y227310D01*
X470052Y227042D01*
Y226083D01*
G01Y227042D02*
X471550Y227617D01*
G01X470930Y229107D02*
X471292Y229337D01*
X471498Y229643D01*
X471550Y229988D01*
X471498Y230295D01*
X471240Y230602D01*
X470930Y230793D01*
X470620Y230832D01*
X470258Y230755D01*
X470000Y230487D01*
X469897Y230218D01*
Y229873D01*
G01Y230218D02*
X469742Y230448D01*
X469483Y230640D01*
X469173Y230717D01*
X468863Y230640D01*
X468605Y230448D01*
X468450Y230103D01*
X468502Y229758D01*
X468708Y229413D01*
G01X470258Y232322D02*
X469897Y232590D01*
X469690Y232820D01*
X469587Y233127D01*
X469690Y233395D01*
X469897Y233587D01*
X470207Y233740D01*
X470568Y233778D01*
X470878Y233740D01*
X471188Y233587D01*
X471447Y233357D01*
X471550Y233088D01*
X471447Y232782D01*
X471137Y232513D01*
X470672Y232360D01*
X470155Y232322D01*
X469483Y232398D01*
X469122Y232513D01*
X468760Y232705D01*
X468502Y232973D01*
X468450Y233242D01*
X468553Y233510D01*
X468812Y233702D01*
G01X468967Y235422D02*
X468657Y235652D01*
X468502Y235920D01*
X468450Y236227D01*
X468553Y236610D01*
X468812Y236878D01*
X469122Y236955D01*
X469432Y236917D01*
X469690Y236763D01*
X470207Y235997D01*
X470568Y235652D01*
X471085Y235422D01*
X471550Y235345D01*
Y236955D01*
G01X466550Y251583D02*
X463450D01*
Y252542D01*
X463605Y252848D01*
X463812Y253040D01*
X464225Y253117D01*
X464638Y253040D01*
X464897Y252810D01*
X465052Y252542D01*
Y251583D01*
G01Y252542D02*
X466550Y253117D01*
G01X465930Y254607D02*
X466292Y254837D01*
X466498Y255143D01*
X466550Y255488D01*
X466498Y255795D01*
X466240Y256102D01*
X465930Y256293D01*
X465620Y256332D01*
X465258Y256255D01*
X465000Y255987D01*
X464897Y255718D01*
Y255373D01*
G01Y255718D02*
X464742Y255948D01*
X464483Y256140D01*
X464173Y256217D01*
X463863Y256140D01*
X463605Y255948D01*
X463450Y255603D01*
X463502Y255258D01*
X463708Y254913D01*
G01X466550Y259010D02*
X463450D01*
X465672Y257592D01*
Y259508D01*
G01X466550Y261650D02*
X466498Y261918D01*
X466343Y262225D01*
X466085Y262417D01*
X465723Y262493D01*
X465362Y262417D01*
X465052Y262187D01*
X464897Y261842D01*
Y261458D01*
X464793Y261228D01*
X464535Y261037D01*
X464173Y260960D01*
X463812Y261075D01*
X463553Y261343D01*
X463450Y261650D01*
X463553Y261957D01*
X463812Y262225D01*
X464173Y262340D01*
X464535Y262263D01*
X464793Y262072D01*
X464897Y261842D01*
Y261458D01*
X465052Y261113D01*
X465362Y260883D01*
X465723Y260807D01*
X466085Y260883D01*
X466343Y261075D01*
X466498Y261382D01*
X466550Y261650D01*
G01X473208Y260193D02*
X473053Y259963D01*
X472950Y259695D01*
Y259388D01*
X473105Y259043D01*
X473363Y258775D01*
X473673Y258583D01*
X474190Y258430D01*
X474655Y258392D01*
X475120Y258468D01*
X475430Y258583D01*
X475740Y258813D01*
X475947Y259082D01*
X476050Y259350D01*
Y259618D01*
X475947Y259887D01*
X475792Y260117D01*
X475585Y260308D01*
G01X476050Y262450D02*
X472950D01*
X473570Y261990D01*
G01X476050D02*
Y262910D01*
G01Y265473D02*
X475378Y265550D01*
X474810Y265665D01*
X474293Y265818D01*
X473725Y266010D01*
X472950Y266317D01*
Y264783D01*
G01X476050Y269110D02*
X472950D01*
X475172Y267692D01*
Y269608D01*
G01X476350Y280550D02*
Y277450D01*
G01X475468Y280550D02*
X477232D01*
G01X478683Y277450D02*
Y280550D01*
X479603D01*
X479910Y280395D01*
X480140Y280033D01*
X480217Y279620D01*
X480140Y279207D01*
X479948Y278897D01*
X479603Y278742D01*
X478683D01*
G01X483010Y277450D02*
Y280550D01*
X481592Y278328D01*
X483508D01*
G01X485650Y280550D02*
X485343Y280447D01*
X485113Y280188D01*
X484960Y279878D01*
X484845Y279465D01*
X484807Y279000D01*
X484845Y278535D01*
X484960Y278122D01*
X485113Y277812D01*
X485343Y277553D01*
X485650Y277450D01*
X485957Y277553D01*
X486187Y277812D01*
X486340Y278122D01*
X486455Y278535D01*
X486493Y279000D01*
X486455Y279465D01*
X486340Y279878D01*
X486187Y280188D01*
X485957Y280447D01*
X485650Y280550D01*
G01X474550Y333583D02*
X471450D01*
Y334542D01*
X471605Y334848D01*
X471812Y335040D01*
X472225Y335117D01*
X472638Y335040D01*
X472897Y334810D01*
X473052Y334542D01*
Y333583D01*
G01Y334542D02*
X474550Y335117D01*
G01Y337450D02*
X471450D01*
X472070Y336990D01*
G01X474550D02*
Y337910D01*
G01Y340550D02*
X471450D01*
X472070Y340090D01*
G01X474550D02*
Y341010D01*
G01Y344110D02*
X471450D01*
X473672Y342692D01*
Y344608D01*
G01X479050Y333583D02*
X475950D01*
Y334542D01*
X476105Y334848D01*
X476312Y335040D01*
X476725Y335117D01*
X477138Y335040D01*
X477397Y334810D01*
X477552Y334542D01*
Y333583D01*
G01Y334542D02*
X479050Y335117D01*
G01Y337450D02*
X475950D01*
X476570Y336990D01*
G01X479050D02*
Y337910D01*
G01Y340550D02*
X475950D01*
X476570Y340090D01*
G01X479050D02*
Y341010D01*
G01X477758Y342922D02*
X477397Y343190D01*
X477190Y343420D01*
X477087Y343727D01*
X477190Y343995D01*
X477397Y344187D01*
X477707Y344340D01*
X478068Y344378D01*
X478378Y344340D01*
X478688Y344187D01*
X478947Y343957D01*
X479050Y343688D01*
X478947Y343382D01*
X478637Y343113D01*
X478172Y342960D01*
X477655Y342922D01*
X476983Y342998D01*
X476622Y343113D01*
X476260Y343305D01*
X476002Y343573D01*
X475950Y343842D01*
X476053Y344110D01*
X476312Y344302D01*
G01X466683Y373950D02*
Y377050D01*
X467603D01*
X467910Y376895D01*
X468140Y376533D01*
X468217Y376120D01*
X468140Y375707D01*
X467948Y375397D01*
X467603Y375242D01*
X466683D01*
G01X469822Y376533D02*
X470052Y376843D01*
X470320Y376998D01*
X470627Y377050D01*
X471010Y376947D01*
X471278Y376688D01*
X471355Y376378D01*
X471317Y376068D01*
X471163Y375810D01*
X470397Y375293D01*
X470052Y374932D01*
X469822Y374415D01*
X469745Y373950D01*
X471355D01*
G01X469500Y364950D02*
X469768Y365002D01*
X470075Y365157D01*
X470267Y365415D01*
X470343Y365777D01*
X470267Y366138D01*
X470037Y366448D01*
X469692Y366603D01*
X469308D01*
X469078Y366707D01*
X468887Y366965D01*
X468810Y367327D01*
X468925Y367688D01*
X469193Y367947D01*
X469500Y368050D01*
X469807Y367947D01*
X470075Y367688D01*
X470190Y367327D01*
X470113Y366965D01*
X469922Y366707D01*
X469692Y366603D01*
X469308D01*
X468963Y366448D01*
X468733Y366138D01*
X468657Y365777D01*
X468733Y365415D01*
X468925Y365157D01*
X469232Y365002D01*
X469500Y364950D01*
G01X470272Y388533D02*
X470502Y388843D01*
X470770Y388998D01*
X471077Y389050D01*
X471460Y388947D01*
X471728Y388688D01*
X471805Y388378D01*
X471767Y388068D01*
X471613Y387810D01*
X470847Y387293D01*
X470502Y386932D01*
X470272Y386415D01*
X470195Y385950D01*
X471805D01*
G01X470903Y410950D02*
Y414050D01*
X471900Y411467D01*
X472897Y414050D01*
Y410950D01*
G01X475767D02*
X474233D01*
Y414050D01*
X475767D01*
G01X475153Y412552D02*
X474233D01*
G01X477257Y411570D02*
X477487Y411208D01*
X477793Y411002D01*
X478138Y410950D01*
X478445Y411002D01*
X478752Y411260D01*
X478943Y411570D01*
X478982Y411880D01*
X478905Y412242D01*
X478637Y412500D01*
X478368Y412603D01*
X478023D01*
G01X478368D02*
X478598Y412758D01*
X478790Y413017D01*
X478867Y413327D01*
X478790Y413637D01*
X478598Y413895D01*
X478253Y414050D01*
X477908Y413998D01*
X477563Y413792D01*
G01X482500Y73000D02*
X482768Y73052D01*
X483075Y73207D01*
X483267Y73465D01*
X483343Y73827D01*
X483267Y74188D01*
X483037Y74498D01*
X482692Y74653D01*
X482308D01*
X482078Y74757D01*
X481887Y75015D01*
X481810Y75377D01*
X481925Y75738D01*
X482193Y75997D01*
X482500Y76100D01*
X482807Y75997D01*
X483075Y75738D01*
X483190Y75377D01*
X483113Y75015D01*
X482922Y74757D01*
X482692Y74653D01*
X482308D01*
X481963Y74498D01*
X481733Y74188D01*
X481657Y73827D01*
X481733Y73465D01*
X481925Y73207D01*
X482232Y73052D01*
X482500Y73000D01*
G01X493057Y99050D02*
Y96828D01*
X493210Y96363D01*
X493517Y96053D01*
X493900Y95950D01*
X494283Y96053D01*
X494590Y96363D01*
X494743Y96828D01*
Y99050D01*
G01X496157Y96570D02*
X496387Y96208D01*
X496693Y96002D01*
X497038Y95950D01*
X497345Y96002D01*
X497652Y96260D01*
X497843Y96570D01*
X497882Y96880D01*
X497805Y97242D01*
X497537Y97500D01*
X497268Y97603D01*
X496923D01*
G01X497268D02*
X497498Y97758D01*
X497690Y98017D01*
X497767Y98327D01*
X497690Y98637D01*
X497498Y98895D01*
X497153Y99050D01*
X496808Y98998D01*
X496463Y98792D01*
G01X500023Y95950D02*
X500100Y96622D01*
X500215Y97190D01*
X500368Y97707D01*
X500560Y98275D01*
X500867Y99050D01*
X499333D01*
G01X492793Y120092D02*
X492563Y120247D01*
X492295Y120350D01*
X491988D01*
X491643Y120195D01*
X491375Y119937D01*
X491183Y119627D01*
X491030Y119110D01*
X490992Y118645D01*
X491068Y118180D01*
X491183Y117870D01*
X491413Y117560D01*
X491682Y117353D01*
X491950Y117250D01*
X492218D01*
X492487Y117353D01*
X492717Y117508D01*
X492908Y117715D01*
G01X494322Y119833D02*
X494552Y120143D01*
X494820Y120298D01*
X495127Y120350D01*
X495510Y120247D01*
X495778Y119988D01*
X495855Y119678D01*
X495817Y119368D01*
X495663Y119110D01*
X494897Y118593D01*
X494552Y118232D01*
X494322Y117715D01*
X494245Y117250D01*
X495855D01*
G01X497498Y117612D02*
X497767Y117353D01*
X498073Y117250D01*
X498380Y117353D01*
X498648Y117663D01*
X498840Y118128D01*
X498917Y118593D01*
Y119162D01*
X498840Y119627D01*
X498648Y120040D01*
X498418Y120247D01*
X498150Y120350D01*
X497843Y120247D01*
X497613Y120040D01*
X497460Y119730D01*
X497383Y119317D01*
X497460Y118955D01*
X497652Y118593D01*
X497882Y118387D01*
X498150Y118335D01*
X498457Y118438D01*
X498687Y118697D01*
X498917Y119162D01*
G01X500522Y119833D02*
X500752Y120143D01*
X501020Y120298D01*
X501327Y120350D01*
X501710Y120247D01*
X501978Y119988D01*
X502055Y119678D01*
X502017Y119368D01*
X501863Y119110D01*
X501097Y118593D01*
X500752Y118232D01*
X500522Y117715D01*
X500445Y117250D01*
X502055D01*
G01X487250Y129600D02*
X489750D01*
G01X487250Y128987D02*
Y130213D01*
G01X489750Y131267D02*
X487250D01*
Y131907D01*
X487375Y132120D01*
X487667Y132280D01*
X488000Y132333D01*
X488333Y132280D01*
X488583Y132147D01*
X488708Y131907D01*
Y131267D01*
G01X489750Y134000D02*
X487250D01*
X487750Y133680D01*
G01X489750D02*
Y134320D01*
G01X489458Y135747D02*
X489667Y135933D01*
X489750Y136147D01*
X489667Y136360D01*
X489417Y136547D01*
X489042Y136680D01*
X488667Y136733D01*
X488208D01*
X487833Y136680D01*
X487500Y136547D01*
X487333Y136387D01*
X487250Y136200D01*
X487333Y135987D01*
X487500Y135827D01*
X487750Y135720D01*
X488083Y135667D01*
X488375Y135720D01*
X488667Y135853D01*
X488833Y136013D01*
X488875Y136200D01*
X488792Y136413D01*
X488583Y136573D01*
X488208Y136733D01*
G01X489458Y137947D02*
X489667Y138133D01*
X489750Y138347D01*
X489667Y138560D01*
X489417Y138747D01*
X489042Y138880D01*
X488667Y138933D01*
X488208D01*
X487833Y138880D01*
X487500Y138747D01*
X487333Y138587D01*
X487250Y138400D01*
X487333Y138187D01*
X487500Y138027D01*
X487750Y137920D01*
X488083Y137867D01*
X488375Y137920D01*
X488667Y138053D01*
X488833Y138213D01*
X488875Y138400D01*
X488792Y138613D01*
X488583Y138773D01*
X488208Y138933D01*
G01X482250Y140600D02*
X484750D01*
G01X482250Y139987D02*
Y141213D01*
G01X484750Y142267D02*
X482250D01*
Y142907D01*
X482375Y143120D01*
X482667Y143280D01*
X483000Y143333D01*
X483333Y143280D01*
X483583Y143147D01*
X483708Y142907D01*
Y142267D01*
G01X484750Y145000D02*
X482250D01*
X482750Y144680D01*
G01X484750D02*
Y145320D01*
G01X484250Y146613D02*
X484542Y146773D01*
X484708Y146987D01*
X484750Y147227D01*
X484708Y147440D01*
X484500Y147653D01*
X484250Y147787D01*
X484000Y147813D01*
X483708Y147760D01*
X483500Y147573D01*
X483417Y147387D01*
Y147147D01*
G01Y147387D02*
X483292Y147547D01*
X483083Y147680D01*
X482833Y147733D01*
X482583Y147680D01*
X482375Y147547D01*
X482250Y147307D01*
X482292Y147067D01*
X482458Y146827D01*
G01X484458Y148947D02*
X484667Y149133D01*
X484750Y149347D01*
X484667Y149560D01*
X484417Y149747D01*
X484042Y149880D01*
X483667Y149933D01*
X483208D01*
X482833Y149880D01*
X482500Y149747D01*
X482333Y149587D01*
X482250Y149400D01*
X482333Y149187D01*
X482500Y149027D01*
X482750Y148920D01*
X483083Y148867D01*
X483375Y148920D01*
X483667Y149053D01*
X483833Y149213D01*
X483875Y149400D01*
X483792Y149613D01*
X483583Y149773D01*
X483208Y149933D01*
G01X487250Y151100D02*
X489750D01*
G01X487250Y150487D02*
Y151713D01*
G01X489750Y152767D02*
X487250D01*
Y153407D01*
X487375Y153620D01*
X487667Y153780D01*
X488000Y153833D01*
X488333Y153780D01*
X488583Y153647D01*
X488708Y153407D01*
Y152767D01*
G01X489750Y155500D02*
X487250D01*
X487750Y155180D01*
G01X489750D02*
Y155820D01*
G01X489250Y157113D02*
X489542Y157273D01*
X489708Y157487D01*
X489750Y157727D01*
X489708Y157940D01*
X489500Y158153D01*
X489250Y158287D01*
X489000Y158313D01*
X488708Y158260D01*
X488500Y158073D01*
X488417Y157887D01*
Y157647D01*
G01Y157887D02*
X488292Y158047D01*
X488083Y158180D01*
X487833Y158233D01*
X487583Y158180D01*
X487375Y158047D01*
X487250Y157807D01*
X487292Y157567D01*
X487458Y157327D01*
G01X489750Y159847D02*
X489208Y159900D01*
X488750Y159980D01*
X488333Y160087D01*
X487875Y160220D01*
X487250Y160433D01*
Y159367D01*
G01X493250Y152700D02*
X495750D01*
G01X493250Y152087D02*
Y153313D01*
G01X495750Y154367D02*
X493250D01*
Y155007D01*
X493375Y155220D01*
X493667Y155380D01*
X494000Y155433D01*
X494333Y155380D01*
X494583Y155247D01*
X494708Y155007D01*
Y154367D01*
G01Y156593D02*
X494417Y156780D01*
X494250Y156940D01*
X494167Y157153D01*
X494250Y157340D01*
X494417Y157473D01*
X494667Y157580D01*
X494958Y157607D01*
X495208Y157580D01*
X495458Y157473D01*
X495667Y157313D01*
X495750Y157127D01*
X495667Y156913D01*
X495417Y156727D01*
X495042Y156620D01*
X494625Y156593D01*
X494083Y156647D01*
X493792Y156727D01*
X493500Y156860D01*
X493292Y157047D01*
X493250Y157233D01*
X493333Y157420D01*
X493542Y157553D01*
G01X493667Y158793D02*
X493417Y158953D01*
X493292Y159140D01*
X493250Y159353D01*
X493333Y159620D01*
X493542Y159807D01*
X493792Y159860D01*
X494042Y159833D01*
X494250Y159727D01*
X494667Y159193D01*
X494958Y158953D01*
X495375Y158793D01*
X495750Y158740D01*
Y159860D01*
G01X497083Y171450D02*
Y174550D01*
X498042D01*
X498348Y174395D01*
X498540Y174188D01*
X498617Y173775D01*
X498540Y173362D01*
X498310Y173103D01*
X498042Y172948D01*
X497083D01*
G01X498042D02*
X498617Y171450D01*
G01X500222Y174033D02*
X500452Y174343D01*
X500720Y174498D01*
X501027Y174550D01*
X501410Y174447D01*
X501678Y174188D01*
X501755Y173878D01*
X501717Y173568D01*
X501563Y173310D01*
X500797Y172793D01*
X500452Y172432D01*
X500222Y171915D01*
X500145Y171450D01*
X501755D01*
G01X504050D02*
X504318Y171502D01*
X504625Y171657D01*
X504817Y171915D01*
X504893Y172277D01*
X504817Y172638D01*
X504587Y172948D01*
X504242Y173103D01*
X503858D01*
X503628Y173207D01*
X503437Y173465D01*
X503360Y173827D01*
X503475Y174188D01*
X503743Y174447D01*
X504050Y174550D01*
X504357Y174447D01*
X504625Y174188D01*
X504740Y173827D01*
X504663Y173465D01*
X504472Y173207D01*
X504242Y173103D01*
X503858D01*
X503513Y172948D01*
X503283Y172638D01*
X503207Y172277D01*
X503283Y171915D01*
X503475Y171657D01*
X503782Y171502D01*
X504050Y171450D01*
G01X507150D02*
X507418Y171502D01*
X507725Y171657D01*
X507917Y171915D01*
X507993Y172277D01*
X507917Y172638D01*
X507687Y172948D01*
X507342Y173103D01*
X506958D01*
X506728Y173207D01*
X506537Y173465D01*
X506460Y173827D01*
X506575Y174188D01*
X506843Y174447D01*
X507150Y174550D01*
X507457Y174447D01*
X507725Y174188D01*
X507840Y173827D01*
X507763Y173465D01*
X507572Y173207D01*
X507342Y173103D01*
X506958D01*
X506613Y172948D01*
X506383Y172638D01*
X506307Y172277D01*
X506383Y171915D01*
X506575Y171657D01*
X506882Y171502D01*
X507150Y171450D01*
G01X497133Y167450D02*
Y170550D01*
X498092D01*
X498398Y170395D01*
X498590Y170188D01*
X498667Y169775D01*
X498590Y169362D01*
X498360Y169103D01*
X498092Y168948D01*
X497133D01*
G01X498092D02*
X498667Y167450D01*
G01X500348Y167812D02*
X500617Y167553D01*
X500923Y167450D01*
X501230Y167553D01*
X501498Y167863D01*
X501690Y168328D01*
X501767Y168793D01*
Y169362D01*
X501690Y169827D01*
X501498Y170240D01*
X501268Y170447D01*
X501000Y170550D01*
X500693Y170447D01*
X500463Y170240D01*
X500310Y169930D01*
X500233Y169517D01*
X500310Y169155D01*
X500502Y168793D01*
X500732Y168587D01*
X501000Y168535D01*
X501307Y168638D01*
X501537Y168897D01*
X501767Y169362D01*
G01X503257Y168070D02*
X503487Y167708D01*
X503793Y167502D01*
X504138Y167450D01*
X504445Y167502D01*
X504752Y167760D01*
X504943Y168070D01*
X504982Y168380D01*
X504905Y168742D01*
X504637Y169000D01*
X504368Y169103D01*
X504023D01*
G01X504368D02*
X504598Y169258D01*
X504790Y169517D01*
X504867Y169827D01*
X504790Y170137D01*
X504598Y170395D01*
X504253Y170550D01*
X503908Y170498D01*
X503563Y170292D01*
G01X497083Y180450D02*
Y183550D01*
X498042D01*
X498348Y183395D01*
X498540Y183188D01*
X498617Y182775D01*
X498540Y182362D01*
X498310Y182103D01*
X498042Y181948D01*
X497083D01*
G01X498042D02*
X498617Y180450D01*
G01X500222Y183033D02*
X500452Y183343D01*
X500720Y183498D01*
X501027Y183550D01*
X501410Y183447D01*
X501678Y183188D01*
X501755Y182878D01*
X501717Y182568D01*
X501563Y182310D01*
X500797Y181793D01*
X500452Y181432D01*
X500222Y180915D01*
X500145Y180450D01*
X501755D01*
G01X504050D02*
Y183550D01*
X503590Y182930D01*
G01Y180450D02*
X504510D01*
G01X507150D02*
Y183550D01*
X506690Y182930D01*
G01Y180450D02*
X507610D01*
G01X497083Y175950D02*
Y179050D01*
X498042D01*
X498348Y178895D01*
X498540Y178688D01*
X498617Y178275D01*
X498540Y177862D01*
X498310Y177603D01*
X498042Y177448D01*
X497083D01*
G01X498042D02*
X498617Y175950D01*
G01X500222Y178533D02*
X500452Y178843D01*
X500720Y178998D01*
X501027Y179050D01*
X501410Y178947D01*
X501678Y178688D01*
X501755Y178378D01*
X501717Y178068D01*
X501563Y177810D01*
X500797Y177293D01*
X500452Y176932D01*
X500222Y176415D01*
X500145Y175950D01*
X501755D01*
G01X504050D02*
Y179050D01*
X503590Y178430D01*
G01Y175950D02*
X504510D01*
G01X506422Y178533D02*
X506652Y178843D01*
X506920Y178998D01*
X507227Y179050D01*
X507610Y178947D01*
X507878Y178688D01*
X507955Y178378D01*
X507917Y178068D01*
X507763Y177810D01*
X506997Y177293D01*
X506652Y176932D01*
X506422Y176415D01*
X506345Y175950D01*
X507955D01*
G01X487133Y191450D02*
Y194550D01*
X488092D01*
X488398Y194395D01*
X488590Y194188D01*
X488667Y193775D01*
X488590Y193362D01*
X488360Y193103D01*
X488092Y192948D01*
X487133D01*
G01X488092D02*
X488667Y191450D01*
G01X490348Y191812D02*
X490617Y191553D01*
X490923Y191450D01*
X491230Y191553D01*
X491498Y191863D01*
X491690Y192328D01*
X491767Y192793D01*
Y193362D01*
X491690Y193827D01*
X491498Y194240D01*
X491268Y194447D01*
X491000Y194550D01*
X490693Y194447D01*
X490463Y194240D01*
X490310Y193930D01*
X490233Y193517D01*
X490310Y193155D01*
X490502Y192793D01*
X490732Y192587D01*
X491000Y192535D01*
X491307Y192638D01*
X491537Y192897D01*
X491767Y193362D01*
G01X493257Y191915D02*
X493487Y191657D01*
X493755Y191502D01*
X494100Y191450D01*
X494445Y191553D01*
X494713Y191760D01*
X494905Y192122D01*
X494943Y192535D01*
X494867Y192948D01*
X494675Y193207D01*
X494407Y193413D01*
X494138Y193465D01*
X493870Y193413D01*
X493525Y193207D01*
X493640Y194550D01*
X494675D01*
G01X487133Y186450D02*
Y189550D01*
X488092D01*
X488398Y189395D01*
X488590Y189188D01*
X488667Y188775D01*
X488590Y188362D01*
X488360Y188103D01*
X488092Y187948D01*
X487133D01*
G01X488092D02*
X488667Y186450D01*
G01X490348Y186812D02*
X490617Y186553D01*
X490923Y186450D01*
X491230Y186553D01*
X491498Y186863D01*
X491690Y187328D01*
X491767Y187793D01*
Y188362D01*
X491690Y188827D01*
X491498Y189240D01*
X491268Y189447D01*
X491000Y189550D01*
X490693Y189447D01*
X490463Y189240D01*
X490310Y188930D01*
X490233Y188517D01*
X490310Y188155D01*
X490502Y187793D01*
X490732Y187587D01*
X491000Y187535D01*
X491307Y187638D01*
X491537Y187897D01*
X491767Y188362D01*
G01X494560Y186450D02*
Y189550D01*
X493142Y187328D01*
X495058D01*
G01X497583Y208950D02*
Y212050D01*
X498542D01*
X498848Y211895D01*
X499040Y211688D01*
X499117Y211275D01*
X499040Y210862D01*
X498810Y210603D01*
X498542Y210448D01*
X497583D01*
G01X498542D02*
X499117Y208950D01*
G01X501450D02*
Y212050D01*
X500990Y211430D01*
G01Y208950D02*
X501910D01*
G01X503898Y209312D02*
X504167Y209053D01*
X504473Y208950D01*
X504780Y209053D01*
X505048Y209363D01*
X505240Y209828D01*
X505317Y210293D01*
Y210862D01*
X505240Y211327D01*
X505048Y211740D01*
X504818Y211947D01*
X504550Y212050D01*
X504243Y211947D01*
X504013Y211740D01*
X503860Y211430D01*
X503783Y211017D01*
X503860Y210655D01*
X504052Y210293D01*
X504282Y210087D01*
X504550Y210035D01*
X504857Y210138D01*
X505087Y210397D01*
X505317Y210862D01*
G01X506807Y209570D02*
X507037Y209208D01*
X507343Y209002D01*
X507688Y208950D01*
X507995Y209002D01*
X508302Y209260D01*
X508493Y209570D01*
X508532Y209880D01*
X508455Y210242D01*
X508187Y210500D01*
X507918Y210603D01*
X507573D01*
G01X507918D02*
X508148Y210758D01*
X508340Y211017D01*
X508417Y211327D01*
X508340Y211637D01*
X508148Y211895D01*
X507803Y212050D01*
X507458Y211998D01*
X507113Y211792D01*
G01X497583Y204950D02*
Y208050D01*
X498542D01*
X498848Y207895D01*
X499040Y207688D01*
X499117Y207275D01*
X499040Y206862D01*
X498810Y206603D01*
X498542Y206448D01*
X497583D01*
G01X498542D02*
X499117Y204950D01*
G01X500607Y205570D02*
X500837Y205208D01*
X501143Y205002D01*
X501488Y204950D01*
X501795Y205002D01*
X502102Y205260D01*
X502293Y205570D01*
X502332Y205880D01*
X502255Y206242D01*
X501987Y206500D01*
X501718Y206603D01*
X501373D01*
G01X501718D02*
X501948Y206758D01*
X502140Y207017D01*
X502217Y207327D01*
X502140Y207637D01*
X501948Y207895D01*
X501603Y208050D01*
X501258Y207998D01*
X500913Y207792D01*
G01X503707Y205415D02*
X503937Y205157D01*
X504205Y205002D01*
X504550Y204950D01*
X504895Y205053D01*
X505163Y205260D01*
X505355Y205622D01*
X505393Y206035D01*
X505317Y206448D01*
X505125Y206707D01*
X504857Y206913D01*
X504588Y206965D01*
X504320Y206913D01*
X503975Y206707D01*
X504090Y208050D01*
X505125D01*
G01X506922Y206242D02*
X507190Y206603D01*
X507420Y206810D01*
X507727Y206913D01*
X507995Y206810D01*
X508187Y206603D01*
X508340Y206293D01*
X508378Y205932D01*
X508340Y205622D01*
X508187Y205312D01*
X507957Y205053D01*
X507688Y204950D01*
X507382Y205053D01*
X507113Y205363D01*
X506960Y205828D01*
X506922Y206345D01*
X506998Y207017D01*
X507113Y207378D01*
X507305Y207740D01*
X507573Y207998D01*
X507842Y208050D01*
X508110Y207947D01*
X508302Y207688D01*
G01X485950Y246683D02*
X489050D01*
Y248217D01*
G01X487758Y249822D02*
X487397Y250090D01*
X487190Y250320D01*
X487087Y250627D01*
X487190Y250895D01*
X487397Y251087D01*
X487707Y251240D01*
X488068Y251278D01*
X488378Y251240D01*
X488688Y251087D01*
X488947Y250857D01*
X489050Y250588D01*
X488947Y250282D01*
X488637Y250013D01*
X488172Y249860D01*
X487655Y249822D01*
X486983Y249898D01*
X486622Y250013D01*
X486260Y250205D01*
X486002Y250473D01*
X485950Y250742D01*
X486053Y251010D01*
X486312Y251202D01*
G01X489550Y255083D02*
X486450D01*
Y256042D01*
X486605Y256348D01*
X486812Y256540D01*
X487225Y256617D01*
X487638Y256540D01*
X487897Y256310D01*
X488052Y256042D01*
Y255083D01*
G01Y256042D02*
X489550Y256617D01*
G01Y258950D02*
X486450D01*
X487070Y258490D01*
G01X489550D02*
Y259410D01*
G01Y262510D02*
X486450D01*
X488672Y261092D01*
Y263008D01*
G01X489550Y265150D02*
X486450D01*
X487070Y264690D01*
G01X489550D02*
Y265610D01*
G01X492193Y288292D02*
X491963Y288447D01*
X491695Y288550D01*
X491388D01*
X491043Y288395D01*
X490775Y288137D01*
X490583Y287827D01*
X490430Y287310D01*
X490392Y286845D01*
X490468Y286380D01*
X490583Y286070D01*
X490813Y285760D01*
X491082Y285553D01*
X491350Y285450D01*
X491618D01*
X491887Y285553D01*
X492117Y285708D01*
X492308Y285915D01*
G01X494450Y285450D02*
Y288550D01*
X493990Y287930D01*
G01Y285450D02*
X494910D01*
G01X497550D02*
X497818Y285502D01*
X498125Y285657D01*
X498317Y285915D01*
X498393Y286277D01*
X498317Y286638D01*
X498087Y286948D01*
X497742Y287103D01*
X497358D01*
X497128Y287207D01*
X496937Y287465D01*
X496860Y287827D01*
X496975Y288188D01*
X497243Y288447D01*
X497550Y288550D01*
X497857Y288447D01*
X498125Y288188D01*
X498240Y287827D01*
X498163Y287465D01*
X497972Y287207D01*
X497742Y287103D01*
X497358D01*
X497013Y286948D01*
X496783Y286638D01*
X496707Y286277D01*
X496783Y285915D01*
X496975Y285657D01*
X497282Y285502D01*
X497550Y285450D01*
G01X500573D02*
X500650Y286122D01*
X500765Y286690D01*
X500918Y287207D01*
X501110Y287775D01*
X501417Y288550D01*
X499883D01*
G01X491083Y281450D02*
Y284550D01*
X492042D01*
X492348Y284395D01*
X492540Y284188D01*
X492617Y283775D01*
X492540Y283362D01*
X492310Y283103D01*
X492042Y282948D01*
X491083D01*
G01X492042D02*
X492617Y281450D01*
G01X494950D02*
Y284550D01*
X494490Y283930D01*
G01Y281450D02*
X495410D01*
G01X497322Y282742D02*
X497590Y283103D01*
X497820Y283310D01*
X498127Y283413D01*
X498395Y283310D01*
X498587Y283103D01*
X498740Y282793D01*
X498778Y282432D01*
X498740Y282122D01*
X498587Y281812D01*
X498357Y281553D01*
X498088Y281450D01*
X497782Y281553D01*
X497513Y281863D01*
X497360Y282328D01*
X497322Y282845D01*
X497398Y283517D01*
X497513Y283878D01*
X497705Y284240D01*
X497973Y284498D01*
X498242Y284550D01*
X498510Y284447D01*
X498702Y284188D01*
G01X500422Y282742D02*
X500690Y283103D01*
X500920Y283310D01*
X501227Y283413D01*
X501495Y283310D01*
X501687Y283103D01*
X501840Y282793D01*
X501878Y282432D01*
X501840Y282122D01*
X501687Y281812D01*
X501457Y281553D01*
X501188Y281450D01*
X500882Y281553D01*
X500613Y281863D01*
X500460Y282328D01*
X500422Y282845D01*
X500498Y283517D01*
X500613Y283878D01*
X500805Y284240D01*
X501073Y284498D01*
X501342Y284550D01*
X501610Y284447D01*
X501802Y284188D01*
G01X492193Y292292D02*
X491963Y292447D01*
X491695Y292550D01*
X491388D01*
X491043Y292395D01*
X490775Y292137D01*
X490583Y291827D01*
X490430Y291310D01*
X490392Y290845D01*
X490468Y290380D01*
X490583Y290070D01*
X490813Y289760D01*
X491082Y289553D01*
X491350Y289450D01*
X491618D01*
X491887Y289553D01*
X492117Y289708D01*
X492308Y289915D01*
G01X494450Y289450D02*
Y292550D01*
X493990Y291930D01*
G01Y289450D02*
X494910D01*
G01X496898Y289812D02*
X497167Y289553D01*
X497473Y289450D01*
X497780Y289553D01*
X498048Y289863D01*
X498240Y290328D01*
X498317Y290793D01*
Y291362D01*
X498240Y291827D01*
X498048Y292240D01*
X497818Y292447D01*
X497550Y292550D01*
X497243Y292447D01*
X497013Y292240D01*
X496860Y291930D01*
X496783Y291517D01*
X496860Y291155D01*
X497052Y290793D01*
X497282Y290587D01*
X497550Y290535D01*
X497857Y290638D01*
X498087Y290897D01*
X498317Y291362D01*
G01X500650Y289450D02*
Y292550D01*
X500190Y291930D01*
G01Y289450D02*
X501110D01*
G01X490550Y333583D02*
X487450D01*
Y334542D01*
X487605Y334848D01*
X487812Y335040D01*
X488225Y335117D01*
X488638Y335040D01*
X488897Y334810D01*
X489052Y334542D01*
Y333583D01*
G01Y334542D02*
X490550Y335117D01*
G01Y337450D02*
X487450D01*
X488070Y336990D01*
G01X490550D02*
Y337910D01*
G01Y340550D02*
X487450D01*
X488070Y340090D01*
G01X490550D02*
Y341010D01*
G01X489930Y342807D02*
X490292Y343037D01*
X490498Y343343D01*
X490550Y343688D01*
X490498Y343995D01*
X490240Y344302D01*
X489930Y344493D01*
X489620Y344532D01*
X489258Y344455D01*
X489000Y344187D01*
X488897Y343918D01*
Y343573D01*
G01Y343918D02*
X488742Y344148D01*
X488483Y344340D01*
X488173Y344417D01*
X487863Y344340D01*
X487605Y344148D01*
X487450Y343803D01*
X487502Y343458D01*
X487708Y343113D01*
G01X486050Y333583D02*
X482950D01*
Y334542D01*
X483105Y334848D01*
X483312Y335040D01*
X483725Y335117D01*
X484138Y335040D01*
X484397Y334810D01*
X484552Y334542D01*
Y333583D01*
G01Y334542D02*
X486050Y335117D01*
G01Y337450D02*
X482950D01*
X483570Y336990D01*
G01X486050D02*
Y337910D01*
G01Y340550D02*
X482950D01*
X483570Y340090D01*
G01X486050D02*
Y341010D01*
G01Y343573D02*
X485378Y343650D01*
X484810Y343765D01*
X484293Y343918D01*
X483725Y344110D01*
X482950Y344417D01*
Y342883D01*
G01X495050Y333583D02*
X491950D01*
Y334542D01*
X492105Y334848D01*
X492312Y335040D01*
X492725Y335117D01*
X493138Y335040D01*
X493397Y334810D01*
X493552Y334542D01*
Y333583D01*
G01Y334542D02*
X495050Y335117D01*
G01X492467Y336722D02*
X492157Y336952D01*
X492002Y337220D01*
X491950Y337527D01*
X492053Y337910D01*
X492312Y338178D01*
X492622Y338255D01*
X492932Y338217D01*
X493190Y338063D01*
X493707Y337297D01*
X494068Y336952D01*
X494585Y336722D01*
X495050Y336645D01*
Y338255D01*
G01X493758Y339822D02*
X493397Y340090D01*
X493190Y340320D01*
X493087Y340627D01*
X493190Y340895D01*
X493397Y341087D01*
X493707Y341240D01*
X494068Y341278D01*
X494378Y341240D01*
X494688Y341087D01*
X494947Y340857D01*
X495050Y340588D01*
X494947Y340282D01*
X494637Y340013D01*
X494172Y339860D01*
X493655Y339822D01*
X492983Y339898D01*
X492622Y340013D01*
X492260Y340205D01*
X492002Y340473D01*
X491950Y340742D01*
X492053Y341010D01*
X492312Y341202D01*
G01X495050Y343650D02*
X494998Y343918D01*
X494843Y344225D01*
X494585Y344417D01*
X494223Y344493D01*
X493862Y344417D01*
X493552Y344187D01*
X493397Y343842D01*
Y343458D01*
X493293Y343228D01*
X493035Y343037D01*
X492673Y342960D01*
X492312Y343075D01*
X492053Y343343D01*
X491950Y343650D01*
X492053Y343957D01*
X492312Y344225D01*
X492673Y344340D01*
X493035Y344263D01*
X493293Y344072D01*
X493397Y343842D01*
Y343458D01*
X493552Y343113D01*
X493862Y342883D01*
X494223Y342807D01*
X494585Y342883D01*
X494843Y343075D01*
X494998Y343382D01*
X495050Y343650D01*
G01X489403Y324450D02*
Y327550D01*
X490400Y324967D01*
X491397Y327550D01*
Y324450D01*
G01X494267D02*
X492733D01*
Y327550D01*
X494267D01*
G01X493653Y326052D02*
X492733D01*
G01X497060Y324450D02*
Y327550D01*
X495642Y325328D01*
X497558D01*
G01X514950Y95950D02*
Y99050D01*
X514490Y98430D01*
G01Y95950D02*
X515410D01*
G01X517322Y97242D02*
X517590Y97603D01*
X517820Y97810D01*
X518127Y97913D01*
X518395Y97810D01*
X518587Y97603D01*
X518740Y97293D01*
X518778Y96932D01*
X518740Y96622D01*
X518587Y96312D01*
X518357Y96053D01*
X518088Y95950D01*
X517782Y96053D01*
X517513Y96363D01*
X517360Y96828D01*
X517322Y97345D01*
X517398Y98017D01*
X517513Y98378D01*
X517705Y98740D01*
X517973Y98998D01*
X518242Y99050D01*
X518510Y98947D01*
X518702Y98688D01*
G01X504083Y126450D02*
Y129550D01*
X505042D01*
X505348Y129395D01*
X505540Y129188D01*
X505617Y128775D01*
X505540Y128362D01*
X505310Y128103D01*
X505042Y127948D01*
X504083D01*
G01X505042D02*
X505617Y126450D01*
G01X507950D02*
Y129550D01*
X507490Y128930D01*
G01Y126450D02*
X508410D01*
G01X510398Y126812D02*
X510667Y126553D01*
X510973Y126450D01*
X511280Y126553D01*
X511548Y126863D01*
X511740Y127328D01*
X511817Y127793D01*
Y128362D01*
X511740Y128827D01*
X511548Y129240D01*
X511318Y129447D01*
X511050Y129550D01*
X510743Y129447D01*
X510513Y129240D01*
X510360Y128930D01*
X510283Y128517D01*
X510360Y128155D01*
X510552Y127793D01*
X510782Y127587D01*
X511050Y127535D01*
X511357Y127638D01*
X511587Y127897D01*
X511817Y128362D01*
G01X514610Y126450D02*
Y129550D01*
X513192Y127328D01*
X515108D01*
G01X504083Y130950D02*
Y134050D01*
X505042D01*
X505348Y133895D01*
X505540Y133688D01*
X505617Y133275D01*
X505540Y132862D01*
X505310Y132603D01*
X505042Y132448D01*
X504083D01*
G01X505042D02*
X505617Y130950D01*
G01X507222Y133533D02*
X507452Y133843D01*
X507720Y133998D01*
X508027Y134050D01*
X508410Y133947D01*
X508678Y133688D01*
X508755Y133378D01*
X508717Y133068D01*
X508563Y132810D01*
X507797Y132293D01*
X507452Y131932D01*
X507222Y131415D01*
X507145Y130950D01*
X508755D01*
G01X510322Y133533D02*
X510552Y133843D01*
X510820Y133998D01*
X511127Y134050D01*
X511510Y133947D01*
X511778Y133688D01*
X511855Y133378D01*
X511817Y133068D01*
X511663Y132810D01*
X510897Y132293D01*
X510552Y131932D01*
X510322Y131415D01*
X510245Y130950D01*
X511855D01*
G01X514150D02*
Y134050D01*
X513690Y133430D01*
G01Y130950D02*
X514610D01*
G01X504083Y135450D02*
Y138550D01*
X505042D01*
X505348Y138395D01*
X505540Y138188D01*
X505617Y137775D01*
X505540Y137362D01*
X505310Y137103D01*
X505042Y136948D01*
X504083D01*
G01X505042D02*
X505617Y135450D01*
G01X507222Y138033D02*
X507452Y138343D01*
X507720Y138498D01*
X508027Y138550D01*
X508410Y138447D01*
X508678Y138188D01*
X508755Y137878D01*
X508717Y137568D01*
X508563Y137310D01*
X507797Y136793D01*
X507452Y136432D01*
X507222Y135915D01*
X507145Y135450D01*
X508755D01*
G01X510322Y138033D02*
X510552Y138343D01*
X510820Y138498D01*
X511127Y138550D01*
X511510Y138447D01*
X511778Y138188D01*
X511855Y137878D01*
X511817Y137568D01*
X511663Y137310D01*
X510897Y136793D01*
X510552Y136432D01*
X510322Y135915D01*
X510245Y135450D01*
X511855D01*
G01X513422Y138033D02*
X513652Y138343D01*
X513920Y138498D01*
X514227Y138550D01*
X514610Y138447D01*
X514878Y138188D01*
X514955Y137878D01*
X514917Y137568D01*
X514763Y137310D01*
X513997Y136793D01*
X513652Y136432D01*
X513422Y135915D01*
X513345Y135450D01*
X514955D01*
G01X507750Y140600D02*
X510250D01*
G01X507750Y139987D02*
Y141213D01*
G01X510250Y142267D02*
X507750D01*
Y142907D01*
X507875Y143120D01*
X508167Y143280D01*
X508500Y143333D01*
X508833Y143280D01*
X509083Y143147D01*
X509208Y142907D01*
Y142267D01*
G01X510250Y145000D02*
X507750D01*
X508250Y144680D01*
G01X510250D02*
Y145320D01*
G01X509750Y146613D02*
X510042Y146773D01*
X510208Y146987D01*
X510250Y147227D01*
X510208Y147440D01*
X510000Y147653D01*
X509750Y147787D01*
X509500Y147813D01*
X509208Y147760D01*
X509000Y147573D01*
X508917Y147387D01*
Y147147D01*
G01Y147387D02*
X508792Y147547D01*
X508583Y147680D01*
X508333Y147733D01*
X508083Y147680D01*
X507875Y147547D01*
X507750Y147307D01*
X507792Y147067D01*
X507958Y146827D01*
G01X509875Y148813D02*
X510083Y148973D01*
X510208Y149160D01*
X510250Y149400D01*
X510167Y149640D01*
X510000Y149827D01*
X509708Y149960D01*
X509375Y149987D01*
X509042Y149933D01*
X508833Y149800D01*
X508667Y149613D01*
X508625Y149427D01*
X508667Y149240D01*
X508833Y149000D01*
X507750Y149080D01*
Y149800D01*
G01X511050Y140450D02*
X513550D01*
G01X511050Y139837D02*
Y141063D01*
G01X513550Y142117D02*
X511050D01*
Y142757D01*
X511175Y142970D01*
X511467Y143130D01*
X511800Y143183D01*
X512133Y143130D01*
X512383Y142997D01*
X512508Y142757D01*
Y142117D01*
G01X513550Y144850D02*
X511050D01*
X511550Y144530D01*
G01X513550D02*
Y145170D01*
G01X513050Y146463D02*
X513342Y146623D01*
X513508Y146837D01*
X513550Y147077D01*
X513508Y147290D01*
X513300Y147503D01*
X513050Y147637D01*
X512800Y147663D01*
X512508Y147610D01*
X512300Y147423D01*
X512217Y147237D01*
Y146997D01*
G01Y147237D02*
X512092Y147397D01*
X511883Y147530D01*
X511633Y147583D01*
X511383Y147530D01*
X511175Y147397D01*
X511050Y147157D01*
X511092Y146917D01*
X511258Y146677D01*
G01X513550Y149250D02*
X513508Y149437D01*
X513383Y149650D01*
X513175Y149783D01*
X512883Y149837D01*
X512592Y149783D01*
X512342Y149623D01*
X512217Y149383D01*
Y149117D01*
X512133Y148957D01*
X511925Y148823D01*
X511633Y148770D01*
X511342Y148850D01*
X511133Y149037D01*
X511050Y149250D01*
X511133Y149463D01*
X511342Y149650D01*
X511633Y149730D01*
X511925Y149677D01*
X512133Y149543D01*
X512217Y149383D01*
Y149117D01*
X512342Y148877D01*
X512592Y148717D01*
X512883Y148663D01*
X513175Y148717D01*
X513383Y148850D01*
X513508Y149063D01*
X513550Y149250D01*
G01X505750Y152600D02*
X508250D01*
G01X505750Y151987D02*
Y153213D01*
G01X508250Y154267D02*
X505750D01*
Y154907D01*
X505875Y155120D01*
X506167Y155280D01*
X506500Y155333D01*
X506833Y155280D01*
X507083Y155147D01*
X507208Y154907D01*
Y154267D01*
G01X508250Y157000D02*
X505750D01*
X506250Y156680D01*
G01X508250D02*
Y157320D01*
G01X507750Y158613D02*
X508042Y158773D01*
X508208Y158987D01*
X508250Y159227D01*
X508208Y159440D01*
X508000Y159653D01*
X507750Y159787D01*
X507500Y159813D01*
X507208Y159760D01*
X507000Y159573D01*
X506917Y159387D01*
Y159147D01*
G01Y159387D02*
X506792Y159547D01*
X506583Y159680D01*
X506333Y159733D01*
X506083Y159680D01*
X505875Y159547D01*
X505750Y159307D01*
X505792Y159067D01*
X505958Y158827D01*
G01X508250Y161720D02*
X505750D01*
X507542Y160733D01*
Y162067D01*
G01X504193Y229792D02*
X503963Y229947D01*
X503695Y230050D01*
X503388D01*
X503043Y229895D01*
X502775Y229637D01*
X502583Y229327D01*
X502430Y228810D01*
X502392Y228345D01*
X502468Y227880D01*
X502583Y227570D01*
X502813Y227260D01*
X503082Y227053D01*
X503350Y226950D01*
X503618D01*
X503887Y227053D01*
X504117Y227208D01*
X504308Y227415D01*
G01X506450Y226950D02*
Y230050D01*
X505990Y229430D01*
G01Y226950D02*
X506910D01*
G01X509550D02*
X509818Y227002D01*
X510125Y227157D01*
X510317Y227415D01*
X510393Y227777D01*
X510317Y228138D01*
X510087Y228448D01*
X509742Y228603D01*
X509358D01*
X509128Y228707D01*
X508937Y228965D01*
X508860Y229327D01*
X508975Y229688D01*
X509243Y229947D01*
X509550Y230050D01*
X509857Y229947D01*
X510125Y229688D01*
X510240Y229327D01*
X510163Y228965D01*
X509972Y228707D01*
X509742Y228603D01*
X509358D01*
X509013Y228448D01*
X508783Y228138D01*
X508707Y227777D01*
X508783Y227415D01*
X508975Y227157D01*
X509282Y227002D01*
X509550Y226950D01*
G01X511807Y227570D02*
X512037Y227208D01*
X512343Y227002D01*
X512688Y226950D01*
X512995Y227002D01*
X513302Y227260D01*
X513493Y227570D01*
X513532Y227880D01*
X513455Y228242D01*
X513187Y228500D01*
X512918Y228603D01*
X512573D01*
G01X512918D02*
X513148Y228758D01*
X513340Y229017D01*
X513417Y229327D01*
X513340Y229637D01*
X513148Y229895D01*
X512803Y230050D01*
X512458Y229998D01*
X512113Y229792D01*
G01X504393Y234192D02*
X504163Y234347D01*
X503895Y234450D01*
X503588D01*
X503243Y234295D01*
X502975Y234037D01*
X502783Y233727D01*
X502630Y233210D01*
X502592Y232745D01*
X502668Y232280D01*
X502783Y231970D01*
X503013Y231660D01*
X503282Y231453D01*
X503550Y231350D01*
X503818D01*
X504087Y231453D01*
X504317Y231608D01*
X504508Y231815D01*
G01X506650Y231350D02*
Y234450D01*
X506190Y233830D01*
G01Y231350D02*
X507110D01*
G01X509750D02*
X510018Y231402D01*
X510325Y231557D01*
X510517Y231815D01*
X510593Y232177D01*
X510517Y232538D01*
X510287Y232848D01*
X509942Y233003D01*
X509558D01*
X509328Y233107D01*
X509137Y233365D01*
X509060Y233727D01*
X509175Y234088D01*
X509443Y234347D01*
X509750Y234450D01*
X510057Y234347D01*
X510325Y234088D01*
X510440Y233727D01*
X510363Y233365D01*
X510172Y233107D01*
X509942Y233003D01*
X509558D01*
X509213Y232848D01*
X508983Y232538D01*
X508907Y232177D01*
X508983Y231815D01*
X509175Y231557D01*
X509482Y231402D01*
X509750Y231350D01*
G01X512122Y232642D02*
X512390Y233003D01*
X512620Y233210D01*
X512927Y233313D01*
X513195Y233210D01*
X513387Y233003D01*
X513540Y232693D01*
X513578Y232332D01*
X513540Y232022D01*
X513387Y231712D01*
X513157Y231453D01*
X512888Y231350D01*
X512582Y231453D01*
X512313Y231763D01*
X512160Y232228D01*
X512122Y232745D01*
X512198Y233417D01*
X512313Y233778D01*
X512505Y234140D01*
X512773Y234398D01*
X513042Y234450D01*
X513310Y234347D01*
X513502Y234088D01*
G01X504493Y238492D02*
X504263Y238647D01*
X503995Y238750D01*
X503688D01*
X503343Y238595D01*
X503075Y238337D01*
X502883Y238027D01*
X502730Y237510D01*
X502692Y237045D01*
X502768Y236580D01*
X502883Y236270D01*
X503113Y235960D01*
X503382Y235753D01*
X503650Y235650D01*
X503918D01*
X504187Y235753D01*
X504417Y235908D01*
X504608Y236115D01*
G01X506750Y235650D02*
Y238750D01*
X506290Y238130D01*
G01Y235650D02*
X507210D01*
G01X509850D02*
X510118Y235702D01*
X510425Y235857D01*
X510617Y236115D01*
X510693Y236477D01*
X510617Y236838D01*
X510387Y237148D01*
X510042Y237303D01*
X509658D01*
X509428Y237407D01*
X509237Y237665D01*
X509160Y238027D01*
X509275Y238388D01*
X509543Y238647D01*
X509850Y238750D01*
X510157Y238647D01*
X510425Y238388D01*
X510540Y238027D01*
X510463Y237665D01*
X510272Y237407D01*
X510042Y237303D01*
X509658D01*
X509313Y237148D01*
X509083Y236838D01*
X509007Y236477D01*
X509083Y236115D01*
X509275Y235857D01*
X509582Y235702D01*
X509850Y235650D01*
G01X512298Y236012D02*
X512567Y235753D01*
X512873Y235650D01*
X513180Y235753D01*
X513448Y236063D01*
X513640Y236528D01*
X513717Y236993D01*
Y237562D01*
X513640Y238027D01*
X513448Y238440D01*
X513218Y238647D01*
X512950Y238750D01*
X512643Y238647D01*
X512413Y238440D01*
X512260Y238130D01*
X512183Y237717D01*
X512260Y237355D01*
X512452Y236993D01*
X512682Y236787D01*
X512950Y236735D01*
X513257Y236838D01*
X513487Y237097D01*
X513717Y237562D01*
G01X516993Y244492D02*
X516763Y244647D01*
X516495Y244750D01*
X516188D01*
X515843Y244595D01*
X515575Y244337D01*
X515383Y244027D01*
X515230Y243510D01*
X515192Y243045D01*
X515268Y242580D01*
X515383Y242270D01*
X515613Y241960D01*
X515882Y241753D01*
X516150Y241650D01*
X516418D01*
X516687Y241753D01*
X516917Y241908D01*
X517108Y242115D01*
G01X519250Y241650D02*
Y244750D01*
X518790Y244130D01*
G01Y241650D02*
X519710D01*
G01X521698Y242012D02*
X521967Y241753D01*
X522273Y241650D01*
X522580Y241753D01*
X522848Y242063D01*
X523040Y242528D01*
X523117Y242993D01*
Y243562D01*
X523040Y244027D01*
X522848Y244440D01*
X522618Y244647D01*
X522350Y244750D01*
X522043Y244647D01*
X521813Y244440D01*
X521660Y244130D01*
X521583Y243717D01*
X521660Y243355D01*
X521852Y242993D01*
X522082Y242787D01*
X522350Y242735D01*
X522657Y242838D01*
X522887Y243097D01*
X523117Y243562D01*
G01X525373Y241650D02*
X525450Y242322D01*
X525565Y242890D01*
X525718Y243407D01*
X525910Y243975D01*
X526217Y244750D01*
X524683D01*
G01X517193Y240292D02*
X516963Y240447D01*
X516695Y240550D01*
X516388D01*
X516043Y240395D01*
X515775Y240137D01*
X515583Y239827D01*
X515430Y239310D01*
X515392Y238845D01*
X515468Y238380D01*
X515583Y238070D01*
X515813Y237760D01*
X516082Y237553D01*
X516350Y237450D01*
X516618D01*
X516887Y237553D01*
X517117Y237708D01*
X517308Y237915D01*
G01X519450Y237450D02*
Y240550D01*
X518990Y239930D01*
G01Y237450D02*
X519910D01*
G01X521898Y237812D02*
X522167Y237553D01*
X522473Y237450D01*
X522780Y237553D01*
X523048Y237863D01*
X523240Y238328D01*
X523317Y238793D01*
Y239362D01*
X523240Y239827D01*
X523048Y240240D01*
X522818Y240447D01*
X522550Y240550D01*
X522243Y240447D01*
X522013Y240240D01*
X521860Y239930D01*
X521783Y239517D01*
X521860Y239155D01*
X522052Y238793D01*
X522282Y238587D01*
X522550Y238535D01*
X522857Y238638D01*
X523087Y238897D01*
X523317Y239362D01*
G01X524807Y237915D02*
X525037Y237657D01*
X525305Y237502D01*
X525650Y237450D01*
X525995Y237553D01*
X526263Y237760D01*
X526455Y238122D01*
X526493Y238535D01*
X526417Y238948D01*
X526225Y239207D01*
X525957Y239413D01*
X525688Y239465D01*
X525420Y239413D01*
X525075Y239207D01*
X525190Y240550D01*
X526225D01*
G01X501250Y265900D02*
X498750D01*
X499250Y265580D01*
G01X501250D02*
Y266220D01*
G01X498750Y268100D02*
X498833Y267887D01*
X499042Y267727D01*
X499292Y267620D01*
X499625Y267540D01*
X500000Y267513D01*
X500375Y267540D01*
X500708Y267620D01*
X500958Y267727D01*
X501167Y267887D01*
X501250Y268100D01*
X501167Y268313D01*
X500958Y268473D01*
X500708Y268580D01*
X500375Y268660D01*
X500000Y268687D01*
X499625Y268660D01*
X499292Y268580D01*
X499042Y268473D01*
X498833Y268313D01*
X498750Y268100D01*
G01X499493Y274492D02*
X499680Y274783D01*
X499840Y274950D01*
X500053Y275033D01*
X500240Y274950D01*
X500373Y274783D01*
X500480Y274533D01*
X500507Y274242D01*
X500480Y273992D01*
X500373Y273742D01*
X500213Y273533D01*
X500027Y273450D01*
X499813Y273533D01*
X499627Y273783D01*
X499520Y274158D01*
X499493Y274575D01*
X499547Y275117D01*
X499627Y275408D01*
X499760Y275700D01*
X499947Y275908D01*
X500133Y275950D01*
X500320Y275867D01*
X500453Y275658D01*
G01X508057Y283050D02*
Y280828D01*
X508210Y280363D01*
X508517Y280053D01*
X508900Y279950D01*
X509283Y280053D01*
X509590Y280363D01*
X509743Y280828D01*
Y283050D01*
G01X511272Y282533D02*
X511502Y282843D01*
X511770Y282998D01*
X512077Y283050D01*
X512460Y282947D01*
X512728Y282688D01*
X512805Y282378D01*
X512767Y282068D01*
X512613Y281810D01*
X511847Y281293D01*
X511502Y280932D01*
X511272Y280415D01*
X511195Y279950D01*
X512805D01*
G01X515100D02*
Y283050D01*
X514640Y282430D01*
G01Y279950D02*
X515560D01*
G01X502050Y333583D02*
X498950D01*
Y334542D01*
X499105Y334848D01*
X499312Y335040D01*
X499725Y335117D01*
X500138Y335040D01*
X500397Y334810D01*
X500552Y334542D01*
Y333583D01*
G01Y334542D02*
X502050Y335117D01*
G01Y337450D02*
X498950D01*
X499570Y336990D01*
G01X502050D02*
Y337910D01*
G01Y340550D02*
X498950D01*
X499570Y340090D01*
G01X502050D02*
Y341010D01*
G01X499467Y342922D02*
X499157Y343152D01*
X499002Y343420D01*
X498950Y343727D01*
X499053Y344110D01*
X499312Y344378D01*
X499622Y344455D01*
X499932Y344417D01*
X500190Y344263D01*
X500707Y343497D01*
X501068Y343152D01*
X501585Y342922D01*
X502050Y342845D01*
Y344455D01*
G01X507693Y372292D02*
X507463Y372447D01*
X507195Y372550D01*
X506888D01*
X506543Y372395D01*
X506275Y372137D01*
X506083Y371827D01*
X505930Y371310D01*
X505892Y370845D01*
X505968Y370380D01*
X506083Y370070D01*
X506313Y369760D01*
X506582Y369553D01*
X506850Y369450D01*
X507118D01*
X507387Y369553D01*
X507617Y369708D01*
X507808Y369915D01*
G01X509222Y372033D02*
X509452Y372343D01*
X509720Y372498D01*
X510027Y372550D01*
X510410Y372447D01*
X510678Y372188D01*
X510755Y371878D01*
X510717Y371568D01*
X510563Y371310D01*
X509797Y370793D01*
X509452Y370432D01*
X509222Y369915D01*
X509145Y369450D01*
X510755D01*
G01X512973D02*
X513050Y370122D01*
X513165Y370690D01*
X513318Y371207D01*
X513510Y371775D01*
X513817Y372550D01*
X512283D01*
G01X515422Y372033D02*
X515652Y372343D01*
X515920Y372498D01*
X516227Y372550D01*
X516610Y372447D01*
X516878Y372188D01*
X516955Y371878D01*
X516917Y371568D01*
X516763Y371310D01*
X515997Y370793D01*
X515652Y370432D01*
X515422Y369915D01*
X515345Y369450D01*
X516955D01*
G01X500923Y368450D02*
X501000Y369122D01*
X501115Y369690D01*
X501268Y370207D01*
X501460Y370775D01*
X501767Y371550D01*
X500233D01*
G01X499500Y389450D02*
Y392550D01*
X499040Y391930D01*
G01Y389450D02*
X499960D01*
G01X509208Y396243D02*
X509053Y396013D01*
X508950Y395745D01*
Y395438D01*
X509105Y395093D01*
X509363Y394825D01*
X509673Y394633D01*
X510190Y394480D01*
X510655Y394442D01*
X511120Y394518D01*
X511430Y394633D01*
X511740Y394863D01*
X511947Y395132D01*
X512050Y395400D01*
Y395668D01*
X511947Y395937D01*
X511792Y396167D01*
X511585Y396358D01*
G01X512050Y398423D02*
X511378Y398500D01*
X510810Y398615D01*
X510293Y398768D01*
X509725Y398960D01*
X508950Y399267D01*
Y397733D01*
G01X509467Y400872D02*
X509157Y401102D01*
X509002Y401370D01*
X508950Y401677D01*
X509053Y402060D01*
X509312Y402328D01*
X509622Y402405D01*
X509932Y402367D01*
X510190Y402213D01*
X510707Y401447D01*
X511068Y401102D01*
X511585Y400872D01*
X512050Y400795D01*
Y402405D01*
G01X512950Y394633D02*
X516050D01*
Y396167D01*
G01Y398500D02*
X512950D01*
X513570Y398040D01*
G01X516050D02*
Y398960D01*
G01X515585Y400757D02*
X515843Y400987D01*
X515998Y401255D01*
X516050Y401600D01*
X515947Y401945D01*
X515740Y402213D01*
X515378Y402405D01*
X514965Y402443D01*
X514552Y402367D01*
X514293Y402175D01*
X514087Y401907D01*
X514035Y401638D01*
X514087Y401370D01*
X514293Y401025D01*
X512950Y401140D01*
Y402175D01*
G01X515850Y407050D02*
Y403950D01*
G01X514968Y407050D02*
X516732D01*
G01X518183Y403950D02*
Y407050D01*
X519103D01*
X519410Y406895D01*
X519640Y406533D01*
X519717Y406120D01*
X519640Y405707D01*
X519448Y405397D01*
X519103Y405242D01*
X518183D01*
G01X522510Y403950D02*
Y407050D01*
X521092Y404828D01*
X523008D01*
G01X525610Y403950D02*
Y407050D01*
X524192Y404828D01*
X526108D01*
G01X533193Y58792D02*
X532963Y58947D01*
X532695Y59050D01*
X532388D01*
X532043Y58895D01*
X531775Y58637D01*
X531583Y58327D01*
X531430Y57810D01*
X531392Y57345D01*
X531468Y56880D01*
X531583Y56570D01*
X531813Y56260D01*
X532082Y56053D01*
X532350Y55950D01*
X532618D01*
X532887Y56053D01*
X533117Y56208D01*
X533308Y56415D01*
G01X534722Y58533D02*
X534952Y58843D01*
X535220Y58998D01*
X535527Y59050D01*
X535910Y58947D01*
X536178Y58688D01*
X536255Y58378D01*
X536217Y58068D01*
X536063Y57810D01*
X535297Y57293D01*
X534952Y56932D01*
X534722Y56415D01*
X534645Y55950D01*
X536255D01*
G01X537707Y56570D02*
X537937Y56208D01*
X538243Y56002D01*
X538588Y55950D01*
X538895Y56002D01*
X539202Y56260D01*
X539393Y56570D01*
X539432Y56880D01*
X539355Y57242D01*
X539087Y57500D01*
X538818Y57603D01*
X538473D01*
G01X538818D02*
X539048Y57758D01*
X539240Y58017D01*
X539317Y58327D01*
X539240Y58637D01*
X539048Y58895D01*
X538703Y59050D01*
X538358Y58998D01*
X538013Y58792D01*
G01X542110Y55950D02*
Y59050D01*
X540692Y56828D01*
X542608D01*
G01X531583Y61450D02*
Y64550D01*
X532542D01*
X532848Y64395D01*
X533040Y64188D01*
X533117Y63775D01*
X533040Y63362D01*
X532810Y63103D01*
X532542Y62948D01*
X531583D01*
G01X532542D02*
X533117Y61450D01*
G01X534722Y64033D02*
X534952Y64343D01*
X535220Y64498D01*
X535527Y64550D01*
X535910Y64447D01*
X536178Y64188D01*
X536255Y63878D01*
X536217Y63568D01*
X536063Y63310D01*
X535297Y62793D01*
X534952Y62432D01*
X534722Y61915D01*
X534645Y61450D01*
X536255D01*
G01X537707Y62070D02*
X537937Y61708D01*
X538243Y61502D01*
X538588Y61450D01*
X538895Y61502D01*
X539202Y61760D01*
X539393Y62070D01*
X539432Y62380D01*
X539355Y62742D01*
X539087Y63000D01*
X538818Y63103D01*
X538473D01*
G01X538818D02*
X539048Y63258D01*
X539240Y63517D01*
X539317Y63827D01*
X539240Y64137D01*
X539048Y64395D01*
X538703Y64550D01*
X538358Y64498D01*
X538013Y64292D01*
G01X541650Y61450D02*
Y64550D01*
X541190Y63930D01*
G01Y61450D02*
X542110D01*
G01X518348Y70312D02*
X518617Y70053D01*
X518923Y69950D01*
X519230Y70053D01*
X519498Y70363D01*
X519690Y70828D01*
X519767Y71293D01*
Y71862D01*
X519690Y72327D01*
X519498Y72740D01*
X519268Y72947D01*
X519000Y73050D01*
X518693Y72947D01*
X518463Y72740D01*
X518310Y72430D01*
X518233Y72017D01*
X518310Y71655D01*
X518502Y71293D01*
X518732Y71087D01*
X519000Y71035D01*
X519307Y71138D01*
X519537Y71397D01*
X519767Y71862D01*
G01X521083Y94450D02*
Y97550D01*
X522042D01*
X522348Y97395D01*
X522540Y97188D01*
X522617Y96775D01*
X522540Y96362D01*
X522310Y96103D01*
X522042Y95948D01*
X521083D01*
G01X522042D02*
X522617Y94450D01*
G01X525410D02*
Y97550D01*
X523992Y95328D01*
X525908D01*
G01X527973Y94450D02*
X528050Y95122D01*
X528165Y95690D01*
X528318Y96207D01*
X528510Y96775D01*
X528817Y97550D01*
X527283D01*
G01X530422Y95742D02*
X530690Y96103D01*
X530920Y96310D01*
X531227Y96413D01*
X531495Y96310D01*
X531687Y96103D01*
X531840Y95793D01*
X531878Y95432D01*
X531840Y95122D01*
X531687Y94812D01*
X531457Y94553D01*
X531188Y94450D01*
X530882Y94553D01*
X530613Y94863D01*
X530460Y95328D01*
X530422Y95845D01*
X530498Y96517D01*
X530613Y96878D01*
X530805Y97240D01*
X531073Y97498D01*
X531342Y97550D01*
X531610Y97447D01*
X531802Y97188D01*
G01X522243Y112292D02*
X522013Y112447D01*
X521745Y112550D01*
X521438D01*
X521093Y112395D01*
X520825Y112137D01*
X520633Y111827D01*
X520480Y111310D01*
X520442Y110845D01*
X520518Y110380D01*
X520633Y110070D01*
X520863Y109760D01*
X521132Y109553D01*
X521400Y109450D01*
X521668D01*
X521937Y109553D01*
X522167Y109708D01*
X522358Y109915D01*
G01X523848Y109812D02*
X524117Y109553D01*
X524423Y109450D01*
X524730Y109553D01*
X524998Y109863D01*
X525190Y110328D01*
X525267Y110793D01*
Y111362D01*
X525190Y111827D01*
X524998Y112240D01*
X524768Y112447D01*
X524500Y112550D01*
X524193Y112447D01*
X523963Y112240D01*
X523810Y111930D01*
X523733Y111517D01*
X523810Y111155D01*
X524002Y110793D01*
X524232Y110587D01*
X524500Y110535D01*
X524807Y110638D01*
X525037Y110897D01*
X525267Y111362D01*
G01X526872Y112033D02*
X527102Y112343D01*
X527370Y112498D01*
X527677Y112550D01*
X528060Y112447D01*
X528328Y112188D01*
X528405Y111878D01*
X528367Y111568D01*
X528213Y111310D01*
X527447Y110793D01*
X527102Y110432D01*
X526872Y109915D01*
X526795Y109450D01*
X528405D01*
G01X521083Y101450D02*
Y104550D01*
X522042D01*
X522348Y104395D01*
X522540Y104188D01*
X522617Y103775D01*
X522540Y103362D01*
X522310Y103103D01*
X522042Y102948D01*
X521083D01*
G01X522042D02*
X522617Y101450D01*
G01X525410D02*
Y104550D01*
X523992Y102328D01*
X525908D01*
G01X527973Y101450D02*
X528050Y102122D01*
X528165Y102690D01*
X528318Y103207D01*
X528510Y103775D01*
X528817Y104550D01*
X527283D01*
G01X531073Y101450D02*
X531150Y102122D01*
X531265Y102690D01*
X531418Y103207D01*
X531610Y103775D01*
X531917Y104550D01*
X530383D01*
G01X521083Y105450D02*
Y108550D01*
X522042D01*
X522348Y108395D01*
X522540Y108188D01*
X522617Y107775D01*
X522540Y107362D01*
X522310Y107103D01*
X522042Y106948D01*
X521083D01*
G01X522042D02*
X522617Y105450D01*
G01X525410D02*
Y108550D01*
X523992Y106328D01*
X525908D01*
G01X528050Y105450D02*
X528318Y105502D01*
X528625Y105657D01*
X528817Y105915D01*
X528893Y106277D01*
X528817Y106638D01*
X528587Y106948D01*
X528242Y107103D01*
X527858D01*
X527628Y107207D01*
X527437Y107465D01*
X527360Y107827D01*
X527475Y108188D01*
X527743Y108447D01*
X528050Y108550D01*
X528357Y108447D01*
X528625Y108188D01*
X528740Y107827D01*
X528663Y107465D01*
X528472Y107207D01*
X528242Y107103D01*
X527858D01*
X527513Y106948D01*
X527283Y106638D01*
X527207Y106277D01*
X527283Y105915D01*
X527475Y105657D01*
X527782Y105502D01*
X528050Y105450D01*
G01X531610D02*
Y108550D01*
X530192Y106328D01*
X532108D01*
G01X517133Y179050D02*
Y175950D01*
X518667D01*
G01X521000D02*
Y179050D01*
X520540Y178430D01*
G01Y175950D02*
X521460D01*
G01X523372Y178533D02*
X523602Y178843D01*
X523870Y178998D01*
X524177Y179050D01*
X524560Y178947D01*
X524828Y178688D01*
X524905Y178378D01*
X524867Y178068D01*
X524713Y177810D01*
X523947Y177293D01*
X523602Y176932D01*
X523372Y176415D01*
X523295Y175950D01*
X524905D01*
G01X532158Y191193D02*
X532003Y190963D01*
X531900Y190695D01*
Y190388D01*
X532055Y190043D01*
X532313Y189775D01*
X532623Y189583D01*
X533140Y189430D01*
X533605Y189392D01*
X534070Y189468D01*
X534380Y189583D01*
X534690Y189813D01*
X534897Y190082D01*
X535000Y190350D01*
Y190618D01*
X534897Y190887D01*
X534742Y191117D01*
X534535Y191308D01*
G01X532417Y192722D02*
X532107Y192952D01*
X531952Y193220D01*
X531900Y193527D01*
X532003Y193910D01*
X532262Y194178D01*
X532572Y194255D01*
X532882Y194217D01*
X533140Y194063D01*
X533657Y193297D01*
X534018Y192952D01*
X534535Y192722D01*
X535000Y192645D01*
Y194255D01*
G01Y196473D02*
X534328Y196550D01*
X533760Y196665D01*
X533243Y196818D01*
X532675Y197010D01*
X531900Y197317D01*
Y195783D01*
G01Y199650D02*
X532003Y199343D01*
X532262Y199113D01*
X532572Y198960D01*
X532985Y198845D01*
X533450Y198807D01*
X533915Y198845D01*
X534328Y198960D01*
X534638Y199113D01*
X534897Y199343D01*
X535000Y199650D01*
X534897Y199957D01*
X534638Y200187D01*
X534328Y200340D01*
X533915Y200455D01*
X533450Y200493D01*
X532985Y200455D01*
X532572Y200340D01*
X532262Y200187D01*
X532003Y199957D01*
X531900Y199650D01*
G01X530708Y205193D02*
X530553Y204963D01*
X530450Y204695D01*
Y204388D01*
X530605Y204043D01*
X530863Y203775D01*
X531173Y203583D01*
X531690Y203430D01*
X532155Y203392D01*
X532620Y203468D01*
X532930Y203583D01*
X533240Y203813D01*
X533447Y204082D01*
X533550Y204350D01*
Y204618D01*
X533447Y204887D01*
X533292Y205117D01*
X533085Y205308D01*
G01X530967Y206722D02*
X530657Y206952D01*
X530502Y207220D01*
X530450Y207527D01*
X530553Y207910D01*
X530812Y208178D01*
X531122Y208255D01*
X531432Y208217D01*
X531690Y208063D01*
X532207Y207297D01*
X532568Y206952D01*
X533085Y206722D01*
X533550Y206645D01*
Y208255D01*
G01X532258Y209822D02*
X531897Y210090D01*
X531690Y210320D01*
X531587Y210627D01*
X531690Y210895D01*
X531897Y211087D01*
X532207Y211240D01*
X532568Y211278D01*
X532878Y211240D01*
X533188Y211087D01*
X533447Y210857D01*
X533550Y210588D01*
X533447Y210282D01*
X533137Y210013D01*
X532672Y209860D01*
X532155Y209822D01*
X531483Y209898D01*
X531122Y210013D01*
X530760Y210205D01*
X530502Y210473D01*
X530450Y210742D01*
X530553Y211010D01*
X530812Y211202D01*
G01X533550Y213650D02*
X530450D01*
X531070Y213190D01*
G01X533550D02*
Y214110D01*
G01X526208Y205193D02*
X526053Y204963D01*
X525950Y204695D01*
Y204388D01*
X526105Y204043D01*
X526363Y203775D01*
X526673Y203583D01*
X527190Y203430D01*
X527655Y203392D01*
X528120Y203468D01*
X528430Y203583D01*
X528740Y203813D01*
X528947Y204082D01*
X529050Y204350D01*
Y204618D01*
X528947Y204887D01*
X528792Y205117D01*
X528585Y205308D01*
G01X526467Y206722D02*
X526157Y206952D01*
X526002Y207220D01*
X525950Y207527D01*
X526053Y207910D01*
X526312Y208178D01*
X526622Y208255D01*
X526932Y208217D01*
X527190Y208063D01*
X527707Y207297D01*
X528068Y206952D01*
X528585Y206722D01*
X529050Y206645D01*
Y208255D01*
G01X527758Y209822D02*
X527397Y210090D01*
X527190Y210320D01*
X527087Y210627D01*
X527190Y210895D01*
X527397Y211087D01*
X527707Y211240D01*
X528068Y211278D01*
X528378Y211240D01*
X528688Y211087D01*
X528947Y210857D01*
X529050Y210588D01*
X528947Y210282D01*
X528637Y210013D01*
X528172Y209860D01*
X527655Y209822D01*
X526983Y209898D01*
X526622Y210013D01*
X526260Y210205D01*
X526002Y210473D01*
X525950Y210742D01*
X526053Y211010D01*
X526312Y211202D01*
G01X525950Y213650D02*
X526053Y213343D01*
X526312Y213113D01*
X526622Y212960D01*
X527035Y212845D01*
X527500Y212807D01*
X527965Y212845D01*
X528378Y212960D01*
X528688Y213113D01*
X528947Y213343D01*
X529050Y213650D01*
X528947Y213957D01*
X528688Y214187D01*
X528378Y214340D01*
X527965Y214455D01*
X527500Y214493D01*
X527035Y214455D01*
X526622Y214340D01*
X526312Y214187D01*
X526053Y213957D01*
X525950Y213650D01*
G01X523208Y223693D02*
X523053Y223463D01*
X522950Y223195D01*
Y222888D01*
X523105Y222543D01*
X523363Y222275D01*
X523673Y222083D01*
X524190Y221930D01*
X524655Y221892D01*
X525120Y221968D01*
X525430Y222083D01*
X525740Y222313D01*
X525947Y222582D01*
X526050Y222850D01*
Y223118D01*
X525947Y223387D01*
X525792Y223617D01*
X525585Y223808D01*
G01X523467Y225222D02*
X523157Y225452D01*
X523002Y225720D01*
X522950Y226027D01*
X523053Y226410D01*
X523312Y226678D01*
X523622Y226755D01*
X523932Y226717D01*
X524190Y226563D01*
X524707Y225797D01*
X525068Y225452D01*
X525585Y225222D01*
X526050Y225145D01*
Y226755D01*
G01X525585Y228207D02*
X525843Y228437D01*
X525998Y228705D01*
X526050Y229050D01*
X525947Y229395D01*
X525740Y229663D01*
X525378Y229855D01*
X524965Y229893D01*
X524552Y229817D01*
X524293Y229625D01*
X524087Y229357D01*
X524035Y229088D01*
X524087Y228820D01*
X524293Y228475D01*
X522950Y228590D01*
Y229625D01*
G01X525585Y231307D02*
X525843Y231537D01*
X525998Y231805D01*
X526050Y232150D01*
X525947Y232495D01*
X525740Y232763D01*
X525378Y232955D01*
X524965Y232993D01*
X524552Y232917D01*
X524293Y232725D01*
X524087Y232457D01*
X524035Y232188D01*
X524087Y231920D01*
X524293Y231575D01*
X522950Y231690D01*
Y232725D01*
G01X526950Y225683D02*
X530050D01*
Y227217D01*
G01X529688Y228898D02*
X529947Y229167D01*
X530050Y229473D01*
X529947Y229780D01*
X529637Y230048D01*
X529172Y230240D01*
X528707Y230317D01*
X528138D01*
X527673Y230240D01*
X527260Y230048D01*
X527053Y229818D01*
X526950Y229550D01*
X527053Y229243D01*
X527260Y229013D01*
X527570Y228860D01*
X527983Y228783D01*
X528345Y228860D01*
X528707Y229052D01*
X528913Y229282D01*
X528965Y229550D01*
X528862Y229857D01*
X528603Y230087D01*
X528138Y230317D01*
G01X527850Y236550D02*
Y233450D01*
G01X526968Y236550D02*
X528732D01*
G01X530183Y233450D02*
Y236550D01*
X531103D01*
X531410Y236395D01*
X531640Y236033D01*
X531717Y235620D01*
X531640Y235207D01*
X531448Y234897D01*
X531103Y234742D01*
X530183D01*
G01X533207Y233915D02*
X533437Y233657D01*
X533705Y233502D01*
X534050Y233450D01*
X534395Y233553D01*
X534663Y233760D01*
X534855Y234122D01*
X534893Y234535D01*
X534817Y234948D01*
X534625Y235207D01*
X534357Y235413D01*
X534088Y235465D01*
X533820Y235413D01*
X533475Y235207D01*
X533590Y236550D01*
X534625D01*
G01X536422Y236033D02*
X536652Y236343D01*
X536920Y236498D01*
X537227Y236550D01*
X537610Y236447D01*
X537878Y236188D01*
X537955Y235878D01*
X537917Y235568D01*
X537763Y235310D01*
X536997Y234793D01*
X536652Y234432D01*
X536422Y233915D01*
X536345Y233450D01*
X537955D01*
G01X531550Y238583D02*
X528450D01*
Y239542D01*
X528605Y239848D01*
X528812Y240040D01*
X529225Y240117D01*
X529638Y240040D01*
X529897Y239810D01*
X530052Y239542D01*
Y238583D01*
G01Y239542D02*
X531550Y240117D01*
G01Y242450D02*
X528450D01*
X529070Y241990D01*
G01X531550D02*
Y242910D01*
G01Y245550D02*
X531498Y245818D01*
X531343Y246125D01*
X531085Y246317D01*
X530723Y246393D01*
X530362Y246317D01*
X530052Y246087D01*
X529897Y245742D01*
Y245358D01*
X529793Y245128D01*
X529535Y244937D01*
X529173Y244860D01*
X528812Y244975D01*
X528553Y245243D01*
X528450Y245550D01*
X528553Y245857D01*
X528812Y246125D01*
X529173Y246240D01*
X529535Y246163D01*
X529793Y245972D01*
X529897Y245742D01*
Y245358D01*
X530052Y245013D01*
X530362Y244783D01*
X530723Y244707D01*
X531085Y244783D01*
X531343Y244975D01*
X531498Y245282D01*
X531550Y245550D01*
G01Y248573D02*
X530878Y248650D01*
X530310Y248765D01*
X529793Y248918D01*
X529225Y249110D01*
X528450Y249417D01*
Y247883D01*
G01X535550Y238583D02*
X532450D01*
Y239542D01*
X532605Y239848D01*
X532812Y240040D01*
X533225Y240117D01*
X533638Y240040D01*
X533897Y239810D01*
X534052Y239542D01*
Y238583D01*
G01Y239542D02*
X535550Y240117D01*
G01Y242450D02*
X532450D01*
X533070Y241990D01*
G01X535550D02*
Y242910D01*
G01X535188Y244898D02*
X535447Y245167D01*
X535550Y245473D01*
X535447Y245780D01*
X535137Y246048D01*
X534672Y246240D01*
X534207Y246317D01*
X533638D01*
X533173Y246240D01*
X532760Y246048D01*
X532553Y245818D01*
X532450Y245550D01*
X532553Y245243D01*
X532760Y245013D01*
X533070Y244860D01*
X533483Y244783D01*
X533845Y244860D01*
X534207Y245052D01*
X534413Y245282D01*
X534465Y245550D01*
X534362Y245857D01*
X534103Y246087D01*
X533638Y246317D01*
G01X532450Y248650D02*
X532553Y248343D01*
X532812Y248113D01*
X533122Y247960D01*
X533535Y247845D01*
X534000Y247807D01*
X534465Y247845D01*
X534878Y247960D01*
X535188Y248113D01*
X535447Y248343D01*
X535550Y248650D01*
X535447Y248957D01*
X535188Y249187D01*
X534878Y249340D01*
X534465Y249455D01*
X534000Y249493D01*
X533535Y249455D01*
X533122Y249340D01*
X532812Y249187D01*
X532553Y248957D01*
X532450Y248650D01*
G01X527693Y287292D02*
X527463Y287447D01*
X527195Y287550D01*
X526888D01*
X526543Y287395D01*
X526275Y287137D01*
X526083Y286827D01*
X525930Y286310D01*
X525892Y285845D01*
X525968Y285380D01*
X526083Y285070D01*
X526313Y284760D01*
X526582Y284553D01*
X526850Y284450D01*
X527118D01*
X527387Y284553D01*
X527617Y284708D01*
X527808Y284915D01*
G01X529950Y284450D02*
Y287550D01*
X529490Y286930D01*
G01Y284450D02*
X530410D01*
G01X532398Y284812D02*
X532667Y284553D01*
X532973Y284450D01*
X533280Y284553D01*
X533548Y284863D01*
X533740Y285328D01*
X533817Y285793D01*
Y286362D01*
X533740Y286827D01*
X533548Y287240D01*
X533318Y287447D01*
X533050Y287550D01*
X532743Y287447D01*
X532513Y287240D01*
X532360Y286930D01*
X532283Y286517D01*
X532360Y286155D01*
X532552Y285793D01*
X532782Y285587D01*
X533050Y285535D01*
X533357Y285638D01*
X533587Y285897D01*
X533817Y286362D01*
G01X535307Y285070D02*
X535537Y284708D01*
X535843Y284502D01*
X536188Y284450D01*
X536495Y284502D01*
X536802Y284760D01*
X536993Y285070D01*
X537032Y285380D01*
X536955Y285742D01*
X536687Y286000D01*
X536418Y286103D01*
X536073D01*
G01X536418D02*
X536648Y286258D01*
X536840Y286517D01*
X536917Y286827D01*
X536840Y287137D01*
X536648Y287395D01*
X536303Y287550D01*
X535958Y287498D01*
X535613Y287292D01*
G01X521413Y272325D02*
X521573Y272117D01*
X521760Y271992D01*
X522000Y271950D01*
X522240Y272033D01*
X522427Y272200D01*
X522560Y272492D01*
X522587Y272825D01*
X522533Y273158D01*
X522400Y273367D01*
X522213Y273533D01*
X522027Y273575D01*
X521840Y273533D01*
X521600Y273367D01*
X521680Y274450D01*
X522400D01*
G01X532550Y290083D02*
X529450D01*
Y291042D01*
X529605Y291348D01*
X529812Y291540D01*
X530225Y291617D01*
X530638Y291540D01*
X530897Y291310D01*
X531052Y291042D01*
Y290083D01*
G01Y291042D02*
X532550Y291617D01*
G01Y293950D02*
X529450D01*
X530070Y293490D01*
G01X532550D02*
Y294410D01*
G01Y296973D02*
X531878Y297050D01*
X531310Y297165D01*
X530793Y297318D01*
X530225Y297510D01*
X529450Y297817D01*
Y296283D01*
G01X532188Y299498D02*
X532447Y299767D01*
X532550Y300073D01*
X532447Y300380D01*
X532137Y300648D01*
X531672Y300840D01*
X531207Y300917D01*
X530638D01*
X530173Y300840D01*
X529760Y300648D01*
X529553Y300418D01*
X529450Y300150D01*
X529553Y299843D01*
X529760Y299613D01*
X530070Y299460D01*
X530483Y299383D01*
X530845Y299460D01*
X531207Y299652D01*
X531413Y299882D01*
X531465Y300150D01*
X531362Y300457D01*
X531103Y300687D01*
X530638Y300917D01*
G01X518542Y329950D02*
X519500Y333050D01*
X520458Y329950D01*
G01X520113Y331035D02*
X518887D01*
G01X525708Y356743D02*
X525553Y356513D01*
X525450Y356245D01*
Y355938D01*
X525605Y355593D01*
X525863Y355325D01*
X526173Y355133D01*
X526690Y354980D01*
X527155Y354942D01*
X527620Y355018D01*
X527930Y355133D01*
X528240Y355363D01*
X528447Y355632D01*
X528550Y355900D01*
Y356168D01*
X528447Y356437D01*
X528292Y356667D01*
X528085Y356858D01*
G01X528550Y359000D02*
X525450D01*
X526070Y358540D01*
G01X528550D02*
Y359460D01*
G01X525450Y362100D02*
X525553Y361793D01*
X525812Y361563D01*
X526122Y361410D01*
X526535Y361295D01*
X527000Y361257D01*
X527465Y361295D01*
X527878Y361410D01*
X528188Y361563D01*
X528447Y361793D01*
X528550Y362100D01*
X528447Y362407D01*
X528188Y362637D01*
X527878Y362790D01*
X527465Y362905D01*
X527000Y362943D01*
X526535Y362905D01*
X526122Y362790D01*
X525812Y362637D01*
X525553Y362407D01*
X525450Y362100D01*
G01X534793Y350392D02*
X534563Y350547D01*
X534295Y350650D01*
X533988D01*
X533643Y350495D01*
X533375Y350237D01*
X533183Y349927D01*
X533030Y349410D01*
X532992Y348945D01*
X533068Y348480D01*
X533183Y348170D01*
X533413Y347860D01*
X533682Y347653D01*
X533950Y347550D01*
X534218D01*
X534487Y347653D01*
X534717Y347808D01*
X534908Y348015D01*
G01X536283Y347550D02*
Y350650D01*
X537242D01*
X537548Y350495D01*
X537740Y350288D01*
X537817Y349875D01*
X537740Y349462D01*
X537510Y349203D01*
X537242Y349048D01*
X536283D01*
G01X537242D02*
X537817Y347550D01*
G01X540150D02*
Y350650D01*
X539690Y350030D01*
G01Y347550D02*
X540610D01*
G01X543250Y350650D02*
X542943Y350547D01*
X542713Y350288D01*
X542560Y349978D01*
X542445Y349565D01*
X542407Y349100D01*
X542445Y348635D01*
X542560Y348222D01*
X542713Y347912D01*
X542943Y347653D01*
X543250Y347550D01*
X543557Y347653D01*
X543787Y347912D01*
X543940Y348222D01*
X544055Y348635D01*
X544093Y349100D01*
X544055Y349565D01*
X543940Y349978D01*
X543787Y350288D01*
X543557Y350547D01*
X543250Y350650D01*
G01X532208Y358293D02*
X532053Y358063D01*
X531950Y357795D01*
Y357488D01*
X532105Y357143D01*
X532363Y356875D01*
X532673Y356683D01*
X533190Y356530D01*
X533655Y356492D01*
X534120Y356568D01*
X534430Y356683D01*
X534740Y356913D01*
X534947Y357182D01*
X535050Y357450D01*
Y357718D01*
X534947Y357987D01*
X534792Y358217D01*
X534585Y358408D01*
G01X534688Y359898D02*
X534947Y360167D01*
X535050Y360473D01*
X534947Y360780D01*
X534637Y361048D01*
X534172Y361240D01*
X533707Y361317D01*
X533138D01*
X532673Y361240D01*
X532260Y361048D01*
X532053Y360818D01*
X531950Y360550D01*
X532053Y360243D01*
X532260Y360013D01*
X532570Y359860D01*
X532983Y359783D01*
X533345Y359860D01*
X533707Y360052D01*
X533913Y360282D01*
X533965Y360550D01*
X533862Y360857D01*
X533603Y361087D01*
X533138Y361317D01*
G01X523393Y382492D02*
X523163Y382647D01*
X522895Y382750D01*
X522588D01*
X522243Y382595D01*
X521975Y382337D01*
X521783Y382027D01*
X521630Y381510D01*
X521592Y381045D01*
X521668Y380580D01*
X521783Y380270D01*
X522013Y379960D01*
X522282Y379753D01*
X522550Y379650D01*
X522818D01*
X523087Y379753D01*
X523317Y379908D01*
X523508Y380115D01*
G01X524922Y380942D02*
X525190Y381303D01*
X525420Y381510D01*
X525727Y381613D01*
X525995Y381510D01*
X526187Y381303D01*
X526340Y380993D01*
X526378Y380632D01*
X526340Y380322D01*
X526187Y380012D01*
X525957Y379753D01*
X525688Y379650D01*
X525382Y379753D01*
X525113Y380063D01*
X524960Y380528D01*
X524922Y381045D01*
X524998Y381717D01*
X525113Y382078D01*
X525305Y382440D01*
X525573Y382698D01*
X525842Y382750D01*
X526110Y382647D01*
X526302Y382388D01*
G01X521683Y389950D02*
Y393050D01*
X522642D01*
X522948Y392895D01*
X523140Y392688D01*
X523217Y392275D01*
X523140Y391862D01*
X522910Y391603D01*
X522642Y391448D01*
X521683D01*
G01X522642D02*
X523217Y389950D01*
G01X524898Y390312D02*
X525167Y390053D01*
X525473Y389950D01*
X525780Y390053D01*
X526048Y390363D01*
X526240Y390828D01*
X526317Y391293D01*
Y391862D01*
X526240Y392327D01*
X526048Y392740D01*
X525818Y392947D01*
X525550Y393050D01*
X525243Y392947D01*
X525013Y392740D01*
X524860Y392430D01*
X524783Y392017D01*
X524860Y391655D01*
X525052Y391293D01*
X525282Y391087D01*
X525550Y391035D01*
X525857Y391138D01*
X526087Y391397D01*
X526317Y391862D01*
G01X522133Y395450D02*
Y398550D01*
X523092D01*
X523398Y398395D01*
X523590Y398188D01*
X523667Y397775D01*
X523590Y397362D01*
X523360Y397103D01*
X523092Y396948D01*
X522133D01*
G01X523092D02*
X523667Y395450D01*
G01X526000D02*
Y398550D01*
X525540Y397930D01*
G01Y395450D02*
X526460D01*
G01X529100D02*
Y398550D01*
X528640Y397930D01*
G01Y395450D02*
X529560D01*
G01X523087Y411242D02*
X522927Y411367D01*
X522740Y411450D01*
X522527D01*
X522287Y411325D01*
X522100Y411117D01*
X521967Y410867D01*
X521860Y410450D01*
X521833Y410075D01*
X521887Y409700D01*
X521967Y409450D01*
X522127Y409200D01*
X522313Y409033D01*
X522500Y408950D01*
X522687D01*
X522873Y409033D01*
X523033Y409158D01*
X523167Y409325D01*
G01X521050Y414557D02*
X517950D01*
Y415323D01*
X518105Y415630D01*
X518312Y415860D01*
X518622Y416052D01*
X518983Y416205D01*
X519500Y416243D01*
X520017Y416205D01*
X520378Y416052D01*
X520688Y415860D01*
X520895Y415630D01*
X521050Y415323D01*
Y414557D01*
G01X520637Y417695D02*
X520895Y418002D01*
X521050Y418347D01*
Y418653D01*
X520895Y418960D01*
X520637Y419190D01*
X520275Y419305D01*
X519913Y419228D01*
X519603Y419037D01*
X519397Y418692D01*
X519293Y418232D01*
X519087Y417963D01*
X518725Y417848D01*
X518363Y417925D01*
X518105Y418117D01*
X517950Y418385D01*
Y418653D01*
X518053Y418922D01*
X518312Y419152D01*
G01X520688Y420948D02*
X520947Y421217D01*
X521050Y421523D01*
X520947Y421830D01*
X520637Y422098D01*
X520172Y422290D01*
X519707Y422367D01*
X519138D01*
X518673Y422290D01*
X518260Y422098D01*
X518053Y421868D01*
X517950Y421600D01*
X518053Y421293D01*
X518260Y421063D01*
X518570Y420910D01*
X518983Y420833D01*
X519345Y420910D01*
X519707Y421102D01*
X519913Y421332D01*
X519965Y421600D01*
X519862Y421907D01*
X519603Y422137D01*
X519138Y422367D01*
G01X526833Y425250D02*
X527500Y427750D01*
X528167Y425250D01*
G01X527927Y426125D02*
X527073D01*
G01X550157Y61415D02*
X550387Y61157D01*
X550655Y61002D01*
X551000Y60950D01*
X551345Y61053D01*
X551613Y61260D01*
X551805Y61622D01*
X551843Y62035D01*
X551767Y62448D01*
X551575Y62707D01*
X551307Y62913D01*
X551038Y62965D01*
X550770Y62913D01*
X550425Y62707D01*
X550540Y64050D01*
X551575D01*
G01X535350Y75550D02*
Y72450D01*
G01X534468Y75550D02*
X536232D01*
G01X537683Y72450D02*
Y75550D01*
X538603D01*
X538910Y75395D01*
X539140Y75033D01*
X539217Y74620D01*
X539140Y74207D01*
X538948Y73897D01*
X538603Y73742D01*
X537683D01*
G01X540707Y72915D02*
X540937Y72657D01*
X541205Y72502D01*
X541550Y72450D01*
X541895Y72553D01*
X542163Y72760D01*
X542355Y73122D01*
X542393Y73535D01*
X542317Y73948D01*
X542125Y74207D01*
X541857Y74413D01*
X541588Y74465D01*
X541320Y74413D01*
X540975Y74207D01*
X541090Y75550D01*
X542125D01*
G01X544573Y72450D02*
X544650Y73122D01*
X544765Y73690D01*
X544918Y74207D01*
X545110Y74775D01*
X545417Y75550D01*
X543883D01*
G01X535693Y85792D02*
X535463Y85947D01*
X535195Y86050D01*
X534888D01*
X534543Y85895D01*
X534275Y85637D01*
X534083Y85327D01*
X533930Y84810D01*
X533892Y84345D01*
X533968Y83880D01*
X534083Y83570D01*
X534313Y83260D01*
X534582Y83053D01*
X534850Y82950D01*
X535118D01*
X535387Y83053D01*
X535617Y83208D01*
X535808Y83415D01*
G01X537222Y85533D02*
X537452Y85843D01*
X537720Y85998D01*
X538027Y86050D01*
X538410Y85947D01*
X538678Y85688D01*
X538755Y85378D01*
X538717Y85068D01*
X538563Y84810D01*
X537797Y84293D01*
X537452Y83932D01*
X537222Y83415D01*
X537145Y82950D01*
X538755D01*
G01X541510D02*
Y86050D01*
X540092Y83828D01*
X542008D01*
G01X543422Y85533D02*
X543652Y85843D01*
X543920Y85998D01*
X544227Y86050D01*
X544610Y85947D01*
X544878Y85688D01*
X544955Y85378D01*
X544917Y85068D01*
X544763Y84810D01*
X543997Y84293D01*
X543652Y83932D01*
X543422Y83415D01*
X543345Y82950D01*
X544955D01*
G01X535193Y91792D02*
X534963Y91947D01*
X534695Y92050D01*
X534388D01*
X534043Y91895D01*
X533775Y91637D01*
X533583Y91327D01*
X533430Y90810D01*
X533392Y90345D01*
X533468Y89880D01*
X533583Y89570D01*
X533813Y89260D01*
X534082Y89053D01*
X534350Y88950D01*
X534618D01*
X534887Y89053D01*
X535117Y89208D01*
X535308Y89415D01*
G01X536722Y91533D02*
X536952Y91843D01*
X537220Y91998D01*
X537527Y92050D01*
X537910Y91947D01*
X538178Y91688D01*
X538255Y91378D01*
X538217Y91068D01*
X538063Y90810D01*
X537297Y90293D01*
X536952Y89932D01*
X536722Y89415D01*
X536645Y88950D01*
X538255D01*
G01X539707Y89570D02*
X539937Y89208D01*
X540243Y89002D01*
X540588Y88950D01*
X540895Y89002D01*
X541202Y89260D01*
X541393Y89570D01*
X541432Y89880D01*
X541355Y90242D01*
X541087Y90500D01*
X540818Y90603D01*
X540473D01*
G01X540818D02*
X541048Y90758D01*
X541240Y91017D01*
X541317Y91327D01*
X541240Y91637D01*
X541048Y91895D01*
X540703Y92050D01*
X540358Y91998D01*
X540013Y91792D01*
G01X542998Y89312D02*
X543267Y89053D01*
X543573Y88950D01*
X543880Y89053D01*
X544148Y89363D01*
X544340Y89828D01*
X544417Y90293D01*
Y90862D01*
X544340Y91327D01*
X544148Y91740D01*
X543918Y91947D01*
X543650Y92050D01*
X543343Y91947D01*
X543113Y91740D01*
X542960Y91430D01*
X542883Y91017D01*
X542960Y90655D01*
X543152Y90293D01*
X543382Y90087D01*
X543650Y90035D01*
X543957Y90138D01*
X544187Y90397D01*
X544417Y90862D01*
G01X537850Y104050D02*
Y100950D01*
G01X536968Y104050D02*
X538732D01*
G01X540183Y100950D02*
Y104050D01*
X541103D01*
X541410Y103895D01*
X541640Y103533D01*
X541717Y103120D01*
X541640Y102707D01*
X541448Y102397D01*
X541103Y102242D01*
X540183D01*
G01X544510Y100950D02*
Y104050D01*
X543092Y101828D01*
X545008D01*
G01X546422Y102242D02*
X546690Y102603D01*
X546920Y102810D01*
X547227Y102913D01*
X547495Y102810D01*
X547687Y102603D01*
X547840Y102293D01*
X547878Y101932D01*
X547840Y101622D01*
X547687Y101312D01*
X547457Y101053D01*
X547188Y100950D01*
X546882Y101053D01*
X546613Y101363D01*
X546460Y101828D01*
X546422Y102345D01*
X546498Y103017D01*
X546613Y103378D01*
X546805Y103740D01*
X547073Y103998D01*
X547342Y104050D01*
X547610Y103947D01*
X547802Y103688D01*
G01X538193Y124292D02*
X537963Y124447D01*
X537695Y124550D01*
X537388D01*
X537043Y124395D01*
X536775Y124137D01*
X536583Y123827D01*
X536430Y123310D01*
X536392Y122845D01*
X536468Y122380D01*
X536583Y122070D01*
X536813Y121760D01*
X537082Y121553D01*
X537350Y121450D01*
X537618D01*
X537887Y121553D01*
X538117Y121708D01*
X538308Y121915D01*
G01X540450Y121450D02*
Y124550D01*
X539990Y123930D01*
G01Y121450D02*
X540910D01*
G01X543473D02*
X543550Y122122D01*
X543665Y122690D01*
X543818Y123207D01*
X544010Y123775D01*
X544317Y124550D01*
X542783D01*
G01X545807Y122070D02*
X546037Y121708D01*
X546343Y121502D01*
X546688Y121450D01*
X546995Y121502D01*
X547302Y121760D01*
X547493Y122070D01*
X547532Y122380D01*
X547455Y122742D01*
X547187Y123000D01*
X546918Y123103D01*
X546573D01*
G01X546918D02*
X547148Y123258D01*
X547340Y123517D01*
X547417Y123827D01*
X547340Y124137D01*
X547148Y124395D01*
X546803Y124550D01*
X546458Y124498D01*
X546113Y124292D01*
G01X538193Y128292D02*
X537963Y128447D01*
X537695Y128550D01*
X537388D01*
X537043Y128395D01*
X536775Y128137D01*
X536583Y127827D01*
X536430Y127310D01*
X536392Y126845D01*
X536468Y126380D01*
X536583Y126070D01*
X536813Y125760D01*
X537082Y125553D01*
X537350Y125450D01*
X537618D01*
X537887Y125553D01*
X538117Y125708D01*
X538308Y125915D01*
G01X540450Y125450D02*
Y128550D01*
X539990Y127930D01*
G01Y125450D02*
X540910D01*
G01X543473D02*
X543550Y126122D01*
X543665Y126690D01*
X543818Y127207D01*
X544010Y127775D01*
X544317Y128550D01*
X542783D01*
G01X545922Y126742D02*
X546190Y127103D01*
X546420Y127310D01*
X546727Y127413D01*
X546995Y127310D01*
X547187Y127103D01*
X547340Y126793D01*
X547378Y126432D01*
X547340Y126122D01*
X547187Y125812D01*
X546957Y125553D01*
X546688Y125450D01*
X546382Y125553D01*
X546113Y125863D01*
X545960Y126328D01*
X545922Y126845D01*
X545998Y127517D01*
X546113Y127878D01*
X546305Y128240D01*
X546573Y128498D01*
X546842Y128550D01*
X547110Y128447D01*
X547302Y128188D01*
G01X537708Y146193D02*
X537553Y145963D01*
X537450Y145695D01*
Y145388D01*
X537605Y145043D01*
X537863Y144775D01*
X538173Y144583D01*
X538690Y144430D01*
X539155Y144392D01*
X539620Y144468D01*
X539930Y144583D01*
X540240Y144813D01*
X540447Y145082D01*
X540550Y145350D01*
Y145618D01*
X540447Y145887D01*
X540292Y146117D01*
X540085Y146308D01*
G01X537967Y147722D02*
X537657Y147952D01*
X537502Y148220D01*
X537450Y148527D01*
X537553Y148910D01*
X537812Y149178D01*
X538122Y149255D01*
X538432Y149217D01*
X538690Y149063D01*
X539207Y148297D01*
X539568Y147952D01*
X540085Y147722D01*
X540550Y147645D01*
Y149255D01*
G01Y151473D02*
X539878Y151550D01*
X539310Y151665D01*
X538793Y151818D01*
X538225Y152010D01*
X537450Y152317D01*
Y150783D01*
G01X540550Y154650D02*
X537450D01*
X538070Y154190D01*
G01X540550D02*
Y155110D01*
G01X538193Y132792D02*
X537963Y132947D01*
X537695Y133050D01*
X537388D01*
X537043Y132895D01*
X536775Y132637D01*
X536583Y132327D01*
X536430Y131810D01*
X536392Y131345D01*
X536468Y130880D01*
X536583Y130570D01*
X536813Y130260D01*
X537082Y130053D01*
X537350Y129950D01*
X537618D01*
X537887Y130053D01*
X538117Y130208D01*
X538308Y130415D01*
G01X540450Y129950D02*
Y133050D01*
X539990Y132430D01*
G01Y129950D02*
X540910D01*
G01X543473D02*
X543550Y130622D01*
X543665Y131190D01*
X543818Y131707D01*
X544010Y132275D01*
X544317Y133050D01*
X542783D01*
G01X546573Y129950D02*
X546650Y130622D01*
X546765Y131190D01*
X546918Y131707D01*
X547110Y132275D01*
X547417Y133050D01*
X545883D01*
G01X538193Y136792D02*
X537963Y136947D01*
X537695Y137050D01*
X537388D01*
X537043Y136895D01*
X536775Y136637D01*
X536583Y136327D01*
X536430Y135810D01*
X536392Y135345D01*
X536468Y134880D01*
X536583Y134570D01*
X536813Y134260D01*
X537082Y134053D01*
X537350Y133950D01*
X537618D01*
X537887Y134053D01*
X538117Y134208D01*
X538308Y134415D01*
G01X540450Y133950D02*
Y137050D01*
X539990Y136430D01*
G01Y133950D02*
X540910D01*
G01X543473D02*
X543550Y134622D01*
X543665Y135190D01*
X543818Y135707D01*
X544010Y136275D01*
X544317Y137050D01*
X542783D01*
G01X545807Y134415D02*
X546037Y134157D01*
X546305Y134002D01*
X546650Y133950D01*
X546995Y134053D01*
X547263Y134260D01*
X547455Y134622D01*
X547493Y135035D01*
X547417Y135448D01*
X547225Y135707D01*
X546957Y135913D01*
X546688Y135965D01*
X546420Y135913D01*
X546075Y135707D01*
X546190Y137050D01*
X547225D01*
G01X545183Y164550D02*
Y161450D01*
X546717D01*
G01X548207Y161915D02*
X548437Y161657D01*
X548705Y161502D01*
X549050Y161450D01*
X549395Y161553D01*
X549663Y161760D01*
X549855Y162122D01*
X549893Y162535D01*
X549817Y162948D01*
X549625Y163207D01*
X549357Y163413D01*
X549088Y163465D01*
X548820Y163413D01*
X548475Y163207D01*
X548590Y164550D01*
X549625D01*
G01X539208Y190693D02*
X539053Y190463D01*
X538950Y190195D01*
Y189888D01*
X539105Y189543D01*
X539363Y189275D01*
X539673Y189083D01*
X540190Y188930D01*
X540655Y188892D01*
X541120Y188968D01*
X541430Y189083D01*
X541740Y189313D01*
X541947Y189582D01*
X542050Y189850D01*
Y190118D01*
X541947Y190387D01*
X541792Y190617D01*
X541585Y190808D01*
G01X539467Y192222D02*
X539157Y192452D01*
X539002Y192720D01*
X538950Y193027D01*
X539053Y193410D01*
X539312Y193678D01*
X539622Y193755D01*
X539932Y193717D01*
X540190Y193563D01*
X540707Y192797D01*
X541068Y192452D01*
X541585Y192222D01*
X542050Y192145D01*
Y193755D01*
G01X540758Y195322D02*
X540397Y195590D01*
X540190Y195820D01*
X540087Y196127D01*
X540190Y196395D01*
X540397Y196587D01*
X540707Y196740D01*
X541068Y196778D01*
X541378Y196740D01*
X541688Y196587D01*
X541947Y196357D01*
X542050Y196088D01*
X541947Y195782D01*
X541637Y195513D01*
X541172Y195360D01*
X540655Y195322D01*
X539983Y195398D01*
X539622Y195513D01*
X539260Y195705D01*
X539002Y195973D01*
X538950Y196242D01*
X539053Y196510D01*
X539312Y196702D01*
G01X542050Y199150D02*
X541998Y199418D01*
X541843Y199725D01*
X541585Y199917D01*
X541223Y199993D01*
X540862Y199917D01*
X540552Y199687D01*
X540397Y199342D01*
Y198958D01*
X540293Y198728D01*
X540035Y198537D01*
X539673Y198460D01*
X539312Y198575D01*
X539053Y198843D01*
X538950Y199150D01*
X539053Y199457D01*
X539312Y199725D01*
X539673Y199840D01*
X540035Y199763D01*
X540293Y199572D01*
X540397Y199342D01*
Y198958D01*
X540552Y198613D01*
X540862Y198383D01*
X541223Y198307D01*
X541585Y198383D01*
X541843Y198575D01*
X541998Y198882D01*
X542050Y199150D01*
G01X547913Y203325D02*
X548073Y203117D01*
X548260Y202992D01*
X548500Y202950D01*
X548740Y203033D01*
X548927Y203200D01*
X549060Y203492D01*
X549087Y203825D01*
X549033Y204158D01*
X548900Y204367D01*
X548713Y204533D01*
X548527Y204575D01*
X548340Y204533D01*
X548100Y204367D01*
X548180Y205450D01*
X548900D01*
G01X546900Y225450D02*
Y227950D01*
X546580Y227450D01*
G01Y225450D02*
X547220D01*
G01X549100D02*
X549287Y225492D01*
X549500Y225617D01*
X549633Y225825D01*
X549687Y226117D01*
X549633Y226408D01*
X549473Y226658D01*
X549233Y226783D01*
X548967D01*
X548807Y226867D01*
X548673Y227075D01*
X548620Y227367D01*
X548700Y227658D01*
X548887Y227867D01*
X549100Y227950D01*
X549313Y227867D01*
X549500Y227658D01*
X549580Y227367D01*
X549527Y227075D01*
X549393Y226867D01*
X549233Y226783D01*
X548967D01*
X548727Y226658D01*
X548567Y226408D01*
X548513Y226117D01*
X548567Y225825D01*
X548700Y225617D01*
X548913Y225492D01*
X549100Y225450D01*
G01X547208Y242693D02*
X547053Y242463D01*
X546950Y242195D01*
Y241888D01*
X547105Y241543D01*
X547363Y241275D01*
X547673Y241083D01*
X548190Y240930D01*
X548655Y240892D01*
X549120Y240968D01*
X549430Y241083D01*
X549740Y241313D01*
X549947Y241582D01*
X550050Y241850D01*
Y242118D01*
X549947Y242387D01*
X549792Y242617D01*
X549585Y242808D01*
G01X547467Y244222D02*
X547157Y244452D01*
X547002Y244720D01*
X546950Y245027D01*
X547053Y245410D01*
X547312Y245678D01*
X547622Y245755D01*
X547932Y245717D01*
X548190Y245563D01*
X548707Y244797D01*
X549068Y244452D01*
X549585Y244222D01*
X550050Y244145D01*
Y245755D01*
G01X549585Y247207D02*
X549843Y247437D01*
X549998Y247705D01*
X550050Y248050D01*
X549947Y248395D01*
X549740Y248663D01*
X549378Y248855D01*
X548965Y248893D01*
X548552Y248817D01*
X548293Y248625D01*
X548087Y248357D01*
X548035Y248088D01*
X548087Y247820D01*
X548293Y247475D01*
X546950Y247590D01*
Y248625D01*
G01X548758Y250422D02*
X548397Y250690D01*
X548190Y250920D01*
X548087Y251227D01*
X548190Y251495D01*
X548397Y251687D01*
X548707Y251840D01*
X549068Y251878D01*
X549378Y251840D01*
X549688Y251687D01*
X549947Y251457D01*
X550050Y251188D01*
X549947Y250882D01*
X549637Y250613D01*
X549172Y250460D01*
X548655Y250422D01*
X547983Y250498D01*
X547622Y250613D01*
X547260Y250805D01*
X547002Y251073D01*
X546950Y251342D01*
X547053Y251610D01*
X547312Y251802D01*
G01X543208Y242693D02*
X543053Y242463D01*
X542950Y242195D01*
Y241888D01*
X543105Y241543D01*
X543363Y241275D01*
X543673Y241083D01*
X544190Y240930D01*
X544655Y240892D01*
X545120Y240968D01*
X545430Y241083D01*
X545740Y241313D01*
X545947Y241582D01*
X546050Y241850D01*
Y242118D01*
X545947Y242387D01*
X545792Y242617D01*
X545585Y242808D01*
G01X543467Y244222D02*
X543157Y244452D01*
X543002Y244720D01*
X542950Y245027D01*
X543053Y245410D01*
X543312Y245678D01*
X543622Y245755D01*
X543932Y245717D01*
X544190Y245563D01*
X544707Y244797D01*
X545068Y244452D01*
X545585Y244222D01*
X546050Y244145D01*
Y245755D01*
G01X545585Y247207D02*
X545843Y247437D01*
X545998Y247705D01*
X546050Y248050D01*
X545947Y248395D01*
X545740Y248663D01*
X545378Y248855D01*
X544965Y248893D01*
X544552Y248817D01*
X544293Y248625D01*
X544087Y248357D01*
X544035Y248088D01*
X544087Y247820D01*
X544293Y247475D01*
X542950Y247590D01*
Y248625D01*
G01X546050Y251150D02*
X545998Y251418D01*
X545843Y251725D01*
X545585Y251917D01*
X545223Y251993D01*
X544862Y251917D01*
X544552Y251687D01*
X544397Y251342D01*
Y250958D01*
X544293Y250728D01*
X544035Y250537D01*
X543673Y250460D01*
X543312Y250575D01*
X543053Y250843D01*
X542950Y251150D01*
X543053Y251457D01*
X543312Y251725D01*
X543673Y251840D01*
X544035Y251763D01*
X544293Y251572D01*
X544397Y251342D01*
Y250958D01*
X544552Y250613D01*
X544862Y250383D01*
X545223Y250307D01*
X545585Y250383D01*
X545843Y250575D01*
X545998Y250882D01*
X546050Y251150D01*
G01X542050Y241083D02*
X538950D01*
Y242042D01*
X539105Y242348D01*
X539312Y242540D01*
X539725Y242617D01*
X540138Y242540D01*
X540397Y242310D01*
X540552Y242042D01*
Y241083D01*
G01Y242042D02*
X542050Y242617D01*
G01X539467Y244222D02*
X539157Y244452D01*
X539002Y244720D01*
X538950Y245027D01*
X539053Y245410D01*
X539312Y245678D01*
X539622Y245755D01*
X539932Y245717D01*
X540190Y245563D01*
X540707Y244797D01*
X541068Y244452D01*
X541585Y244222D01*
X542050Y244145D01*
Y245755D01*
G01Y248510D02*
X538950D01*
X541172Y247092D01*
Y249008D01*
G01X541585Y250307D02*
X541843Y250537D01*
X541998Y250805D01*
X542050Y251150D01*
X541947Y251495D01*
X541740Y251763D01*
X541378Y251955D01*
X540965Y251993D01*
X540552Y251917D01*
X540293Y251725D01*
X540087Y251457D01*
X540035Y251188D01*
X540087Y250920D01*
X540293Y250575D01*
X538950Y250690D01*
Y251725D01*
G01X542272Y256033D02*
X542502Y256343D01*
X542770Y256498D01*
X543077Y256550D01*
X543460Y256447D01*
X543728Y256188D01*
X543805Y255878D01*
X543767Y255568D01*
X543613Y255310D01*
X542847Y254793D01*
X542502Y254432D01*
X542272Y253915D01*
X542195Y253450D01*
X543805D01*
G01X538250Y253200D02*
X540750D01*
G01X538250Y252587D02*
Y253813D01*
G01X540750Y254867D02*
X538250D01*
Y255507D01*
X538375Y255720D01*
X538667Y255880D01*
X539000Y255933D01*
X539333Y255880D01*
X539583Y255747D01*
X539708Y255507D01*
Y254867D01*
G01X540375Y257013D02*
X540583Y257173D01*
X540708Y257360D01*
X540750Y257600D01*
X540667Y257840D01*
X540500Y258027D01*
X540208Y258160D01*
X539875Y258187D01*
X539542Y258133D01*
X539333Y258000D01*
X539167Y257813D01*
X539125Y257627D01*
X539167Y257440D01*
X539333Y257200D01*
X538250Y257280D01*
Y258000D01*
G01X539708Y259293D02*
X539417Y259480D01*
X539250Y259640D01*
X539167Y259853D01*
X539250Y260040D01*
X539417Y260173D01*
X539667Y260280D01*
X539958Y260307D01*
X540208Y260280D01*
X540458Y260173D01*
X540667Y260013D01*
X540750Y259827D01*
X540667Y259613D01*
X540417Y259427D01*
X540042Y259320D01*
X539625Y259293D01*
X539083Y259347D01*
X538792Y259427D01*
X538500Y259560D01*
X538292Y259747D01*
X538250Y259933D01*
X538333Y260120D01*
X538542Y260253D01*
G01X536550Y290083D02*
X533450D01*
Y291042D01*
X533605Y291348D01*
X533812Y291540D01*
X534225Y291617D01*
X534638Y291540D01*
X534897Y291310D01*
X535052Y291042D01*
Y290083D01*
G01Y291042D02*
X536550Y291617D01*
G01Y293950D02*
X533450D01*
X534070Y293490D01*
G01X536550D02*
Y294410D01*
G01Y297050D02*
X536498Y297318D01*
X536343Y297625D01*
X536085Y297817D01*
X535723Y297893D01*
X535362Y297817D01*
X535052Y297587D01*
X534897Y297242D01*
Y296858D01*
X534793Y296628D01*
X534535Y296437D01*
X534173Y296360D01*
X533812Y296475D01*
X533553Y296743D01*
X533450Y297050D01*
X533553Y297357D01*
X533812Y297625D01*
X534173Y297740D01*
X534535Y297663D01*
X534793Y297472D01*
X534897Y297242D01*
Y296858D01*
X535052Y296513D01*
X535362Y296283D01*
X535723Y296207D01*
X536085Y296283D01*
X536343Y296475D01*
X536498Y296782D01*
X536550Y297050D01*
G01X533967Y299422D02*
X533657Y299652D01*
X533502Y299920D01*
X533450Y300227D01*
X533553Y300610D01*
X533812Y300878D01*
X534122Y300955D01*
X534432Y300917D01*
X534690Y300763D01*
X535207Y299997D01*
X535568Y299652D01*
X536085Y299422D01*
X536550Y299345D01*
Y300955D01*
G01X537950Y305450D02*
Y308550D01*
X537490Y307930D01*
G01Y305450D02*
X538410D01*
G01X541050Y308550D02*
X540743Y308447D01*
X540513Y308188D01*
X540360Y307878D01*
X540245Y307465D01*
X540207Y307000D01*
X540245Y306535D01*
X540360Y306122D01*
X540513Y305812D01*
X540743Y305553D01*
X541050Y305450D01*
X541357Y305553D01*
X541587Y305812D01*
X541740Y306122D01*
X541855Y306535D01*
X541893Y307000D01*
X541855Y307465D01*
X541740Y307878D01*
X541587Y308188D01*
X541357Y308447D01*
X541050Y308550D01*
G01X537172Y353950D02*
Y357050D01*
X538628D01*
G01X538092Y355552D02*
X537172D01*
G01X540157Y357050D02*
Y354828D01*
X540310Y354363D01*
X540617Y354053D01*
X541000Y353950D01*
X541383Y354053D01*
X541690Y354363D01*
X541843Y354828D01*
Y357050D01*
G01X544100Y353950D02*
Y357050D01*
X543640Y356430D01*
G01Y353950D02*
X544560D01*
G01X539107Y376550D02*
Y374328D01*
X539260Y373863D01*
X539567Y373553D01*
X539950Y373450D01*
X540333Y373553D01*
X540640Y373863D01*
X540793Y374328D01*
Y376550D01*
G01X543050Y373450D02*
Y376550D01*
X542590Y375930D01*
G01Y373450D02*
X543510D01*
G01X539893Y368333D02*
X540053Y368583D01*
X540240Y368708D01*
X540453Y368750D01*
X540720Y368667D01*
X540907Y368458D01*
X540960Y368208D01*
X540933Y367958D01*
X540827Y367750D01*
X540293Y367333D01*
X540053Y367042D01*
X539893Y366625D01*
X539840Y366250D01*
X540960D01*
G01X542600Y368750D02*
X542387Y368667D01*
X542227Y368458D01*
X542120Y368208D01*
X542040Y367875D01*
X542013Y367500D01*
X542040Y367125D01*
X542120Y366792D01*
X542227Y366542D01*
X542387Y366333D01*
X542600Y366250D01*
X542813Y366333D01*
X542973Y366542D01*
X543080Y366792D01*
X543160Y367125D01*
X543187Y367500D01*
X543160Y367875D01*
X543080Y368208D01*
X542973Y368458D01*
X542813Y368667D01*
X542600Y368750D01*
G01X542793Y392292D02*
X542563Y392447D01*
X542295Y392550D01*
X541988D01*
X541643Y392395D01*
X541375Y392137D01*
X541183Y391827D01*
X541030Y391310D01*
X540992Y390845D01*
X541068Y390380D01*
X541183Y390070D01*
X541413Y389760D01*
X541682Y389553D01*
X541950Y389450D01*
X542218D01*
X542487Y389553D01*
X542717Y389708D01*
X542908Y389915D01*
G01X545050Y389450D02*
X545318Y389502D01*
X545625Y389657D01*
X545817Y389915D01*
X545893Y390277D01*
X545817Y390638D01*
X545587Y390948D01*
X545242Y391103D01*
X544858D01*
X544628Y391207D01*
X544437Y391465D01*
X544360Y391827D01*
X544475Y392188D01*
X544743Y392447D01*
X545050Y392550D01*
X545357Y392447D01*
X545625Y392188D01*
X545740Y391827D01*
X545663Y391465D01*
X545472Y391207D01*
X545242Y391103D01*
X544858D01*
X544513Y390948D01*
X544283Y390638D01*
X544207Y390277D01*
X544283Y389915D01*
X544475Y389657D01*
X544782Y389502D01*
X545050Y389450D01*
G01X540900Y381250D02*
Y383750D01*
X540580Y383250D01*
G01Y381250D02*
X541220D01*
G01X542593Y383333D02*
X542753Y383583D01*
X542940Y383708D01*
X543153Y383750D01*
X543420Y383667D01*
X543607Y383458D01*
X543660Y383208D01*
X543633Y382958D01*
X543527Y382750D01*
X542993Y382333D01*
X542753Y382042D01*
X542593Y381625D01*
X542540Y381250D01*
X543660D01*
G01X550250Y404213D02*
X547750D01*
Y404747D01*
X547875Y404960D01*
X548042Y405120D01*
X548292Y405253D01*
X548583Y405360D01*
X549000Y405387D01*
X549417Y405360D01*
X549708Y405253D01*
X549958Y405120D01*
X550125Y404960D01*
X550250Y404747D01*
Y404213D01*
G01X549917Y406440D02*
X550125Y406653D01*
X550250Y406893D01*
Y407107D01*
X550125Y407320D01*
X549917Y407480D01*
X549625Y407560D01*
X549333Y407507D01*
X549083Y407373D01*
X548917Y407133D01*
X548833Y406813D01*
X548667Y406627D01*
X548375Y406547D01*
X548083Y406600D01*
X547875Y406733D01*
X547750Y406920D01*
Y407107D01*
X547833Y407293D01*
X548042Y407453D01*
G01X550250Y409147D02*
X549708Y409200D01*
X549250Y409280D01*
X548833Y409387D01*
X548375Y409520D01*
X547750Y409733D01*
Y408667D01*
G01X539087Y404542D02*
X538927Y404667D01*
X538740Y404750D01*
X538527D01*
X538287Y404625D01*
X538100Y404417D01*
X537967Y404167D01*
X537860Y403750D01*
X537833Y403375D01*
X537887Y403000D01*
X537967Y402750D01*
X538127Y402500D01*
X538313Y402333D01*
X538500Y402250D01*
X538687D01*
X538873Y402333D01*
X539033Y402458D01*
X539167Y402625D01*
G01X537050Y403557D02*
X533950D01*
Y404323D01*
X534105Y404630D01*
X534312Y404860D01*
X534622Y405052D01*
X534983Y405205D01*
X535500Y405243D01*
X536017Y405205D01*
X536378Y405052D01*
X536688Y404860D01*
X536895Y404630D01*
X537050Y404323D01*
Y403557D01*
G01X536637Y406695D02*
X536895Y407002D01*
X537050Y407347D01*
Y407653D01*
X536895Y407960D01*
X536637Y408190D01*
X536275Y408305D01*
X535913Y408228D01*
X535603Y408037D01*
X535397Y407692D01*
X535293Y407232D01*
X535087Y406963D01*
X534725Y406848D01*
X534363Y406925D01*
X534105Y407117D01*
X533950Y407385D01*
Y407653D01*
X534053Y407922D01*
X534312Y408152D01*
G01X535758Y409872D02*
X535397Y410140D01*
X535190Y410370D01*
X535087Y410677D01*
X535190Y410945D01*
X535397Y411137D01*
X535707Y411290D01*
X536068Y411328D01*
X536378Y411290D01*
X536688Y411137D01*
X536947Y410907D01*
X537050Y410638D01*
X536947Y410332D01*
X536637Y410063D01*
X536172Y409910D01*
X535655Y409872D01*
X534983Y409948D01*
X534622Y410063D01*
X534260Y410255D01*
X534002Y410523D01*
X533950Y410792D01*
X534053Y411060D01*
X534312Y411252D01*
G01X540133Y399450D02*
Y402550D01*
X541092D01*
X541398Y402395D01*
X541590Y402188D01*
X541667Y401775D01*
X541590Y401362D01*
X541360Y401103D01*
X541092Y400948D01*
X540133D01*
G01X541092D02*
X541667Y399450D01*
G01X544000D02*
Y402550D01*
X543540Y401930D01*
G01Y399450D02*
X544460D01*
G01X546372Y402033D02*
X546602Y402343D01*
X546870Y402498D01*
X547177Y402550D01*
X547560Y402447D01*
X547828Y402188D01*
X547905Y401878D01*
X547867Y401568D01*
X547713Y401310D01*
X546947Y400793D01*
X546602Y400432D01*
X546372Y399915D01*
X546295Y399450D01*
X547905D01*
G01X551050Y421713D02*
X548550D01*
Y422247D01*
X548675Y422460D01*
X548842Y422620D01*
X549092Y422753D01*
X549383Y422860D01*
X549800Y422887D01*
X550217Y422860D01*
X550508Y422753D01*
X550758Y422620D01*
X550925Y422460D01*
X551050Y422247D01*
Y421713D01*
G01X550717Y423940D02*
X550925Y424153D01*
X551050Y424393D01*
Y424607D01*
X550925Y424820D01*
X550717Y424980D01*
X550425Y425060D01*
X550133Y425007D01*
X549883Y424873D01*
X549717Y424633D01*
X549633Y424313D01*
X549467Y424127D01*
X549175Y424047D01*
X548883Y424100D01*
X548675Y424233D01*
X548550Y424420D01*
Y424607D01*
X548633Y424793D01*
X548842Y424953D01*
G01X548967Y426193D02*
X548717Y426353D01*
X548592Y426540D01*
X548550Y426753D01*
X548633Y427020D01*
X548842Y427207D01*
X549092Y427260D01*
X549342Y427233D01*
X549550Y427127D01*
X549967Y426593D01*
X550258Y426353D01*
X550675Y426193D01*
X551050Y426140D01*
Y427260D01*
G01X549587Y420042D02*
X549427Y420167D01*
X549240Y420250D01*
X549027D01*
X548787Y420125D01*
X548600Y419917D01*
X548467Y419667D01*
X548360Y419250D01*
X548333Y418875D01*
X548387Y418500D01*
X548467Y418250D01*
X548627Y418000D01*
X548813Y417833D01*
X549000Y417750D01*
X549187D01*
X549373Y417833D01*
X549533Y417958D01*
X549667Y418125D01*
G01X548833Y412250D02*
X549500Y414750D01*
X550167Y412250D01*
G01X549927Y413125D02*
X549073D01*
G01X537550Y421057D02*
X534450D01*
Y421823D01*
X534605Y422130D01*
X534812Y422360D01*
X535122Y422552D01*
X535483Y422705D01*
X536000Y422743D01*
X536517Y422705D01*
X536878Y422552D01*
X537188Y422360D01*
X537395Y422130D01*
X537550Y421823D01*
Y421057D01*
G01X537137Y424195D02*
X537395Y424502D01*
X537550Y424847D01*
Y425153D01*
X537395Y425460D01*
X537137Y425690D01*
X536775Y425805D01*
X536413Y425728D01*
X536103Y425537D01*
X535897Y425192D01*
X535793Y424732D01*
X535587Y424463D01*
X535225Y424348D01*
X534863Y424425D01*
X534605Y424617D01*
X534450Y424885D01*
Y425153D01*
X534553Y425422D01*
X534812Y425652D01*
G01X537550Y428100D02*
X534450D01*
X535070Y427640D01*
G01X537550D02*
Y428560D01*
G01X538587Y419542D02*
X538427Y419667D01*
X538240Y419750D01*
X538027D01*
X537787Y419625D01*
X537600Y419417D01*
X537467Y419167D01*
X537360Y418750D01*
X537333Y418375D01*
X537387Y418000D01*
X537467Y417750D01*
X537627Y417500D01*
X537813Y417333D01*
X538000Y417250D01*
X538187D01*
X538373Y417333D01*
X538533Y417458D01*
X538667Y417625D01*
G01X536333Y412750D02*
X537000Y415250D01*
X537667Y412750D01*
G01X537427Y413625D02*
X536573D01*
G01X541333Y431450D02*
X542000Y433950D01*
X542667Y431450D01*
G01X542427Y432325D02*
X541573D01*
G01X557557Y59050D02*
Y56828D01*
X557710Y56363D01*
X558017Y56053D01*
X558400Y55950D01*
X558783Y56053D01*
X559090Y56363D01*
X559243Y56828D01*
Y59050D01*
G01X560772Y58533D02*
X561002Y58843D01*
X561270Y58998D01*
X561577Y59050D01*
X561960Y58947D01*
X562228Y58688D01*
X562305Y58378D01*
X562267Y58068D01*
X562113Y57810D01*
X561347Y57293D01*
X561002Y56932D01*
X560772Y56415D01*
X560695Y55950D01*
X562305D01*
G01X563757Y56415D02*
X563987Y56157D01*
X564255Y56002D01*
X564600Y55950D01*
X564945Y56053D01*
X565213Y56260D01*
X565405Y56622D01*
X565443Y57035D01*
X565367Y57448D01*
X565175Y57707D01*
X564907Y57913D01*
X564638Y57965D01*
X564370Y57913D01*
X564025Y57707D01*
X564140Y59050D01*
X565175D01*
G01X562208Y106193D02*
X562053Y105963D01*
X561950Y105695D01*
Y105388D01*
X562105Y105043D01*
X562363Y104775D01*
X562673Y104583D01*
X563190Y104430D01*
X563655Y104392D01*
X564120Y104468D01*
X564430Y104583D01*
X564740Y104813D01*
X564947Y105082D01*
X565050Y105350D01*
Y105618D01*
X564947Y105887D01*
X564792Y106117D01*
X564585Y106308D01*
G01X562467Y107722D02*
X562157Y107952D01*
X562002Y108220D01*
X561950Y108527D01*
X562053Y108910D01*
X562312Y109178D01*
X562622Y109255D01*
X562932Y109217D01*
X563190Y109063D01*
X563707Y108297D01*
X564068Y107952D01*
X564585Y107722D01*
X565050Y107645D01*
Y109255D01*
G01X562467Y110822D02*
X562157Y111052D01*
X562002Y111320D01*
X561950Y111627D01*
X562053Y112010D01*
X562312Y112278D01*
X562622Y112355D01*
X562932Y112317D01*
X563190Y112163D01*
X563707Y111397D01*
X564068Y111052D01*
X564585Y110822D01*
X565050Y110745D01*
Y112355D01*
G01X563758Y113922D02*
X563397Y114190D01*
X563190Y114420D01*
X563087Y114727D01*
X563190Y114995D01*
X563397Y115187D01*
X563707Y115340D01*
X564068Y115378D01*
X564378Y115340D01*
X564688Y115187D01*
X564947Y114957D01*
X565050Y114688D01*
X564947Y114382D01*
X564637Y114113D01*
X564172Y113960D01*
X563655Y113922D01*
X562983Y113998D01*
X562622Y114113D01*
X562260Y114305D01*
X562002Y114573D01*
X561950Y114842D01*
X562053Y115110D01*
X562312Y115302D01*
G01X556708Y106693D02*
X556553Y106463D01*
X556450Y106195D01*
Y105888D01*
X556605Y105543D01*
X556863Y105275D01*
X557173Y105083D01*
X557690Y104930D01*
X558155Y104892D01*
X558620Y104968D01*
X558930Y105083D01*
X559240Y105313D01*
X559447Y105582D01*
X559550Y105850D01*
Y106118D01*
X559447Y106387D01*
X559292Y106617D01*
X559085Y106808D01*
G01X556967Y108222D02*
X556657Y108452D01*
X556502Y108720D01*
X556450Y109027D01*
X556553Y109410D01*
X556812Y109678D01*
X557122Y109755D01*
X557432Y109717D01*
X557690Y109563D01*
X558207Y108797D01*
X558568Y108452D01*
X559085Y108222D01*
X559550Y108145D01*
Y109755D01*
G01X556967Y111322D02*
X556657Y111552D01*
X556502Y111820D01*
X556450Y112127D01*
X556553Y112510D01*
X556812Y112778D01*
X557122Y112855D01*
X557432Y112817D01*
X557690Y112663D01*
X558207Y111897D01*
X558568Y111552D01*
X559085Y111322D01*
X559550Y111245D01*
Y112855D01*
G01Y115610D02*
X556450D01*
X558672Y114192D01*
Y116108D01*
G01X567950Y103633D02*
X571050D01*
Y105167D01*
G01Y107500D02*
X567950D01*
X568570Y107040D01*
G01X571050D02*
Y107960D01*
G01X570430Y109757D02*
X570792Y109987D01*
X570998Y110293D01*
X571050Y110638D01*
X570998Y110945D01*
X570740Y111252D01*
X570430Y111443D01*
X570120Y111482D01*
X569758Y111405D01*
X569500Y111137D01*
X569397Y110868D01*
Y110523D01*
G01Y110868D02*
X569242Y111098D01*
X568983Y111290D01*
X568673Y111367D01*
X568363Y111290D01*
X568105Y111098D01*
X567950Y110753D01*
X568002Y110408D01*
X568208Y110063D01*
G01X565693Y156292D02*
X565463Y156447D01*
X565195Y156550D01*
X564888D01*
X564543Y156395D01*
X564275Y156137D01*
X564083Y155827D01*
X563930Y155310D01*
X563892Y154845D01*
X563968Y154380D01*
X564083Y154070D01*
X564313Y153760D01*
X564582Y153553D01*
X564850Y153450D01*
X565118D01*
X565387Y153553D01*
X565617Y153708D01*
X565808Y153915D01*
G01X567222Y156033D02*
X567452Y156343D01*
X567720Y156498D01*
X568027Y156550D01*
X568410Y156447D01*
X568678Y156188D01*
X568755Y155878D01*
X568717Y155568D01*
X568563Y155310D01*
X567797Y154793D01*
X567452Y154432D01*
X567222Y153915D01*
X567145Y153450D01*
X568755D01*
G01X570322Y154742D02*
X570590Y155103D01*
X570820Y155310D01*
X571127Y155413D01*
X571395Y155310D01*
X571587Y155103D01*
X571740Y154793D01*
X571778Y154432D01*
X571740Y154122D01*
X571587Y153812D01*
X571357Y153553D01*
X571088Y153450D01*
X570782Y153553D01*
X570513Y153863D01*
X570360Y154328D01*
X570322Y154845D01*
X570398Y155517D01*
X570513Y155878D01*
X570705Y156240D01*
X570973Y156498D01*
X571242Y156550D01*
X571510Y156447D01*
X571702Y156188D01*
G01X573498Y153812D02*
X573767Y153553D01*
X574073Y153450D01*
X574380Y153553D01*
X574648Y153863D01*
X574840Y154328D01*
X574917Y154793D01*
Y155362D01*
X574840Y155827D01*
X574648Y156240D01*
X574418Y156447D01*
X574150Y156550D01*
X573843Y156447D01*
X573613Y156240D01*
X573460Y155930D01*
X573383Y155517D01*
X573460Y155155D01*
X573652Y154793D01*
X573882Y154587D01*
X574150Y154535D01*
X574457Y154638D01*
X574687Y154897D01*
X574917Y155362D01*
G01X551850Y158550D02*
Y155450D01*
G01X550968Y158550D02*
X552732D01*
G01X554183Y155450D02*
Y158550D01*
X555103D01*
X555410Y158395D01*
X555640Y158033D01*
X555717Y157620D01*
X555640Y157207D01*
X555448Y156897D01*
X555103Y156742D01*
X554183D01*
G01X557207Y155915D02*
X557437Y155657D01*
X557705Y155502D01*
X558050Y155450D01*
X558395Y155553D01*
X558663Y155760D01*
X558855Y156122D01*
X558893Y156535D01*
X558817Y156948D01*
X558625Y157207D01*
X558357Y157413D01*
X558088Y157465D01*
X557820Y157413D01*
X557475Y157207D01*
X557590Y158550D01*
X558625D01*
G01X561610Y155450D02*
Y158550D01*
X560192Y156328D01*
X562108D01*
G01X555680Y203595D02*
X555867Y203886D01*
X556027Y204053D01*
X556240Y204136D01*
X556427Y204053D01*
X556560Y203886D01*
X556667Y203636D01*
X556694Y203345D01*
X556667Y203095D01*
X556560Y202845D01*
X556400Y202636D01*
X556214Y202553D01*
X556000Y202636D01*
X555814Y202886D01*
X555707Y203261D01*
X555680Y203678D01*
X555734Y204220D01*
X555814Y204511D01*
X555947Y204803D01*
X556134Y205011D01*
X556320Y205053D01*
X556507Y204970D01*
X556640Y204761D01*
G01X559353Y202551D02*
X559406Y203093D01*
X559486Y203551D01*
X559593Y203968D01*
X559726Y204426D01*
X559939Y205051D01*
X558873D01*
G01X567000Y202450D02*
X567187Y202492D01*
X567400Y202617D01*
X567533Y202825D01*
X567587Y203117D01*
X567533Y203408D01*
X567373Y203658D01*
X567133Y203783D01*
X566867D01*
X566707Y203867D01*
X566573Y204075D01*
X566520Y204367D01*
X566600Y204658D01*
X566787Y204867D01*
X567000Y204950D01*
X567213Y204867D01*
X567400Y204658D01*
X567480Y204367D01*
X567427Y204075D01*
X567293Y203867D01*
X567133Y203783D01*
X566867D01*
X566627Y203658D01*
X566467Y203408D01*
X566413Y203117D01*
X566467Y202825D01*
X566600Y202617D01*
X566813Y202492D01*
X567000Y202450D01*
G01X554057Y228050D02*
Y225828D01*
X554210Y225363D01*
X554517Y225053D01*
X554900Y224950D01*
X555283Y225053D01*
X555590Y225363D01*
X555743Y225828D01*
Y228050D01*
G01X557272Y227533D02*
X557502Y227843D01*
X557770Y227998D01*
X558077Y228050D01*
X558460Y227947D01*
X558728Y227688D01*
X558805Y227378D01*
X558767Y227068D01*
X558613Y226810D01*
X557847Y226293D01*
X557502Y225932D01*
X557272Y225415D01*
X557195Y224950D01*
X558805D01*
G01X560372Y226242D02*
X560640Y226603D01*
X560870Y226810D01*
X561177Y226913D01*
X561445Y226810D01*
X561637Y226603D01*
X561790Y226293D01*
X561828Y225932D01*
X561790Y225622D01*
X561637Y225312D01*
X561407Y225053D01*
X561138Y224950D01*
X560832Y225053D01*
X560563Y225363D01*
X560410Y225828D01*
X560372Y226345D01*
X560448Y227017D01*
X560563Y227378D01*
X560755Y227740D01*
X561023Y227998D01*
X561292Y228050D01*
X561560Y227947D01*
X561752Y227688D01*
G01X566900Y224250D02*
Y226750D01*
X566580Y226250D01*
G01Y224250D02*
X567220D01*
G01X568513Y224750D02*
X568673Y224458D01*
X568887Y224292D01*
X569127Y224250D01*
X569340Y224292D01*
X569553Y224500D01*
X569687Y224750D01*
X569713Y225000D01*
X569660Y225292D01*
X569473Y225500D01*
X569287Y225583D01*
X569047D01*
G01X569287D02*
X569447Y225708D01*
X569580Y225917D01*
X569633Y226167D01*
X569580Y226417D01*
X569447Y226625D01*
X569207Y226750D01*
X568967Y226708D01*
X568727Y226542D01*
G01X551208Y242693D02*
X551053Y242463D01*
X550950Y242195D01*
Y241888D01*
X551105Y241543D01*
X551363Y241275D01*
X551673Y241083D01*
X552190Y240930D01*
X552655Y240892D01*
X553120Y240968D01*
X553430Y241083D01*
X553740Y241313D01*
X553947Y241582D01*
X554050Y241850D01*
Y242118D01*
X553947Y242387D01*
X553792Y242617D01*
X553585Y242808D01*
G01X551467Y244222D02*
X551157Y244452D01*
X551002Y244720D01*
X550950Y245027D01*
X551053Y245410D01*
X551312Y245678D01*
X551622Y245755D01*
X551932Y245717D01*
X552190Y245563D01*
X552707Y244797D01*
X553068Y244452D01*
X553585Y244222D01*
X554050Y244145D01*
Y245755D01*
G01X553585Y247207D02*
X553843Y247437D01*
X553998Y247705D01*
X554050Y248050D01*
X553947Y248395D01*
X553740Y248663D01*
X553378Y248855D01*
X552965Y248893D01*
X552552Y248817D01*
X552293Y248625D01*
X552087Y248357D01*
X552035Y248088D01*
X552087Y247820D01*
X552293Y247475D01*
X550950Y247590D01*
Y248625D01*
G01X553688Y250498D02*
X553947Y250767D01*
X554050Y251073D01*
X553947Y251380D01*
X553637Y251648D01*
X553172Y251840D01*
X552707Y251917D01*
X552138D01*
X551673Y251840D01*
X551260Y251648D01*
X551053Y251418D01*
X550950Y251150D01*
X551053Y250843D01*
X551260Y250613D01*
X551570Y250460D01*
X551983Y250383D01*
X552345Y250460D01*
X552707Y250652D01*
X552913Y250882D01*
X552965Y251150D01*
X552862Y251457D01*
X552603Y251687D01*
X552138Y251917D01*
G01X559708Y242693D02*
X559553Y242463D01*
X559450Y242195D01*
Y241888D01*
X559605Y241543D01*
X559863Y241275D01*
X560173Y241083D01*
X560690Y240930D01*
X561155Y240892D01*
X561620Y240968D01*
X561930Y241083D01*
X562240Y241313D01*
X562447Y241582D01*
X562550Y241850D01*
Y242118D01*
X562447Y242387D01*
X562292Y242617D01*
X562085Y242808D01*
G01X559967Y244222D02*
X559657Y244452D01*
X559502Y244720D01*
X559450Y245027D01*
X559553Y245410D01*
X559812Y245678D01*
X560122Y245755D01*
X560432Y245717D01*
X560690Y245563D01*
X561207Y244797D01*
X561568Y244452D01*
X562085Y244222D01*
X562550Y244145D01*
Y245755D01*
G01X561258Y247322D02*
X560897Y247590D01*
X560690Y247820D01*
X560587Y248127D01*
X560690Y248395D01*
X560897Y248587D01*
X561207Y248740D01*
X561568Y248778D01*
X561878Y248740D01*
X562188Y248587D01*
X562447Y248357D01*
X562550Y248088D01*
X562447Y247782D01*
X562137Y247513D01*
X561672Y247360D01*
X561155Y247322D01*
X560483Y247398D01*
X560122Y247513D01*
X559760Y247705D01*
X559502Y247973D01*
X559450Y248242D01*
X559553Y248510D01*
X559812Y248702D01*
G01X562550Y251073D02*
X561878Y251150D01*
X561310Y251265D01*
X560793Y251418D01*
X560225Y251610D01*
X559450Y251917D01*
Y250383D01*
G01X555208Y242693D02*
X555053Y242463D01*
X554950Y242195D01*
Y241888D01*
X555105Y241543D01*
X555363Y241275D01*
X555673Y241083D01*
X556190Y240930D01*
X556655Y240892D01*
X557120Y240968D01*
X557430Y241083D01*
X557740Y241313D01*
X557947Y241582D01*
X558050Y241850D01*
Y242118D01*
X557947Y242387D01*
X557792Y242617D01*
X557585Y242808D01*
G01X555467Y244222D02*
X555157Y244452D01*
X555002Y244720D01*
X554950Y245027D01*
X555053Y245410D01*
X555312Y245678D01*
X555622Y245755D01*
X555932Y245717D01*
X556190Y245563D01*
X556707Y244797D01*
X557068Y244452D01*
X557585Y244222D01*
X558050Y244145D01*
Y245755D01*
G01X556758Y247322D02*
X556397Y247590D01*
X556190Y247820D01*
X556087Y248127D01*
X556190Y248395D01*
X556397Y248587D01*
X556707Y248740D01*
X557068Y248778D01*
X557378Y248740D01*
X557688Y248587D01*
X557947Y248357D01*
X558050Y248088D01*
X557947Y247782D01*
X557637Y247513D01*
X557172Y247360D01*
X556655Y247322D01*
X555983Y247398D01*
X555622Y247513D01*
X555260Y247705D01*
X555002Y247973D01*
X554950Y248242D01*
X555053Y248510D01*
X555312Y248702D01*
G01X558050Y251610D02*
X554950D01*
X557172Y250192D01*
Y252108D01*
G01X553083Y252450D02*
Y255550D01*
X554042D01*
X554348Y255395D01*
X554540Y255188D01*
X554617Y254775D01*
X554540Y254362D01*
X554310Y254103D01*
X554042Y253948D01*
X553083D01*
G01X554042D02*
X554617Y252450D01*
G01X556222Y255033D02*
X556452Y255343D01*
X556720Y255498D01*
X557027Y255550D01*
X557410Y255447D01*
X557678Y255188D01*
X557755Y254878D01*
X557717Y254568D01*
X557563Y254310D01*
X556797Y253793D01*
X556452Y253432D01*
X556222Y252915D01*
X556145Y252450D01*
X557755D01*
G01X559207Y252915D02*
X559437Y252657D01*
X559705Y252502D01*
X560050Y252450D01*
X560395Y252553D01*
X560663Y252760D01*
X560855Y253122D01*
X560893Y253535D01*
X560817Y253948D01*
X560625Y254207D01*
X560357Y254413D01*
X560088Y254465D01*
X559820Y254413D01*
X559475Y254207D01*
X559590Y255550D01*
X560625D01*
G01X563610Y252450D02*
Y255550D01*
X562192Y253328D01*
X564108D01*
G01X558633Y309570D02*
X558825Y309260D01*
X559055Y309053D01*
X559323Y308950D01*
X559630Y309053D01*
X559860Y309260D01*
X560090Y309570D01*
X560167Y309983D01*
Y312050D01*
G01X562500Y308950D02*
Y312050D01*
X562040Y311430D01*
G01Y308950D02*
X562960D01*
G01X566060D02*
Y312050D01*
X564642Y309828D01*
X566558D01*
G01X566343Y334792D02*
X566113Y334947D01*
X565845Y335050D01*
X565538D01*
X565193Y334895D01*
X564925Y334637D01*
X564733Y334327D01*
X564580Y333810D01*
X564542Y333345D01*
X564618Y332880D01*
X564733Y332570D01*
X564963Y332260D01*
X565232Y332053D01*
X565500Y331950D01*
X565768D01*
X566037Y332053D01*
X566267Y332208D01*
X566458Y332415D01*
G01X558293Y353792D02*
X558063Y353947D01*
X557795Y354050D01*
X557488D01*
X557143Y353895D01*
X556875Y353637D01*
X556683Y353327D01*
X556530Y352810D01*
X556492Y352345D01*
X556568Y351880D01*
X556683Y351570D01*
X556913Y351260D01*
X557182Y351053D01*
X557450Y350950D01*
X557718D01*
X557987Y351053D01*
X558217Y351208D01*
X558408Y351415D01*
G01X559822Y353533D02*
X560052Y353843D01*
X560320Y353998D01*
X560627Y354050D01*
X561010Y353947D01*
X561278Y353688D01*
X561355Y353378D01*
X561317Y353068D01*
X561163Y352810D01*
X560397Y352293D01*
X560052Y351932D01*
X559822Y351415D01*
X559745Y350950D01*
X561355D01*
G01X551850Y349050D02*
Y345950D01*
G01X550968Y349050D02*
X552732D01*
G01X554183Y345950D02*
Y349050D01*
X555103D01*
X555410Y348895D01*
X555640Y348533D01*
X555717Y348120D01*
X555640Y347707D01*
X555448Y347397D01*
X555103Y347242D01*
X554183D01*
G01X558510Y345950D02*
Y349050D01*
X557092Y346828D01*
X559008D01*
G01X560307Y346570D02*
X560537Y346208D01*
X560843Y346002D01*
X561188Y345950D01*
X561495Y346002D01*
X561802Y346260D01*
X561993Y346570D01*
X562032Y346880D01*
X561955Y347242D01*
X561687Y347500D01*
X561418Y347603D01*
X561073D01*
G01X561418D02*
X561648Y347758D01*
X561840Y348017D01*
X561917Y348327D01*
X561840Y348637D01*
X561648Y348895D01*
X561303Y349050D01*
X560958Y348998D01*
X560613Y348792D01*
G01X563267Y386750D02*
Y389250D01*
X563933D01*
X564147Y389125D01*
X564280Y388958D01*
X564333Y388625D01*
X564280Y388292D01*
X564120Y388083D01*
X563933Y387958D01*
X563267D01*
G01X563933D02*
X564333Y386750D01*
G01X566000D02*
Y389250D01*
X565680Y388750D01*
G01Y386750D02*
X566320D01*
G01X568520D02*
Y389250D01*
X567533Y387458D01*
X568867D01*
G01X564547Y381542D02*
X564733Y381333D01*
X564947Y381250D01*
X565160Y381333D01*
X565347Y381583D01*
X565480Y381958D01*
X565533Y382333D01*
Y382792D01*
X565480Y383167D01*
X565347Y383500D01*
X565187Y383667D01*
X565000Y383750D01*
X564787Y383667D01*
X564627Y383500D01*
X564520Y383250D01*
X564467Y382917D01*
X564520Y382625D01*
X564653Y382333D01*
X564813Y382167D01*
X565000Y382125D01*
X565213Y382208D01*
X565373Y382417D01*
X565533Y382792D01*
G01X562750Y405213D02*
X560250D01*
Y405747D01*
X560375Y405960D01*
X560542Y406120D01*
X560792Y406253D01*
X561083Y406360D01*
X561500Y406387D01*
X561917Y406360D01*
X562208Y406253D01*
X562458Y406120D01*
X562625Y405960D01*
X562750Y405747D01*
Y405213D01*
G01X562417Y407440D02*
X562625Y407653D01*
X562750Y407893D01*
Y408107D01*
X562625Y408320D01*
X562417Y408480D01*
X562125Y408560D01*
X561833Y408507D01*
X561583Y408373D01*
X561417Y408133D01*
X561333Y407813D01*
X561167Y407627D01*
X560875Y407547D01*
X560583Y407600D01*
X560375Y407733D01*
X560250Y407920D01*
Y408107D01*
X560333Y408293D01*
X560542Y408453D01*
G01X562750Y410200D02*
X562708Y410387D01*
X562583Y410600D01*
X562375Y410733D01*
X562083Y410787D01*
X561792Y410733D01*
X561542Y410573D01*
X561417Y410333D01*
Y410067D01*
X561333Y409907D01*
X561125Y409773D01*
X560833Y409720D01*
X560542Y409800D01*
X560333Y409987D01*
X560250Y410200D01*
X560333Y410413D01*
X560542Y410600D01*
X560833Y410680D01*
X561125Y410627D01*
X561333Y410493D01*
X561417Y410333D01*
Y410067D01*
X561542Y409827D01*
X561792Y409667D01*
X562083Y409613D01*
X562375Y409667D01*
X562583Y409800D01*
X562708Y410013D01*
X562750Y410200D01*
G01X553087Y402542D02*
X552927Y402667D01*
X552740Y402750D01*
X552527D01*
X552287Y402625D01*
X552100Y402417D01*
X551967Y402167D01*
X551860Y401750D01*
X551833Y401375D01*
X551887Y401000D01*
X551967Y400750D01*
X552127Y400500D01*
X552313Y400333D01*
X552500Y400250D01*
X552687D01*
X552873Y400333D01*
X553033Y400458D01*
X553167Y400625D01*
G01X563267Y392250D02*
Y394750D01*
X563933D01*
X564147Y394625D01*
X564280Y394458D01*
X564333Y394125D01*
X564280Y393792D01*
X564120Y393583D01*
X563933Y393458D01*
X563267D01*
G01X563933D02*
X564333Y392250D01*
G01X566000D02*
Y394750D01*
X565680Y394250D01*
G01Y392250D02*
X566320D01*
G01X567613Y392750D02*
X567773Y392458D01*
X567987Y392292D01*
X568227Y392250D01*
X568440Y392292D01*
X568653Y392500D01*
X568787Y392750D01*
X568813Y393000D01*
X568760Y393292D01*
X568573Y393500D01*
X568387Y393583D01*
X568147D01*
G01X568387D02*
X568547Y393708D01*
X568680Y393917D01*
X568733Y394167D01*
X568680Y394417D01*
X568547Y394625D01*
X568307Y394750D01*
X568067Y394708D01*
X567827Y394542D01*
G01X562700Y401750D02*
Y399250D01*
G01X562087Y401750D02*
X563313D01*
G01X564367Y399250D02*
Y401750D01*
X565007D01*
X565220Y401625D01*
X565380Y401333D01*
X565433Y401000D01*
X565380Y400667D01*
X565247Y400417D01*
X565007Y400292D01*
X564367D01*
G01X566513Y399750D02*
X566673Y399458D01*
X566887Y399292D01*
X567127Y399250D01*
X567340Y399292D01*
X567553Y399500D01*
X567687Y399750D01*
X567713Y400000D01*
X567660Y400292D01*
X567473Y400500D01*
X567287Y400583D01*
X567047D01*
G01X567287D02*
X567447Y400708D01*
X567580Y400917D01*
X567633Y401167D01*
X567580Y401417D01*
X567447Y401625D01*
X567207Y401750D01*
X566967Y401708D01*
X566727Y401542D01*
G01X568793Y400292D02*
X568980Y400583D01*
X569140Y400750D01*
X569353Y400833D01*
X569540Y400750D01*
X569673Y400583D01*
X569780Y400333D01*
X569807Y400042D01*
X569780Y399792D01*
X569673Y399542D01*
X569513Y399333D01*
X569327Y399250D01*
X569113Y399333D01*
X568927Y399583D01*
X568820Y399958D01*
X568793Y400375D01*
X568847Y400917D01*
X568927Y401208D01*
X569060Y401500D01*
X569247Y401708D01*
X569433Y401750D01*
X569620Y401667D01*
X569753Y401458D01*
G01X559833Y414250D02*
X560500Y416750D01*
X561167Y414250D01*
G01X560927Y415125D02*
X560073D01*
G01X562550Y419713D02*
X560050D01*
Y420247D01*
X560175Y420460D01*
X560342Y420620D01*
X560592Y420753D01*
X560883Y420860D01*
X561300Y420887D01*
X561717Y420860D01*
X562008Y420753D01*
X562258Y420620D01*
X562425Y420460D01*
X562550Y420247D01*
Y419713D01*
G01X562217Y421940D02*
X562425Y422153D01*
X562550Y422393D01*
Y422607D01*
X562425Y422820D01*
X562217Y422980D01*
X561925Y423060D01*
X561633Y423007D01*
X561383Y422873D01*
X561217Y422633D01*
X561133Y422313D01*
X560967Y422127D01*
X560675Y422047D01*
X560383Y422100D01*
X560175Y422233D01*
X560050Y422420D01*
Y422607D01*
X560133Y422793D01*
X560342Y422953D01*
G01X562050Y424113D02*
X562342Y424273D01*
X562508Y424487D01*
X562550Y424727D01*
X562508Y424940D01*
X562300Y425153D01*
X562050Y425287D01*
X561800Y425313D01*
X561508Y425260D01*
X561300Y425073D01*
X561217Y424887D01*
Y424647D01*
G01Y424887D02*
X561092Y425047D01*
X560883Y425180D01*
X560633Y425233D01*
X560383Y425180D01*
X560175Y425047D01*
X560050Y424807D01*
X560092Y424567D01*
X560258Y424327D01*
G01X557333Y430750D02*
X558000Y433250D01*
X558667Y430750D01*
G01X558427Y431625D02*
X557573D01*
G01X583693Y62292D02*
X583463Y62447D01*
X583195Y62550D01*
X582888D01*
X582543Y62395D01*
X582275Y62137D01*
X582083Y61827D01*
X581930Y61310D01*
X581892Y60845D01*
X581968Y60380D01*
X582083Y60070D01*
X582313Y59760D01*
X582582Y59553D01*
X582850Y59450D01*
X583118D01*
X583387Y59553D01*
X583617Y59708D01*
X583808Y59915D01*
G01X585222Y62033D02*
X585452Y62343D01*
X585720Y62498D01*
X586027Y62550D01*
X586410Y62447D01*
X586678Y62188D01*
X586755Y61878D01*
X586717Y61568D01*
X586563Y61310D01*
X585797Y60793D01*
X585452Y60432D01*
X585222Y59915D01*
X585145Y59450D01*
X586755D01*
G01X588322Y62033D02*
X588552Y62343D01*
X588820Y62498D01*
X589127Y62550D01*
X589510Y62447D01*
X589778Y62188D01*
X589855Y61878D01*
X589817Y61568D01*
X589663Y61310D01*
X588897Y60793D01*
X588552Y60432D01*
X588322Y59915D01*
X588245Y59450D01*
X589855D01*
G01X592073D02*
X592150Y60122D01*
X592265Y60690D01*
X592418Y61207D01*
X592610Y61775D01*
X592917Y62550D01*
X591383D01*
G01X583693Y58292D02*
X583463Y58447D01*
X583195Y58550D01*
X582888D01*
X582543Y58395D01*
X582275Y58137D01*
X582083Y57827D01*
X581930Y57310D01*
X581892Y56845D01*
X581968Y56380D01*
X582083Y56070D01*
X582313Y55760D01*
X582582Y55553D01*
X582850Y55450D01*
X583118D01*
X583387Y55553D01*
X583617Y55708D01*
X583808Y55915D01*
G01X585222Y58033D02*
X585452Y58343D01*
X585720Y58498D01*
X586027Y58550D01*
X586410Y58447D01*
X586678Y58188D01*
X586755Y57878D01*
X586717Y57568D01*
X586563Y57310D01*
X585797Y56793D01*
X585452Y56432D01*
X585222Y55915D01*
X585145Y55450D01*
X586755D01*
G01X588207Y56070D02*
X588437Y55708D01*
X588743Y55502D01*
X589088Y55450D01*
X589395Y55502D01*
X589702Y55760D01*
X589893Y56070D01*
X589932Y56380D01*
X589855Y56742D01*
X589587Y57000D01*
X589318Y57103D01*
X588973D01*
G01X589318D02*
X589548Y57258D01*
X589740Y57517D01*
X589817Y57827D01*
X589740Y58137D01*
X589548Y58395D01*
X589203Y58550D01*
X588858Y58498D01*
X588513Y58292D01*
G01X592150Y55450D02*
Y58550D01*
X591690Y57930D01*
G01Y55450D02*
X592610D01*
G01X582583Y63450D02*
Y66550D01*
X583542D01*
X583848Y66395D01*
X584040Y66188D01*
X584117Y65775D01*
X584040Y65362D01*
X583810Y65103D01*
X583542Y64948D01*
X582583D01*
G01X583542D02*
X584117Y63450D01*
G01X585722Y66033D02*
X585952Y66343D01*
X586220Y66498D01*
X586527Y66550D01*
X586910Y66447D01*
X587178Y66188D01*
X587255Y65878D01*
X587217Y65568D01*
X587063Y65310D01*
X586297Y64793D01*
X585952Y64432D01*
X585722Y63915D01*
X585645Y63450D01*
X587255D01*
G01X588822Y66033D02*
X589052Y66343D01*
X589320Y66498D01*
X589627Y66550D01*
X590010Y66447D01*
X590278Y66188D01*
X590355Y65878D01*
X590317Y65568D01*
X590163Y65310D01*
X589397Y64793D01*
X589052Y64432D01*
X588822Y63915D01*
X588745Y63450D01*
X590355D01*
G01X592650D02*
X592918Y63502D01*
X593225Y63657D01*
X593417Y63915D01*
X593493Y64277D01*
X593417Y64638D01*
X593187Y64948D01*
X592842Y65103D01*
X592458D01*
X592228Y65207D01*
X592037Y65465D01*
X591960Y65827D01*
X592075Y66188D01*
X592343Y66447D01*
X592650Y66550D01*
X592957Y66447D01*
X593225Y66188D01*
X593340Y65827D01*
X593263Y65465D01*
X593072Y65207D01*
X592842Y65103D01*
X592458D01*
X592113Y64948D01*
X591883Y64638D01*
X591807Y64277D01*
X591883Y63915D01*
X592075Y63657D01*
X592382Y63502D01*
X592650Y63450D01*
G01X572622Y63064D02*
X572890Y63425D01*
X573120Y63632D01*
X573427Y63735D01*
X573695Y63632D01*
X573887Y63425D01*
X574040Y63115D01*
X574078Y62754D01*
X574040Y62444D01*
X573887Y62134D01*
X573657Y61875D01*
X573388Y61772D01*
X573082Y61875D01*
X572813Y62185D01*
X572660Y62650D01*
X572622Y63167D01*
X572698Y63839D01*
X572813Y64200D01*
X573005Y64562D01*
X573273Y64820D01*
X573542Y64872D01*
X573810Y64769D01*
X574002Y64510D01*
G01X575193Y86292D02*
X574963Y86447D01*
X574695Y86550D01*
X574388D01*
X574043Y86395D01*
X573775Y86137D01*
X573583Y85827D01*
X573430Y85310D01*
X573392Y84845D01*
X573468Y84380D01*
X573583Y84070D01*
X573813Y83760D01*
X574082Y83553D01*
X574350Y83450D01*
X574618D01*
X574887Y83553D01*
X575117Y83708D01*
X575308Y83915D01*
G01X576722Y86033D02*
X576952Y86343D01*
X577220Y86498D01*
X577527Y86550D01*
X577910Y86447D01*
X578178Y86188D01*
X578255Y85878D01*
X578217Y85568D01*
X578063Y85310D01*
X577297Y84793D01*
X576952Y84432D01*
X576722Y83915D01*
X576645Y83450D01*
X578255D01*
G01X579707Y84070D02*
X579937Y83708D01*
X580243Y83502D01*
X580588Y83450D01*
X580895Y83502D01*
X581202Y83760D01*
X581393Y84070D01*
X581432Y84380D01*
X581355Y84742D01*
X581087Y85000D01*
X580818Y85103D01*
X580473D01*
G01X580818D02*
X581048Y85258D01*
X581240Y85517D01*
X581317Y85827D01*
X581240Y86137D01*
X581048Y86395D01*
X580703Y86550D01*
X580358Y86498D01*
X580013Y86292D01*
G01X583650Y86550D02*
X583343Y86447D01*
X583113Y86188D01*
X582960Y85878D01*
X582845Y85465D01*
X582807Y85000D01*
X582845Y84535D01*
X582960Y84122D01*
X583113Y83812D01*
X583343Y83553D01*
X583650Y83450D01*
X583957Y83553D01*
X584187Y83812D01*
X584340Y84122D01*
X584455Y84535D01*
X584493Y85000D01*
X584455Y85465D01*
X584340Y85878D01*
X584187Y86188D01*
X583957Y86447D01*
X583650Y86550D01*
G01X575193Y90292D02*
X574963Y90447D01*
X574695Y90550D01*
X574388D01*
X574043Y90395D01*
X573775Y90137D01*
X573583Y89827D01*
X573430Y89310D01*
X573392Y88845D01*
X573468Y88380D01*
X573583Y88070D01*
X573813Y87760D01*
X574082Y87553D01*
X574350Y87450D01*
X574618D01*
X574887Y87553D01*
X575117Y87708D01*
X575308Y87915D01*
G01X576722Y90033D02*
X576952Y90343D01*
X577220Y90498D01*
X577527Y90550D01*
X577910Y90447D01*
X578178Y90188D01*
X578255Y89878D01*
X578217Y89568D01*
X578063Y89310D01*
X577297Y88793D01*
X576952Y88432D01*
X576722Y87915D01*
X576645Y87450D01*
X578255D01*
G01X579822Y90033D02*
X580052Y90343D01*
X580320Y90498D01*
X580627Y90550D01*
X581010Y90447D01*
X581278Y90188D01*
X581355Y89878D01*
X581317Y89568D01*
X581163Y89310D01*
X580397Y88793D01*
X580052Y88432D01*
X579822Y87915D01*
X579745Y87450D01*
X581355D01*
G01X583650D02*
X583918Y87502D01*
X584225Y87657D01*
X584417Y87915D01*
X584493Y88277D01*
X584417Y88638D01*
X584187Y88948D01*
X583842Y89103D01*
X583458D01*
X583228Y89207D01*
X583037Y89465D01*
X582960Y89827D01*
X583075Y90188D01*
X583343Y90447D01*
X583650Y90550D01*
X583957Y90447D01*
X584225Y90188D01*
X584340Y89827D01*
X584263Y89465D01*
X584072Y89207D01*
X583842Y89103D01*
X583458D01*
X583113Y88948D01*
X582883Y88638D01*
X582807Y88277D01*
X582883Y87915D01*
X583075Y87657D01*
X583382Y87502D01*
X583650Y87450D01*
G01X574850Y96050D02*
Y92950D01*
G01X573968Y96050D02*
X575732D01*
G01X577183Y92950D02*
Y96050D01*
X578103D01*
X578410Y95895D01*
X578640Y95533D01*
X578717Y95120D01*
X578640Y94707D01*
X578448Y94397D01*
X578103Y94242D01*
X577183D01*
G01X581510Y92950D02*
Y96050D01*
X580092Y93828D01*
X582008D01*
G01X584150Y92950D02*
Y96050D01*
X583690Y95430D01*
G01Y92950D02*
X584610D01*
G01X574350Y109550D02*
Y106450D01*
G01X573468Y109550D02*
X575232D01*
G01X576683Y106450D02*
Y109550D01*
X577603D01*
X577910Y109395D01*
X578140Y109033D01*
X578217Y108620D01*
X578140Y108207D01*
X577948Y107897D01*
X577603Y107742D01*
X576683D01*
G01X579822Y109033D02*
X580052Y109343D01*
X580320Y109498D01*
X580627Y109550D01*
X581010Y109447D01*
X581278Y109188D01*
X581355Y108878D01*
X581317Y108568D01*
X581163Y108310D01*
X580397Y107793D01*
X580052Y107432D01*
X579822Y106915D01*
X579745Y106450D01*
X581355D01*
G01X582922Y109033D02*
X583152Y109343D01*
X583420Y109498D01*
X583727Y109550D01*
X584110Y109447D01*
X584378Y109188D01*
X584455Y108878D01*
X584417Y108568D01*
X584263Y108310D01*
X583497Y107793D01*
X583152Y107432D01*
X582922Y106915D01*
X582845Y106450D01*
X584455D01*
G01X585083Y114950D02*
Y118050D01*
X586042D01*
X586348Y117895D01*
X586540Y117688D01*
X586617Y117275D01*
X586540Y116862D01*
X586310Y116603D01*
X586042Y116448D01*
X585083D01*
G01X586042D02*
X586617Y114950D01*
G01X589410D02*
Y118050D01*
X587992Y115828D01*
X589908D01*
G01X592050Y118050D02*
X591743Y117947D01*
X591513Y117688D01*
X591360Y117378D01*
X591245Y116965D01*
X591207Y116500D01*
X591245Y116035D01*
X591360Y115622D01*
X591513Y115312D01*
X591743Y115053D01*
X592050Y114950D01*
X592357Y115053D01*
X592587Y115312D01*
X592740Y115622D01*
X592855Y116035D01*
X592893Y116500D01*
X592855Y116965D01*
X592740Y117378D01*
X592587Y117688D01*
X592357Y117947D01*
X592050Y118050D01*
G01X595073Y114950D02*
X595150Y115622D01*
X595265Y116190D01*
X595418Y116707D01*
X595610Y117275D01*
X595917Y118050D01*
X594383D01*
G01X585133Y118950D02*
Y122050D01*
X586092D01*
X586398Y121895D01*
X586590Y121688D01*
X586667Y121275D01*
X586590Y120862D01*
X586360Y120603D01*
X586092Y120448D01*
X585133D01*
G01X586092D02*
X586667Y118950D01*
G01X588272Y121533D02*
X588502Y121843D01*
X588770Y121998D01*
X589077Y122050D01*
X589460Y121947D01*
X589728Y121688D01*
X589805Y121378D01*
X589767Y121068D01*
X589613Y120810D01*
X588847Y120293D01*
X588502Y119932D01*
X588272Y119415D01*
X588195Y118950D01*
X589805D01*
G01X592100Y122050D02*
X591793Y121947D01*
X591563Y121688D01*
X591410Y121378D01*
X591295Y120965D01*
X591257Y120500D01*
X591295Y120035D01*
X591410Y119622D01*
X591563Y119312D01*
X591793Y119053D01*
X592100Y118950D01*
X592407Y119053D01*
X592637Y119312D01*
X592790Y119622D01*
X592905Y120035D01*
X592943Y120500D01*
X592905Y120965D01*
X592790Y121378D01*
X592637Y121688D01*
X592407Y121947D01*
X592100Y122050D01*
G01X585950Y123950D02*
Y127050D01*
X585490Y126430D01*
G01Y123950D02*
X586410D01*
G01X588322Y126533D02*
X588552Y126843D01*
X588820Y126998D01*
X589127Y127050D01*
X589510Y126947D01*
X589778Y126688D01*
X589855Y126378D01*
X589817Y126068D01*
X589663Y125810D01*
X588897Y125293D01*
X588552Y124932D01*
X588322Y124415D01*
X588245Y123950D01*
X589855D01*
G01X578350Y180050D02*
Y176950D01*
G01X577468Y180050D02*
X579232D01*
G01X580683Y176950D02*
Y180050D01*
X581603D01*
X581910Y179895D01*
X582140Y179533D01*
X582217Y179120D01*
X582140Y178707D01*
X581948Y178397D01*
X581603Y178242D01*
X580683D01*
G01X583822Y179533D02*
X584052Y179843D01*
X584320Y179998D01*
X584627Y180050D01*
X585010Y179947D01*
X585278Y179688D01*
X585355Y179378D01*
X585317Y179068D01*
X585163Y178810D01*
X584397Y178293D01*
X584052Y177932D01*
X583822Y177415D01*
X583745Y176950D01*
X585355D01*
G01X587573D02*
X587650Y177622D01*
X587765Y178190D01*
X587918Y178707D01*
X588110Y179275D01*
X588417Y180050D01*
X586883D01*
G01X576772Y170033D02*
X577002Y170343D01*
X577270Y170498D01*
X577577Y170550D01*
X577960Y170447D01*
X578228Y170188D01*
X578305Y169878D01*
X578267Y169568D01*
X578113Y169310D01*
X577347Y168793D01*
X577002Y168432D01*
X576772Y167915D01*
X576695Y167450D01*
X578305D01*
G01X580550Y189133D02*
X577450D01*
Y190092D01*
X577605Y190398D01*
X577812Y190590D01*
X578225Y190667D01*
X578638Y190590D01*
X578897Y190360D01*
X579052Y190092D01*
Y189133D01*
G01Y190092D02*
X580550Y190667D01*
G01X579258Y192272D02*
X578897Y192540D01*
X578690Y192770D01*
X578587Y193077D01*
X578690Y193345D01*
X578897Y193537D01*
X579207Y193690D01*
X579568Y193728D01*
X579878Y193690D01*
X580188Y193537D01*
X580447Y193307D01*
X580550Y193038D01*
X580447Y192732D01*
X580137Y192463D01*
X579672Y192310D01*
X579155Y192272D01*
X578483Y192348D01*
X578122Y192463D01*
X577760Y192655D01*
X577502Y192923D01*
X577450Y193192D01*
X577553Y193460D01*
X577812Y193652D01*
G01X579258Y195372D02*
X578897Y195640D01*
X578690Y195870D01*
X578587Y196177D01*
X578690Y196445D01*
X578897Y196637D01*
X579207Y196790D01*
X579568Y196828D01*
X579878Y196790D01*
X580188Y196637D01*
X580447Y196407D01*
X580550Y196138D01*
X580447Y195832D01*
X580137Y195563D01*
X579672Y195410D01*
X579155Y195372D01*
X578483Y195448D01*
X578122Y195563D01*
X577760Y195755D01*
X577502Y196023D01*
X577450Y196292D01*
X577553Y196560D01*
X577812Y196752D01*
G01X586950Y189103D02*
X583850D01*
Y190062D01*
X584005Y190368D01*
X584212Y190560D01*
X584625Y190637D01*
X585038Y190560D01*
X585297Y190330D01*
X585452Y190062D01*
Y189103D01*
G01Y190062D02*
X586950Y190637D01*
G01X585658Y192242D02*
X585297Y192510D01*
X585090Y192740D01*
X584987Y193047D01*
X585090Y193315D01*
X585297Y193507D01*
X585607Y193660D01*
X585968Y193698D01*
X586278Y193660D01*
X586588Y193507D01*
X586847Y193277D01*
X586950Y193008D01*
X586847Y192702D01*
X586537Y192433D01*
X586072Y192280D01*
X585555Y192242D01*
X584883Y192318D01*
X584522Y192433D01*
X584160Y192625D01*
X583902Y192893D01*
X583850Y193162D01*
X583953Y193430D01*
X584212Y193622D01*
G01X586950Y196070D02*
X586898Y196338D01*
X586743Y196645D01*
X586485Y196837D01*
X586123Y196913D01*
X585762Y196837D01*
X585452Y196607D01*
X585297Y196262D01*
Y195878D01*
X585193Y195648D01*
X584935Y195457D01*
X584573Y195380D01*
X584212Y195495D01*
X583953Y195763D01*
X583850Y196070D01*
X583953Y196377D01*
X584212Y196645D01*
X584573Y196760D01*
X584935Y196683D01*
X585193Y196492D01*
X585297Y196262D01*
Y195878D01*
X585452Y195533D01*
X585762Y195303D01*
X586123Y195227D01*
X586485Y195303D01*
X586743Y195495D01*
X586898Y195802D01*
X586950Y196070D01*
G01X575500Y196250D02*
Y198750D01*
X575180Y198250D01*
G01Y196250D02*
X575820D01*
G01X580708Y203193D02*
X580553Y202963D01*
X580450Y202695D01*
Y202388D01*
X580605Y202043D01*
X580863Y201775D01*
X581173Y201583D01*
X581690Y201430D01*
X582155Y201392D01*
X582620Y201468D01*
X582930Y201583D01*
X583240Y201813D01*
X583447Y202082D01*
X583550Y202350D01*
Y202618D01*
X583447Y202887D01*
X583292Y203117D01*
X583085Y203308D01*
G01X580967Y204722D02*
X580657Y204952D01*
X580502Y205220D01*
X580450Y205527D01*
X580553Y205910D01*
X580812Y206178D01*
X581122Y206255D01*
X581432Y206217D01*
X581690Y206063D01*
X582207Y205297D01*
X582568Y204952D01*
X583085Y204722D01*
X583550Y204645D01*
Y206255D01*
G01X582258Y207822D02*
X581897Y208090D01*
X581690Y208320D01*
X581587Y208627D01*
X581690Y208895D01*
X581897Y209087D01*
X582207Y209240D01*
X582568Y209278D01*
X582878Y209240D01*
X583188Y209087D01*
X583447Y208857D01*
X583550Y208588D01*
X583447Y208282D01*
X583137Y208013D01*
X582672Y207860D01*
X582155Y207822D01*
X581483Y207898D01*
X581122Y208013D01*
X580760Y208205D01*
X580502Y208473D01*
X580450Y208742D01*
X580553Y209010D01*
X580812Y209202D01*
G01X580967Y210922D02*
X580657Y211152D01*
X580502Y211420D01*
X580450Y211727D01*
X580553Y212110D01*
X580812Y212378D01*
X581122Y212455D01*
X581432Y212417D01*
X581690Y212263D01*
X582207Y211497D01*
X582568Y211152D01*
X583085Y210922D01*
X583550Y210845D01*
Y212455D01*
G01X585208Y203193D02*
X585053Y202963D01*
X584950Y202695D01*
Y202388D01*
X585105Y202043D01*
X585363Y201775D01*
X585673Y201583D01*
X586190Y201430D01*
X586655Y201392D01*
X587120Y201468D01*
X587430Y201583D01*
X587740Y201813D01*
X587947Y202082D01*
X588050Y202350D01*
Y202618D01*
X587947Y202887D01*
X587792Y203117D01*
X587585Y203308D01*
G01X585467Y204722D02*
X585157Y204952D01*
X585002Y205220D01*
X584950Y205527D01*
X585053Y205910D01*
X585312Y206178D01*
X585622Y206255D01*
X585932Y206217D01*
X586190Y206063D01*
X586707Y205297D01*
X587068Y204952D01*
X587585Y204722D01*
X588050Y204645D01*
Y206255D01*
G01X587585Y207707D02*
X587843Y207937D01*
X587998Y208205D01*
X588050Y208550D01*
X587947Y208895D01*
X587740Y209163D01*
X587378Y209355D01*
X586965Y209393D01*
X586552Y209317D01*
X586293Y209125D01*
X586087Y208857D01*
X586035Y208588D01*
X586087Y208320D01*
X586293Y207975D01*
X584950Y208090D01*
Y209125D01*
G01X588050Y211573D02*
X587378Y211650D01*
X586810Y211765D01*
X586293Y211918D01*
X585725Y212110D01*
X584950Y212417D01*
Y210883D01*
G01X580583Y213950D02*
Y217050D01*
X581542D01*
X581848Y216895D01*
X582040Y216688D01*
X582117Y216275D01*
X582040Y215862D01*
X581810Y215603D01*
X581542Y215448D01*
X580583D01*
G01X581542D02*
X582117Y213950D01*
G01X583722Y216533D02*
X583952Y216843D01*
X584220Y216998D01*
X584527Y217050D01*
X584910Y216947D01*
X585178Y216688D01*
X585255Y216378D01*
X585217Y216068D01*
X585063Y215810D01*
X584297Y215293D01*
X583952Y214932D01*
X583722Y214415D01*
X583645Y213950D01*
X585255D01*
G01X588010D02*
Y217050D01*
X586592Y214828D01*
X588508D01*
G01X590650Y213950D02*
X590918Y214002D01*
X591225Y214157D01*
X591417Y214415D01*
X591493Y214777D01*
X591417Y215138D01*
X591187Y215448D01*
X590842Y215603D01*
X590458D01*
X590228Y215707D01*
X590037Y215965D01*
X589960Y216327D01*
X590075Y216688D01*
X590343Y216947D01*
X590650Y217050D01*
X590957Y216947D01*
X591225Y216688D01*
X591340Y216327D01*
X591263Y215965D01*
X591072Y215707D01*
X590842Y215603D01*
X590458D01*
X590113Y215448D01*
X589883Y215138D01*
X589807Y214777D01*
X589883Y214415D01*
X590075Y214157D01*
X590382Y214002D01*
X590650Y213950D01*
G01X584050Y225083D02*
X580950D01*
Y226042D01*
X581105Y226348D01*
X581312Y226540D01*
X581725Y226617D01*
X582138Y226540D01*
X582397Y226310D01*
X582552Y226042D01*
Y225083D01*
G01Y226042D02*
X584050Y226617D01*
G01X581467Y228222D02*
X581157Y228452D01*
X581002Y228720D01*
X580950Y229027D01*
X581053Y229410D01*
X581312Y229678D01*
X581622Y229755D01*
X581932Y229717D01*
X582190Y229563D01*
X582707Y228797D01*
X583068Y228452D01*
X583585Y228222D01*
X584050Y228145D01*
Y229755D01*
G01X583585Y231207D02*
X583843Y231437D01*
X583998Y231705D01*
X584050Y232050D01*
X583947Y232395D01*
X583740Y232663D01*
X583378Y232855D01*
X582965Y232893D01*
X582552Y232817D01*
X582293Y232625D01*
X582087Y232357D01*
X582035Y232088D01*
X582087Y231820D01*
X582293Y231475D01*
X580950Y231590D01*
Y232625D01*
G01X583585Y234307D02*
X583843Y234537D01*
X583998Y234805D01*
X584050Y235150D01*
X583947Y235495D01*
X583740Y235763D01*
X583378Y235955D01*
X582965Y235993D01*
X582552Y235917D01*
X582293Y235725D01*
X582087Y235457D01*
X582035Y235188D01*
X582087Y234920D01*
X582293Y234575D01*
X580950Y234690D01*
Y235725D01*
G01X568900Y219250D02*
Y221750D01*
X568580Y221250D01*
G01Y219250D02*
X569220D01*
G01X570593Y221333D02*
X570753Y221583D01*
X570940Y221708D01*
X571153Y221750D01*
X571420Y221667D01*
X571607Y221458D01*
X571660Y221208D01*
X571633Y220958D01*
X571527Y220750D01*
X570993Y220333D01*
X570753Y220042D01*
X570593Y219625D01*
X570540Y219250D01*
X571660D01*
G01X581083Y236950D02*
Y240050D01*
X582042D01*
X582348Y239895D01*
X582540Y239688D01*
X582617Y239275D01*
X582540Y238862D01*
X582310Y238603D01*
X582042Y238448D01*
X581083D01*
G01X582042D02*
X582617Y236950D01*
G01X584222Y239533D02*
X584452Y239843D01*
X584720Y239998D01*
X585027Y240050D01*
X585410Y239947D01*
X585678Y239688D01*
X585755Y239378D01*
X585717Y239068D01*
X585563Y238810D01*
X584797Y238293D01*
X584452Y237932D01*
X584222Y237415D01*
X584145Y236950D01*
X585755D01*
G01X587398Y237312D02*
X587667Y237053D01*
X587973Y236950D01*
X588280Y237053D01*
X588548Y237363D01*
X588740Y237828D01*
X588817Y238293D01*
Y238862D01*
X588740Y239327D01*
X588548Y239740D01*
X588318Y239947D01*
X588050Y240050D01*
X587743Y239947D01*
X587513Y239740D01*
X587360Y239430D01*
X587283Y239017D01*
X587360Y238655D01*
X587552Y238293D01*
X587782Y238087D01*
X588050Y238035D01*
X588357Y238138D01*
X588587Y238397D01*
X588817Y238862D01*
G01X590422Y238242D02*
X590690Y238603D01*
X590920Y238810D01*
X591227Y238913D01*
X591495Y238810D01*
X591687Y238603D01*
X591840Y238293D01*
X591878Y237932D01*
X591840Y237622D01*
X591687Y237312D01*
X591457Y237053D01*
X591188Y236950D01*
X590882Y237053D01*
X590613Y237363D01*
X590460Y237828D01*
X590422Y238345D01*
X590498Y239017D01*
X590613Y239378D01*
X590805Y239740D01*
X591073Y239998D01*
X591342Y240050D01*
X591610Y239947D01*
X591802Y239688D01*
G01X581083Y240950D02*
Y244050D01*
X582042D01*
X582348Y243895D01*
X582540Y243688D01*
X582617Y243275D01*
X582540Y242862D01*
X582310Y242603D01*
X582042Y242448D01*
X581083D01*
G01X582042D02*
X582617Y240950D01*
G01X584222Y243533D02*
X584452Y243843D01*
X584720Y243998D01*
X585027Y244050D01*
X585410Y243947D01*
X585678Y243688D01*
X585755Y243378D01*
X585717Y243068D01*
X585563Y242810D01*
X584797Y242293D01*
X584452Y241932D01*
X584222Y241415D01*
X584145Y240950D01*
X585755D01*
G01X587398Y241312D02*
X587667Y241053D01*
X587973Y240950D01*
X588280Y241053D01*
X588548Y241363D01*
X588740Y241828D01*
X588817Y242293D01*
Y242862D01*
X588740Y243327D01*
X588548Y243740D01*
X588318Y243947D01*
X588050Y244050D01*
X587743Y243947D01*
X587513Y243740D01*
X587360Y243430D01*
X587283Y243017D01*
X587360Y242655D01*
X587552Y242293D01*
X587782Y242087D01*
X588050Y242035D01*
X588357Y242138D01*
X588587Y242397D01*
X588817Y242862D01*
G01X591073Y240950D02*
X591150Y241622D01*
X591265Y242190D01*
X591418Y242707D01*
X591610Y243275D01*
X591917Y244050D01*
X590383D01*
G01X581083Y246950D02*
Y250050D01*
X582042D01*
X582348Y249895D01*
X582540Y249688D01*
X582617Y249275D01*
X582540Y248862D01*
X582310Y248603D01*
X582042Y248448D01*
X581083D01*
G01X582042D02*
X582617Y246950D01*
G01X584222Y249533D02*
X584452Y249843D01*
X584720Y249998D01*
X585027Y250050D01*
X585410Y249947D01*
X585678Y249688D01*
X585755Y249378D01*
X585717Y249068D01*
X585563Y248810D01*
X584797Y248293D01*
X584452Y247932D01*
X584222Y247415D01*
X584145Y246950D01*
X585755D01*
G01X587398Y247312D02*
X587667Y247053D01*
X587973Y246950D01*
X588280Y247053D01*
X588548Y247363D01*
X588740Y247828D01*
X588817Y248293D01*
Y248862D01*
X588740Y249327D01*
X588548Y249740D01*
X588318Y249947D01*
X588050Y250050D01*
X587743Y249947D01*
X587513Y249740D01*
X587360Y249430D01*
X587283Y249017D01*
X587360Y248655D01*
X587552Y248293D01*
X587782Y248087D01*
X588050Y248035D01*
X588357Y248138D01*
X588587Y248397D01*
X588817Y248862D01*
G01X591150Y246950D02*
X591418Y247002D01*
X591725Y247157D01*
X591917Y247415D01*
X591993Y247777D01*
X591917Y248138D01*
X591687Y248448D01*
X591342Y248603D01*
X590958D01*
X590728Y248707D01*
X590537Y248965D01*
X590460Y249327D01*
X590575Y249688D01*
X590843Y249947D01*
X591150Y250050D01*
X591457Y249947D01*
X591725Y249688D01*
X591840Y249327D01*
X591763Y248965D01*
X591572Y248707D01*
X591342Y248603D01*
X590958D01*
X590613Y248448D01*
X590383Y248138D01*
X590307Y247777D01*
X590383Y247415D01*
X590575Y247157D01*
X590882Y247002D01*
X591150Y246950D01*
G01X570350Y253550D02*
Y250450D01*
G01X569468Y253550D02*
X571232D01*
G01X572683Y250450D02*
Y253550D01*
X573603D01*
X573910Y253395D01*
X574140Y253033D01*
X574217Y252620D01*
X574140Y252207D01*
X573948Y251897D01*
X573603Y251742D01*
X572683D01*
G01X575707Y251070D02*
X575937Y250708D01*
X576243Y250502D01*
X576588Y250450D01*
X576895Y250502D01*
X577202Y250760D01*
X577393Y251070D01*
X577432Y251380D01*
X577355Y251742D01*
X577087Y252000D01*
X576818Y252103D01*
X576473D01*
G01X576818D02*
X577048Y252258D01*
X577240Y252517D01*
X577317Y252827D01*
X577240Y253137D01*
X577048Y253395D01*
X576703Y253550D01*
X576358Y253498D01*
X576013Y253292D01*
G01X578998Y250812D02*
X579267Y250553D01*
X579573Y250450D01*
X579880Y250553D01*
X580148Y250863D01*
X580340Y251328D01*
X580417Y251793D01*
Y252362D01*
X580340Y252827D01*
X580148Y253240D01*
X579918Y253447D01*
X579650Y253550D01*
X579343Y253447D01*
X579113Y253240D01*
X578960Y252930D01*
X578883Y252517D01*
X578960Y252155D01*
X579152Y251793D01*
X579382Y251587D01*
X579650Y251535D01*
X579957Y251638D01*
X580187Y251897D01*
X580417Y252362D01*
G01X583500Y260450D02*
Y263550D01*
X583040Y262930D01*
G01Y260450D02*
X583960D01*
G01X581848Y304312D02*
X582117Y304053D01*
X582423Y303950D01*
X582730Y304053D01*
X582998Y304363D01*
X583190Y304828D01*
X583267Y305293D01*
Y305862D01*
X583190Y306327D01*
X582998Y306740D01*
X582768Y306947D01*
X582500Y307050D01*
X582193Y306947D01*
X581963Y306740D01*
X581810Y306430D01*
X581733Y306017D01*
X581810Y305655D01*
X582002Y305293D01*
X582232Y305087D01*
X582500Y305035D01*
X582807Y305138D01*
X583037Y305397D01*
X583267Y305862D01*
G01X570683Y318950D02*
Y322050D01*
X571642D01*
X571948Y321895D01*
X572140Y321688D01*
X572217Y321275D01*
X572140Y320862D01*
X571910Y320603D01*
X571642Y320448D01*
X570683D01*
G01X571642D02*
X572217Y318950D01*
G01X573707Y319415D02*
X573937Y319157D01*
X574205Y319002D01*
X574550Y318950D01*
X574895Y319053D01*
X575163Y319260D01*
X575355Y319622D01*
X575393Y320035D01*
X575317Y320448D01*
X575125Y320707D01*
X574857Y320913D01*
X574588Y320965D01*
X574320Y320913D01*
X573975Y320707D01*
X574090Y322050D01*
X575125D01*
G01X570683Y314950D02*
Y318050D01*
X571642D01*
X571948Y317895D01*
X572140Y317688D01*
X572217Y317275D01*
X572140Y316862D01*
X571910Y316603D01*
X571642Y316448D01*
X570683D01*
G01X571642D02*
X572217Y314950D01*
G01X575010D02*
Y318050D01*
X573592Y315828D01*
X575508D01*
G01X572293Y325792D02*
X572063Y325947D01*
X571795Y326050D01*
X571488D01*
X571143Y325895D01*
X570875Y325637D01*
X570683Y325327D01*
X570530Y324810D01*
X570492Y324345D01*
X570568Y323880D01*
X570683Y323570D01*
X570913Y323260D01*
X571182Y323053D01*
X571450Y322950D01*
X571718D01*
X571987Y323053D01*
X572217Y323208D01*
X572408Y323415D01*
G01X573707Y323570D02*
X573937Y323208D01*
X574243Y323002D01*
X574588Y322950D01*
X574895Y323002D01*
X575202Y323260D01*
X575393Y323570D01*
X575432Y323880D01*
X575355Y324242D01*
X575087Y324500D01*
X574818Y324603D01*
X574473D01*
G01X574818D02*
X575048Y324758D01*
X575240Y325017D01*
X575317Y325327D01*
X575240Y325637D01*
X575048Y325895D01*
X574703Y326050D01*
X574358Y325998D01*
X574013Y325792D01*
G01X572293Y337792D02*
X572063Y337947D01*
X571795Y338050D01*
X571488D01*
X571143Y337895D01*
X570875Y337637D01*
X570683Y337327D01*
X570530Y336810D01*
X570492Y336345D01*
X570568Y335880D01*
X570683Y335570D01*
X570913Y335260D01*
X571182Y335053D01*
X571450Y334950D01*
X571718D01*
X571987Y335053D01*
X572217Y335208D01*
X572408Y335415D01*
G01X575010Y334950D02*
Y338050D01*
X573592Y335828D01*
X575508D01*
G01X570683Y330950D02*
Y334050D01*
X571642D01*
X571948Y333895D01*
X572140Y333688D01*
X572217Y333275D01*
X572140Y332862D01*
X571910Y332603D01*
X571642Y332448D01*
X570683D01*
G01X571642D02*
X572217Y330950D01*
G01X574550D02*
X574818Y331002D01*
X575125Y331157D01*
X575317Y331415D01*
X575393Y331777D01*
X575317Y332138D01*
X575087Y332448D01*
X574742Y332603D01*
X574358D01*
X574128Y332707D01*
X573937Y332965D01*
X573860Y333327D01*
X573975Y333688D01*
X574243Y333947D01*
X574550Y334050D01*
X574857Y333947D01*
X575125Y333688D01*
X575240Y333327D01*
X575163Y332965D01*
X574972Y332707D01*
X574742Y332603D01*
X574358D01*
X574013Y332448D01*
X573783Y332138D01*
X573707Y331777D01*
X573783Y331415D01*
X573975Y331157D01*
X574282Y331002D01*
X574550Y330950D01*
G01X570683Y326950D02*
Y330050D01*
X571642D01*
X571948Y329895D01*
X572140Y329688D01*
X572217Y329275D01*
X572140Y328862D01*
X571910Y328603D01*
X571642Y328448D01*
X570683D01*
G01X571642D02*
X572217Y326950D01*
G01X574473D02*
X574550Y327622D01*
X574665Y328190D01*
X574818Y328707D01*
X575010Y329275D01*
X575317Y330050D01*
X573783D01*
G01X570733Y339150D02*
Y342250D01*
X571692D01*
X571998Y342095D01*
X572190Y341888D01*
X572267Y341475D01*
X572190Y341062D01*
X571960Y340803D01*
X571692Y340648D01*
X570733D01*
G01X571692D02*
X572267Y339150D01*
G01X575060D02*
Y342250D01*
X573642Y340028D01*
X575558D01*
G01X576972Y340442D02*
X577240Y340803D01*
X577470Y341010D01*
X577777Y341113D01*
X578045Y341010D01*
X578237Y340803D01*
X578390Y340493D01*
X578428Y340132D01*
X578390Y339822D01*
X578237Y339512D01*
X578007Y339253D01*
X577738Y339150D01*
X577432Y339253D01*
X577163Y339563D01*
X577010Y340028D01*
X576972Y340545D01*
X577048Y341217D01*
X577163Y341578D01*
X577355Y341940D01*
X577623Y342198D01*
X577892Y342250D01*
X578160Y342147D01*
X578352Y341888D01*
G01X583793Y388792D02*
X583563Y388947D01*
X583295Y389050D01*
X582988D01*
X582643Y388895D01*
X582375Y388637D01*
X582183Y388327D01*
X582030Y387810D01*
X581992Y387345D01*
X582068Y386880D01*
X582183Y386570D01*
X582413Y386260D01*
X582682Y386053D01*
X582950Y385950D01*
X583218D01*
X583487Y386053D01*
X583717Y386208D01*
X583908Y386415D01*
G01X585973Y385950D02*
X586050Y386622D01*
X586165Y387190D01*
X586318Y387707D01*
X586510Y388275D01*
X586817Y389050D01*
X585283D01*
G01X583893Y384492D02*
X583663Y384647D01*
X583395Y384750D01*
X583088D01*
X582743Y384595D01*
X582475Y384337D01*
X582283Y384027D01*
X582130Y383510D01*
X582092Y383045D01*
X582168Y382580D01*
X582283Y382270D01*
X582513Y381960D01*
X582782Y381753D01*
X583050Y381650D01*
X583318D01*
X583587Y381753D01*
X583817Y381908D01*
X584008Y382115D01*
G01X585307D02*
X585537Y381857D01*
X585805Y381702D01*
X586150Y381650D01*
X586495Y381753D01*
X586763Y381960D01*
X586955Y382322D01*
X586993Y382735D01*
X586917Y383148D01*
X586725Y383407D01*
X586457Y383613D01*
X586188Y383665D01*
X585920Y383613D01*
X585575Y383407D01*
X585690Y384750D01*
X586725D01*
G01X582133Y389950D02*
Y393050D01*
X583092D01*
X583398Y392895D01*
X583590Y392688D01*
X583667Y392275D01*
X583590Y391862D01*
X583360Y391603D01*
X583092Y391448D01*
X582133D01*
G01X583092D02*
X583667Y389950D01*
G01X586000D02*
Y393050D01*
X585540Y392430D01*
G01Y389950D02*
X586460D01*
G01X588257Y390415D02*
X588487Y390157D01*
X588755Y390002D01*
X589100Y389950D01*
X589445Y390053D01*
X589713Y390260D01*
X589905Y390622D01*
X589943Y391035D01*
X589867Y391448D01*
X589675Y391707D01*
X589407Y391913D01*
X589138Y391965D01*
X588870Y391913D01*
X588525Y391707D01*
X588640Y393050D01*
X589675D01*
G01X571587Y402542D02*
X571427Y402667D01*
X571240Y402750D01*
X571027D01*
X570787Y402625D01*
X570600Y402417D01*
X570467Y402167D01*
X570360Y401750D01*
X570333Y401375D01*
X570387Y401000D01*
X570467Y400750D01*
X570627Y400500D01*
X570813Y400333D01*
X571000Y400250D01*
X571187D01*
X571373Y400333D01*
X571533Y400458D01*
X571667Y400625D01*
G01X586050Y405057D02*
X582950D01*
Y405823D01*
X583105Y406130D01*
X583312Y406360D01*
X583622Y406552D01*
X583983Y406705D01*
X584500Y406743D01*
X585017Y406705D01*
X585378Y406552D01*
X585688Y406360D01*
X585895Y406130D01*
X586050Y405823D01*
Y405057D01*
G01X585637Y408195D02*
X585895Y408502D01*
X586050Y408847D01*
Y409153D01*
X585895Y409460D01*
X585637Y409690D01*
X585275Y409805D01*
X584913Y409728D01*
X584603Y409537D01*
X584397Y409192D01*
X584293Y408732D01*
X584087Y408463D01*
X583725Y408348D01*
X583363Y408425D01*
X583105Y408617D01*
X582950Y408885D01*
Y409153D01*
X583053Y409422D01*
X583312Y409652D01*
G01X585585Y411257D02*
X585843Y411487D01*
X585998Y411755D01*
X586050Y412100D01*
X585947Y412445D01*
X585740Y412713D01*
X585378Y412905D01*
X584965Y412943D01*
X584552Y412867D01*
X584293Y412675D01*
X584087Y412407D01*
X584035Y412138D01*
X584087Y411870D01*
X584293Y411525D01*
X582950Y411640D01*
Y412675D01*
G01X581087Y402542D02*
X580927Y402667D01*
X580740Y402750D01*
X580527D01*
X580287Y402625D01*
X580100Y402417D01*
X579967Y402167D01*
X579860Y401750D01*
X579833Y401375D01*
X579887Y401000D01*
X579967Y400750D01*
X580127Y400500D01*
X580313Y400333D01*
X580500Y400250D01*
X580687D01*
X580873Y400333D01*
X581033Y400458D01*
X581167Y400625D01*
G01X578200Y397250D02*
Y394750D01*
G01X577587Y397250D02*
X578813D01*
G01X579867Y394750D02*
Y397250D01*
X580507D01*
X580720Y397125D01*
X580880Y396833D01*
X580933Y396500D01*
X580880Y396167D01*
X580747Y395917D01*
X580507Y395792D01*
X579867D01*
G01X582013Y395250D02*
X582173Y394958D01*
X582387Y394792D01*
X582627Y394750D01*
X582840Y394792D01*
X583053Y395000D01*
X583187Y395250D01*
X583213Y395500D01*
X583160Y395792D01*
X582973Y396000D01*
X582787Y396083D01*
X582547D01*
G01X582787D02*
X582947Y396208D01*
X583080Y396417D01*
X583133Y396667D01*
X583080Y396917D01*
X582947Y397125D01*
X582707Y397250D01*
X582467Y397208D01*
X582227Y397042D01*
G01X584747Y394750D02*
X584800Y395292D01*
X584880Y395750D01*
X584987Y396167D01*
X585120Y396625D01*
X585333Y397250D01*
X584267D01*
G01X583333Y415750D02*
X584000Y418250D01*
X584667Y415750D01*
G01X584427Y416625D02*
X583573D01*
G01X587050Y424057D02*
X583950D01*
Y424823D01*
X584105Y425130D01*
X584312Y425360D01*
X584622Y425552D01*
X584983Y425705D01*
X585500Y425743D01*
X586017Y425705D01*
X586378Y425552D01*
X586688Y425360D01*
X586895Y425130D01*
X587050Y424823D01*
Y424057D01*
G01X586637Y427195D02*
X586895Y427502D01*
X587050Y427847D01*
Y428153D01*
X586895Y428460D01*
X586637Y428690D01*
X586275Y428805D01*
X585913Y428728D01*
X585603Y428537D01*
X585397Y428192D01*
X585293Y427732D01*
X585087Y427463D01*
X584725Y427348D01*
X584363Y427425D01*
X584105Y427617D01*
X583950Y427885D01*
Y428153D01*
X584053Y428422D01*
X584312Y428652D01*
G01X587050Y431560D02*
X583950D01*
X586172Y430142D01*
Y432058D01*
G01X585587Y421042D02*
X585427Y421167D01*
X585240Y421250D01*
X585027D01*
X584787Y421125D01*
X584600Y420917D01*
X584467Y420667D01*
X584360Y420250D01*
X584333Y419875D01*
X584387Y419500D01*
X584467Y419250D01*
X584627Y419000D01*
X584813Y418833D01*
X585000Y418750D01*
X585187D01*
X585373Y418833D01*
X585533Y418958D01*
X585667Y419125D01*
G01X572587Y421042D02*
X572427Y421167D01*
X572240Y421250D01*
X572027D01*
X571787Y421125D01*
X571600Y420917D01*
X571467Y420667D01*
X571360Y420250D01*
X571333Y419875D01*
X571387Y419500D01*
X571467Y419250D01*
X571627Y419000D01*
X571813Y418833D01*
X572000Y418750D01*
X572187D01*
X572373Y418833D01*
X572533Y418958D01*
X572667Y419125D01*
G01X581333Y430750D02*
X582000Y433250D01*
X582667Y430750D01*
G01X582427Y431625D02*
X581573D01*
G01X569333Y431250D02*
X570000Y433750D01*
X570667Y431250D01*
G01X570427Y432125D02*
X569573D01*
G01X588583Y85450D02*
Y88550D01*
X589542D01*
X589848Y88395D01*
X590040Y88188D01*
X590117Y87775D01*
X590040Y87362D01*
X589810Y87103D01*
X589542Y86948D01*
X588583D01*
G01X589542D02*
X590117Y85450D01*
G01X592910D02*
Y88550D01*
X591492Y86328D01*
X593408D01*
G01X594822Y88033D02*
X595052Y88343D01*
X595320Y88498D01*
X595627Y88550D01*
X596010Y88447D01*
X596278Y88188D01*
X596355Y87878D01*
X596317Y87568D01*
X596163Y87310D01*
X595397Y86793D01*
X595052Y86432D01*
X594822Y85915D01*
X594745Y85450D01*
X596355D01*
G01X597807Y86070D02*
X598037Y85708D01*
X598343Y85502D01*
X598688Y85450D01*
X598995Y85502D01*
X599302Y85760D01*
X599493Y86070D01*
X599532Y86380D01*
X599455Y86742D01*
X599187Y87000D01*
X598918Y87103D01*
X598573D01*
G01X598918D02*
X599148Y87258D01*
X599340Y87517D01*
X599417Y87827D01*
X599340Y88137D01*
X599148Y88395D01*
X598803Y88550D01*
X598458Y88498D01*
X598113Y88292D01*
G01X588133Y89950D02*
Y93050D01*
X589092D01*
X589398Y92895D01*
X589590Y92688D01*
X589667Y92275D01*
X589590Y91862D01*
X589360Y91603D01*
X589092Y91448D01*
X588133D01*
G01X589092D02*
X589667Y89950D01*
G01X591272Y92533D02*
X591502Y92843D01*
X591770Y92998D01*
X592077Y93050D01*
X592460Y92947D01*
X592728Y92688D01*
X592805Y92378D01*
X592767Y92068D01*
X592613Y91810D01*
X591847Y91293D01*
X591502Y90932D01*
X591272Y90415D01*
X591195Y89950D01*
X592805D01*
G01X595100D02*
Y93050D01*
X594640Y92430D01*
G01Y89950D02*
X595560D01*
G01X587930Y147683D02*
X588240Y147875D01*
X588447Y148105D01*
X588550Y148373D01*
X588447Y148680D01*
X588240Y148910D01*
X587930Y149140D01*
X587517Y149217D01*
X585450D01*
G01X588085Y150707D02*
X588343Y150937D01*
X588498Y151205D01*
X588550Y151550D01*
X588447Y151895D01*
X588240Y152163D01*
X587878Y152355D01*
X587465Y152393D01*
X587052Y152317D01*
X586793Y152125D01*
X586587Y151857D01*
X586535Y151588D01*
X586587Y151320D01*
X586793Y150975D01*
X585450Y151090D01*
Y152125D01*
G01X599967Y185772D02*
X599657Y186002D01*
X599502Y186270D01*
X599450Y186577D01*
X599553Y186960D01*
X599812Y187228D01*
X600122Y187305D01*
X600432Y187267D01*
X600690Y187113D01*
X601207Y186347D01*
X601568Y186002D01*
X602085Y185772D01*
X602550Y185695D01*
Y187305D01*
G01X593050Y219000D02*
X592998Y219268D01*
X592843Y219575D01*
X592585Y219767D01*
X592223Y219843D01*
X591862Y219767D01*
X591552Y219537D01*
X591397Y219192D01*
Y218808D01*
X591293Y218578D01*
X591035Y218387D01*
X590673Y218310D01*
X590312Y218425D01*
X590053Y218693D01*
X589950Y219000D01*
X590053Y219307D01*
X590312Y219575D01*
X590673Y219690D01*
X591035Y219613D01*
X591293Y219422D01*
X591397Y219192D01*
Y218808D01*
X591552Y218463D01*
X591862Y218233D01*
X592223Y218157D01*
X592585Y218233D01*
X592843Y218425D01*
X592998Y218732D01*
X593050Y219000D01*
G01X593850Y246550D02*
Y243450D01*
G01X592968Y246550D02*
X594732D01*
G01X596183Y243450D02*
Y246550D01*
X597103D01*
X597410Y246395D01*
X597640Y246033D01*
X597717Y245620D01*
X597640Y245207D01*
X597448Y244897D01*
X597103Y244742D01*
X596183D01*
G01X599322Y246033D02*
X599552Y246343D01*
X599820Y246498D01*
X600127Y246550D01*
X600510Y246447D01*
X600778Y246188D01*
X600855Y245878D01*
X600817Y245568D01*
X600663Y245310D01*
X599897Y244793D01*
X599552Y244432D01*
X599322Y243915D01*
X599245Y243450D01*
X600855D01*
G01X602422Y244742D02*
X602690Y245103D01*
X602920Y245310D01*
X603227Y245413D01*
X603495Y245310D01*
X603687Y245103D01*
X603840Y244793D01*
X603878Y244432D01*
X603840Y244122D01*
X603687Y243812D01*
X603457Y243553D01*
X603188Y243450D01*
X602882Y243553D01*
X602613Y243863D01*
X602460Y244328D01*
X602422Y244845D01*
X602498Y245517D01*
X602613Y245878D01*
X602805Y246240D01*
X603073Y246498D01*
X603342Y246550D01*
X603610Y246447D01*
X603802Y246188D01*
G01X602133Y240050D02*
Y236950D01*
X603667D01*
G01X606000D02*
Y240050D01*
X605540Y239430D01*
G01Y236950D02*
X606460D01*
G01X609023D02*
X609100Y237622D01*
X609215Y238190D01*
X609368Y238707D01*
X609560Y239275D01*
X609867Y240050D01*
X608333D01*
G01X590772Y259533D02*
X591002Y259843D01*
X591270Y259998D01*
X591577Y260050D01*
X591960Y259947D01*
X592228Y259688D01*
X592305Y259378D01*
X592267Y259068D01*
X592113Y258810D01*
X591347Y258293D01*
X591002Y257932D01*
X590772Y257415D01*
X590695Y256950D01*
X592305D01*
G01X591550Y304450D02*
X588450D01*
X589070Y303990D01*
G01X591550D02*
Y304910D01*
G01X588450Y307550D02*
X588553Y307243D01*
X588812Y307013D01*
X589122Y306860D01*
X589535Y306745D01*
X590000Y306707D01*
X590465Y306745D01*
X590878Y306860D01*
X591188Y307013D01*
X591447Y307243D01*
X591550Y307550D01*
X591447Y307857D01*
X591188Y308087D01*
X590878Y308240D01*
X590465Y308355D01*
X590000Y308393D01*
X589535Y308355D01*
X589122Y308240D01*
X588812Y308087D01*
X588553Y307857D01*
X588450Y307550D01*
G01X595772Y318742D02*
X596040Y319103D01*
X596270Y319310D01*
X596577Y319413D01*
X596845Y319310D01*
X597037Y319103D01*
X597190Y318793D01*
X597228Y318432D01*
X597190Y318122D01*
X597037Y317812D01*
X596807Y317553D01*
X596538Y317450D01*
X596232Y317553D01*
X595963Y317863D01*
X595810Y318328D01*
X595772Y318845D01*
X595848Y319517D01*
X595963Y319878D01*
X596155Y320240D01*
X596423Y320498D01*
X596692Y320550D01*
X596960Y320447D01*
X597152Y320188D01*
G01X590960Y381450D02*
Y384550D01*
X589542Y382328D01*
X591458D01*
G01X590587Y402042D02*
X590427Y402167D01*
X590240Y402250D01*
X590027D01*
X589787Y402125D01*
X589600Y401917D01*
X589467Y401667D01*
X589360Y401250D01*
X589333Y400875D01*
X589387Y400500D01*
X589467Y400250D01*
X589627Y400000D01*
X589813Y399833D01*
X590000Y399750D01*
X590187D01*
X590373Y399833D01*
X590533Y399958D01*
X590667Y400125D01*
G01X597750Y402007D02*
X594650D01*
Y402773D01*
X594805Y403080D01*
X595012Y403310D01*
X595322Y403502D01*
X595683Y403655D01*
X596200Y403693D01*
X596717Y403655D01*
X597078Y403502D01*
X597388Y403310D01*
X597595Y403080D01*
X597750Y402773D01*
Y402007D01*
G01X597337Y405145D02*
X597595Y405452D01*
X597750Y405797D01*
Y406103D01*
X597595Y406410D01*
X597337Y406640D01*
X596975Y406755D01*
X596613Y406678D01*
X596303Y406487D01*
X596097Y406142D01*
X595993Y405682D01*
X595787Y405413D01*
X595425Y405298D01*
X595063Y405375D01*
X594805Y405567D01*
X594650Y405835D01*
Y406103D01*
X594753Y406372D01*
X595012Y406602D01*
G01X597750Y409050D02*
X594650D01*
X595270Y408590D01*
G01X597750D02*
Y409510D01*
G01X597388Y411498D02*
X597647Y411767D01*
X597750Y412073D01*
X597647Y412380D01*
X597337Y412648D01*
X596872Y412840D01*
X596407Y412917D01*
X595838D01*
X595373Y412840D01*
X594960Y412648D01*
X594753Y412418D01*
X594650Y412150D01*
X594753Y411843D01*
X594960Y411613D01*
X595270Y411460D01*
X595683Y411383D01*
X596045Y411460D01*
X596407Y411652D01*
X596613Y411882D01*
X596665Y412150D01*
X596562Y412457D01*
X596303Y412687D01*
X595838Y412917D01*
G01X602087Y402042D02*
X601927Y402167D01*
X601740Y402250D01*
X601527D01*
X601287Y402125D01*
X601100Y401917D01*
X600967Y401667D01*
X600860Y401250D01*
X600833Y400875D01*
X600887Y400500D01*
X600967Y400250D01*
X601127Y400000D01*
X601313Y399833D01*
X601500Y399750D01*
X601687D01*
X601873Y399833D01*
X602033Y399958D01*
X602167Y400125D01*
G01X598087Y420242D02*
X597927Y420367D01*
X597740Y420450D01*
X597527D01*
X597287Y420325D01*
X597100Y420117D01*
X596967Y419867D01*
X596860Y419450D01*
X596833Y419075D01*
X596887Y418700D01*
X596967Y418450D01*
X597127Y418200D01*
X597313Y418033D01*
X597500Y417950D01*
X597687D01*
X597873Y418033D01*
X598033Y418158D01*
X598167Y418325D01*
G01X587333Y417750D02*
X588000Y420250D01*
X588667Y417750D01*
G01X588427Y418625D02*
X587573D01*
G01X601833Y430750D02*
X602500Y433250D01*
X603167Y430750D01*
G01X602927Y431625D02*
X602073D01*
G01X613057Y96050D02*
Y93828D01*
X613210Y93363D01*
X613517Y93053D01*
X613900Y92950D01*
X614283Y93053D01*
X614590Y93363D01*
X614743Y93828D01*
Y96050D01*
G01X616157Y93570D02*
X616387Y93208D01*
X616693Y93002D01*
X617038Y92950D01*
X617345Y93002D01*
X617652Y93260D01*
X617843Y93570D01*
X617882Y93880D01*
X617805Y94242D01*
X617537Y94500D01*
X617268Y94603D01*
X616923D01*
G01X617268D02*
X617498Y94758D01*
X617690Y95017D01*
X617767Y95327D01*
X617690Y95637D01*
X617498Y95895D01*
X617153Y96050D01*
X616808Y95998D01*
X616463Y95792D01*
G01X619372Y94242D02*
X619640Y94603D01*
X619870Y94810D01*
X620177Y94913D01*
X620445Y94810D01*
X620637Y94603D01*
X620790Y94293D01*
X620828Y93932D01*
X620790Y93622D01*
X620637Y93312D01*
X620407Y93053D01*
X620138Y92950D01*
X619832Y93053D01*
X619563Y93363D01*
X619410Y93828D01*
X619372Y94345D01*
X619448Y95017D01*
X619563Y95378D01*
X619755Y95740D01*
X620023Y95998D01*
X620292Y96050D01*
X620560Y95947D01*
X620752Y95688D01*
G01X614950Y114450D02*
Y117550D01*
X614490Y116930D01*
G01Y114450D02*
X615410D01*
G01X618050D02*
Y117550D01*
X617590Y116930D01*
G01Y114450D02*
X618510D01*
G01X618550Y189133D02*
X615450D01*
Y190092D01*
X615605Y190398D01*
X615812Y190590D01*
X616225Y190667D01*
X616638Y190590D01*
X616897Y190360D01*
X617052Y190092D01*
Y189133D01*
G01Y190092D02*
X618550Y190667D01*
G01X617258Y192272D02*
X616897Y192540D01*
X616690Y192770D01*
X616587Y193077D01*
X616690Y193345D01*
X616897Y193537D01*
X617207Y193690D01*
X617568Y193728D01*
X617878Y193690D01*
X618188Y193537D01*
X618447Y193307D01*
X618550Y193038D01*
X618447Y192732D01*
X618137Y192463D01*
X617672Y192310D01*
X617155Y192272D01*
X616483Y192348D01*
X616122Y192463D01*
X615760Y192655D01*
X615502Y192923D01*
X615450Y193192D01*
X615553Y193460D01*
X615812Y193652D01*
G01X618550Y196023D02*
X617878Y196100D01*
X617310Y196215D01*
X616793Y196368D01*
X616225Y196560D01*
X615450Y196867D01*
Y195333D01*
G01X614550Y187083D02*
X611450D01*
Y188042D01*
X611605Y188348D01*
X611812Y188540D01*
X612225Y188617D01*
X612638Y188540D01*
X612897Y188310D01*
X613052Y188042D01*
Y187083D01*
G01Y188042D02*
X614550Y188617D01*
G01X611967Y190222D02*
X611657Y190452D01*
X611502Y190720D01*
X611450Y191027D01*
X611553Y191410D01*
X611812Y191678D01*
X612122Y191755D01*
X612432Y191717D01*
X612690Y191563D01*
X613207Y190797D01*
X613568Y190452D01*
X614085Y190222D01*
X614550Y190145D01*
Y191755D01*
G01X614188Y193398D02*
X614447Y193667D01*
X614550Y193973D01*
X614447Y194280D01*
X614137Y194548D01*
X613672Y194740D01*
X613207Y194817D01*
X612638D01*
X612173Y194740D01*
X611760Y194548D01*
X611553Y194318D01*
X611450Y194050D01*
X611553Y193743D01*
X611760Y193513D01*
X612070Y193360D01*
X612483Y193283D01*
X612845Y193360D01*
X613207Y193552D01*
X613413Y193782D01*
X613465Y194050D01*
X613362Y194357D01*
X613103Y194587D01*
X612638Y194817D01*
G01X614188Y196498D02*
X614447Y196767D01*
X614550Y197073D01*
X614447Y197380D01*
X614137Y197648D01*
X613672Y197840D01*
X613207Y197917D01*
X612638D01*
X612173Y197840D01*
X611760Y197648D01*
X611553Y197418D01*
X611450Y197150D01*
X611553Y196843D01*
X611760Y196613D01*
X612070Y196460D01*
X612483Y196383D01*
X612845Y196460D01*
X613207Y196652D01*
X613413Y196882D01*
X613465Y197150D01*
X613362Y197457D01*
X613103Y197687D01*
X612638Y197917D01*
G01X606050Y199460D02*
X602950D01*
X605172Y198042D01*
Y199958D01*
G01X615050Y185500D02*
X611950D01*
X612570Y185040D01*
G01X615050D02*
Y185960D01*
G01X608693Y219292D02*
X608463Y219447D01*
X608195Y219550D01*
X607888D01*
X607543Y219395D01*
X607275Y219137D01*
X607083Y218827D01*
X606930Y218310D01*
X606892Y217845D01*
X606968Y217380D01*
X607083Y217070D01*
X607313Y216760D01*
X607582Y216553D01*
X607850Y216450D01*
X608118D01*
X608387Y216553D01*
X608617Y216708D01*
X608808Y216915D01*
G01X610222Y219033D02*
X610452Y219343D01*
X610720Y219498D01*
X611027Y219550D01*
X611410Y219447D01*
X611678Y219188D01*
X611755Y218878D01*
X611717Y218568D01*
X611563Y218310D01*
X610797Y217793D01*
X610452Y217432D01*
X610222Y216915D01*
X610145Y216450D01*
X611755D01*
G01X613973D02*
X614050Y217122D01*
X614165Y217690D01*
X614318Y218207D01*
X614510Y218775D01*
X614817Y219550D01*
X613283D01*
G01X616307Y216915D02*
X616537Y216657D01*
X616805Y216502D01*
X617150Y216450D01*
X617495Y216553D01*
X617763Y216760D01*
X617955Y217122D01*
X617993Y217535D01*
X617917Y217948D01*
X617725Y218207D01*
X617457Y218413D01*
X617188Y218465D01*
X616920Y218413D01*
X616575Y218207D01*
X616690Y219550D01*
X617725D01*
G01X608693Y215292D02*
X608463Y215447D01*
X608195Y215550D01*
X607888D01*
X607543Y215395D01*
X607275Y215137D01*
X607083Y214827D01*
X606930Y214310D01*
X606892Y213845D01*
X606968Y213380D01*
X607083Y213070D01*
X607313Y212760D01*
X607582Y212553D01*
X607850Y212450D01*
X608118D01*
X608387Y212553D01*
X608617Y212708D01*
X608808Y212915D01*
G01X610222Y215033D02*
X610452Y215343D01*
X610720Y215498D01*
X611027Y215550D01*
X611410Y215447D01*
X611678Y215188D01*
X611755Y214878D01*
X611717Y214568D01*
X611563Y214310D01*
X610797Y213793D01*
X610452Y213432D01*
X610222Y212915D01*
X610145Y212450D01*
X611755D01*
G01X613973D02*
X614050Y213122D01*
X614165Y213690D01*
X614318Y214207D01*
X614510Y214775D01*
X614817Y215550D01*
X613283D01*
G01X617610Y212450D02*
Y215550D01*
X616192Y213328D01*
X618108D01*
G01X615208Y201243D02*
X615053Y201013D01*
X614950Y200745D01*
Y200438D01*
X615105Y200093D01*
X615363Y199825D01*
X615673Y199633D01*
X616190Y199480D01*
X616655Y199442D01*
X617120Y199518D01*
X617430Y199633D01*
X617740Y199863D01*
X617947Y200132D01*
X618050Y200400D01*
Y200668D01*
X617947Y200937D01*
X617792Y201167D01*
X617585Y201358D01*
G01X616758Y202772D02*
X616397Y203040D01*
X616190Y203270D01*
X616087Y203577D01*
X616190Y203845D01*
X616397Y204037D01*
X616707Y204190D01*
X617068Y204228D01*
X617378Y204190D01*
X617688Y204037D01*
X617947Y203807D01*
X618050Y203538D01*
X617947Y203232D01*
X617637Y202963D01*
X617172Y202810D01*
X616655Y202772D01*
X615983Y202848D01*
X615622Y202963D01*
X615260Y203155D01*
X615002Y203423D01*
X614950Y203692D01*
X615053Y203960D01*
X615312Y204152D01*
G01X617430Y205757D02*
X617792Y205987D01*
X617998Y206293D01*
X618050Y206638D01*
X617998Y206945D01*
X617740Y207252D01*
X617430Y207443D01*
X617120Y207482D01*
X616758Y207405D01*
X616500Y207137D01*
X616397Y206868D01*
Y206523D01*
G01Y206868D02*
X616242Y207098D01*
X615983Y207290D01*
X615673Y207367D01*
X615363Y207290D01*
X615105Y207098D01*
X614950Y206753D01*
X615002Y206408D01*
X615208Y206063D01*
G01X611208Y201243D02*
X611053Y201013D01*
X610950Y200745D01*
Y200438D01*
X611105Y200093D01*
X611363Y199825D01*
X611673Y199633D01*
X612190Y199480D01*
X612655Y199442D01*
X613120Y199518D01*
X613430Y199633D01*
X613740Y199863D01*
X613947Y200132D01*
X614050Y200400D01*
Y200668D01*
X613947Y200937D01*
X613792Y201167D01*
X613585Y201358D01*
G01X612758Y202772D02*
X612397Y203040D01*
X612190Y203270D01*
X612087Y203577D01*
X612190Y203845D01*
X612397Y204037D01*
X612707Y204190D01*
X613068Y204228D01*
X613378Y204190D01*
X613688Y204037D01*
X613947Y203807D01*
X614050Y203538D01*
X613947Y203232D01*
X613637Y202963D01*
X613172Y202810D01*
X612655Y202772D01*
X611983Y202848D01*
X611622Y202963D01*
X611260Y203155D01*
X611002Y203423D01*
X610950Y203692D01*
X611053Y203960D01*
X611312Y204152D01*
G01X614050Y206600D02*
X610950D01*
X611570Y206140D01*
G01X614050D02*
Y207060D01*
G01X606950Y202557D02*
X609172D01*
X609637Y202710D01*
X609947Y203017D01*
X610050Y203400D01*
X609947Y203783D01*
X609637Y204090D01*
X609172Y204243D01*
X606950D01*
G01X607467Y205772D02*
X607157Y206002D01*
X607002Y206270D01*
X606950Y206577D01*
X607053Y206960D01*
X607312Y207228D01*
X607622Y207305D01*
X607932Y207267D01*
X608190Y207113D01*
X608707Y206347D01*
X609068Y206002D01*
X609585Y205772D01*
X610050Y205695D01*
Y207305D01*
G01Y209523D02*
X609378Y209600D01*
X608810Y209715D01*
X608293Y209868D01*
X607725Y210060D01*
X606950Y210367D01*
Y208833D01*
G01X618157Y233944D02*
X618387Y233582D01*
X618693Y233376D01*
X619038Y233324D01*
X619345Y233376D01*
X619652Y233634D01*
X619843Y233944D01*
X619882Y234254D01*
X619805Y234616D01*
X619537Y234874D01*
X619268Y234977D01*
X618923D01*
G01X619268D02*
X619498Y235132D01*
X619690Y235391D01*
X619767Y235701D01*
X619690Y236011D01*
X619498Y236269D01*
X619153Y236424D01*
X618808Y236372D01*
X618463Y236166D01*
G01X606085Y218157D02*
X606343Y218387D01*
X606498Y218655D01*
X606550Y219000D01*
X606447Y219345D01*
X606240Y219613D01*
X605878Y219805D01*
X605465Y219843D01*
X605052Y219767D01*
X604793Y219575D01*
X604587Y219307D01*
X604535Y219038D01*
X604587Y218770D01*
X604793Y218425D01*
X603450Y218540D01*
Y219575D01*
G01X613708Y240743D02*
X613553Y240513D01*
X613450Y240245D01*
Y239938D01*
X613605Y239593D01*
X613863Y239325D01*
X614173Y239133D01*
X614690Y238980D01*
X615155Y238942D01*
X615620Y239018D01*
X615930Y239133D01*
X616240Y239363D01*
X616447Y239632D01*
X616550Y239900D01*
Y240168D01*
X616447Y240437D01*
X616292Y240667D01*
X616085Y240858D01*
G01X616550Y243460D02*
X613450D01*
X615672Y242042D01*
Y243958D01*
G01X613450Y246100D02*
X613553Y245793D01*
X613812Y245563D01*
X614122Y245410D01*
X614535Y245295D01*
X615000Y245257D01*
X615465Y245295D01*
X615878Y245410D01*
X616188Y245563D01*
X616447Y245793D01*
X616550Y246100D01*
X616447Y246407D01*
X616188Y246637D01*
X615878Y246790D01*
X615465Y246905D01*
X615000Y246943D01*
X614535Y246905D01*
X614122Y246790D01*
X613812Y246637D01*
X613553Y246407D01*
X613450Y246100D01*
G01X609133Y308570D02*
X609325Y308260D01*
X609555Y308053D01*
X609823Y307950D01*
X610130Y308053D01*
X610360Y308260D01*
X610590Y308570D01*
X610667Y308983D01*
Y311050D01*
G01X613000Y307950D02*
Y311050D01*
X612540Y310430D01*
G01Y307950D02*
X613460D01*
G01X616100Y311050D02*
X615793Y310947D01*
X615563Y310688D01*
X615410Y310378D01*
X615295Y309965D01*
X615257Y309500D01*
X615295Y309035D01*
X615410Y308622D01*
X615563Y308312D01*
X615793Y308053D01*
X616100Y307950D01*
X616407Y308053D01*
X616637Y308312D01*
X616790Y308622D01*
X616905Y309035D01*
X616943Y309500D01*
X616905Y309965D01*
X616790Y310378D01*
X616637Y310688D01*
X616407Y310947D01*
X616100Y311050D01*
G01X609657Y318570D02*
X609887Y318208D01*
X610193Y318002D01*
X610538Y317950D01*
X610845Y318002D01*
X611152Y318260D01*
X611343Y318570D01*
X611382Y318880D01*
X611305Y319242D01*
X611037Y319500D01*
X610768Y319603D01*
X610423D01*
G01X610768D02*
X610998Y319758D01*
X611190Y320017D01*
X611267Y320327D01*
X611190Y320637D01*
X610998Y320895D01*
X610653Y321050D01*
X610308Y320998D01*
X609963Y320792D01*
G01X608500Y380950D02*
Y384050D01*
X608040Y383430D01*
G01Y380950D02*
X608960D01*
G01X610050Y401007D02*
X606950D01*
Y401773D01*
X607105Y402080D01*
X607312Y402310D01*
X607622Y402502D01*
X607983Y402655D01*
X608500Y402693D01*
X609017Y402655D01*
X609378Y402502D01*
X609688Y402310D01*
X609895Y402080D01*
X610050Y401773D01*
Y401007D01*
G01X609637Y404145D02*
X609895Y404452D01*
X610050Y404797D01*
Y405103D01*
X609895Y405410D01*
X609637Y405640D01*
X609275Y405755D01*
X608913Y405678D01*
X608603Y405487D01*
X608397Y405142D01*
X608293Y404682D01*
X608087Y404413D01*
X607725Y404298D01*
X607363Y404375D01*
X607105Y404567D01*
X606950Y404835D01*
Y405103D01*
X607053Y405372D01*
X607312Y405602D01*
G01X607467Y407322D02*
X607157Y407552D01*
X607002Y407820D01*
X606950Y408127D01*
X607053Y408510D01*
X607312Y408778D01*
X607622Y408855D01*
X607932Y408817D01*
X608190Y408663D01*
X608707Y407897D01*
X609068Y407552D01*
X609585Y407322D01*
X610050Y407245D01*
Y408855D01*
G01X606950Y411150D02*
X607053Y410843D01*
X607312Y410613D01*
X607622Y410460D01*
X608035Y410345D01*
X608500Y410307D01*
X608965Y410345D01*
X609378Y410460D01*
X609688Y410613D01*
X609947Y410843D01*
X610050Y411150D01*
X609947Y411457D01*
X609688Y411687D01*
X609378Y411840D01*
X608965Y411955D01*
X608500Y411993D01*
X608035Y411955D01*
X607622Y411840D01*
X607312Y411687D01*
X607053Y411457D01*
X606950Y411150D01*
G01X619087Y402542D02*
X618927Y402667D01*
X618740Y402750D01*
X618527D01*
X618287Y402625D01*
X618100Y402417D01*
X617967Y402167D01*
X617860Y401750D01*
X617833Y401375D01*
X617887Y401000D01*
X617967Y400750D01*
X618127Y400500D01*
X618313Y400333D01*
X618500Y400250D01*
X618687D01*
X618873Y400333D01*
X619033Y400458D01*
X619167Y400625D01*
G01X609550Y419007D02*
X606450D01*
Y419773D01*
X606605Y420080D01*
X606812Y420310D01*
X607122Y420502D01*
X607483Y420655D01*
X608000Y420693D01*
X608517Y420655D01*
X608878Y420502D01*
X609188Y420310D01*
X609395Y420080D01*
X609550Y419773D01*
Y419007D01*
G01X609137Y422145D02*
X609395Y422452D01*
X609550Y422797D01*
Y423103D01*
X609395Y423410D01*
X609137Y423640D01*
X608775Y423755D01*
X608413Y423678D01*
X608103Y423487D01*
X607897Y423142D01*
X607793Y422682D01*
X607587Y422413D01*
X607225Y422298D01*
X606863Y422375D01*
X606605Y422567D01*
X606450Y422835D01*
Y423103D01*
X606553Y423372D01*
X606812Y423602D01*
G01X609550Y426050D02*
X606450D01*
X607070Y425590D01*
G01X609550D02*
Y426510D01*
G01X606450Y429150D02*
X606553Y428843D01*
X606812Y428613D01*
X607122Y428460D01*
X607535Y428345D01*
X608000Y428307D01*
X608465Y428345D01*
X608878Y428460D01*
X609188Y428613D01*
X609447Y428843D01*
X609550Y429150D01*
X609447Y429457D01*
X609188Y429687D01*
X608878Y429840D01*
X608465Y429955D01*
X608000Y429993D01*
X607535Y429955D01*
X607122Y429840D01*
X606812Y429687D01*
X606553Y429457D01*
X606450Y429150D01*
G01X620087Y420042D02*
X619927Y420167D01*
X619740Y420250D01*
X619527D01*
X619287Y420125D01*
X619100Y419917D01*
X618967Y419667D01*
X618860Y419250D01*
X618833Y418875D01*
X618887Y418500D01*
X618967Y418250D01*
X619127Y418000D01*
X619313Y417833D01*
X619500Y417750D01*
X619687D01*
X619873Y417833D01*
X620033Y417958D01*
X620167Y418125D01*
G01X606833Y413750D02*
X607500Y416250D01*
X608167Y413750D01*
G01X607927Y414625D02*
X607073D01*
G01X618333Y413250D02*
X619000Y415750D01*
X619667Y413250D01*
G01X619427Y414125D02*
X618573D01*
G01X618833Y430250D02*
X619500Y432750D01*
X620167Y430250D01*
G01X619927Y431125D02*
X619073D01*
G01X636583Y88950D02*
Y92050D01*
X637542D01*
X637848Y91895D01*
X638040Y91688D01*
X638117Y91275D01*
X638040Y90862D01*
X637810Y90603D01*
X637542Y90448D01*
X636583D01*
G01X637542D02*
X638117Y88950D01*
G01X640910D02*
Y92050D01*
X639492Y89828D01*
X641408D01*
G01X643550Y88950D02*
Y92050D01*
X643090Y91430D01*
G01Y88950D02*
X644010D01*
G01X646650Y92050D02*
X646343Y91947D01*
X646113Y91688D01*
X645960Y91378D01*
X645845Y90965D01*
X645807Y90500D01*
X645845Y90035D01*
X645960Y89622D01*
X646113Y89312D01*
X646343Y89053D01*
X646650Y88950D01*
X646957Y89053D01*
X647187Y89312D01*
X647340Y89622D01*
X647455Y90035D01*
X647493Y90500D01*
X647455Y90965D01*
X647340Y91378D01*
X647187Y91688D01*
X646957Y91947D01*
X646650Y92050D01*
G01X630657Y92915D02*
X630887Y92657D01*
X631155Y92502D01*
X631500Y92450D01*
X631845Y92553D01*
X632113Y92760D01*
X632305Y93122D01*
X632343Y93535D01*
X632267Y93948D01*
X632075Y94207D01*
X631807Y94413D01*
X631538Y94465D01*
X631270Y94413D01*
X630925Y94207D01*
X631040Y95550D01*
X632075D01*
G01X635853Y80450D02*
Y83550D01*
X636850Y80967D01*
X637847Y83550D01*
Y80450D01*
G01X640717D02*
X639183D01*
Y83550D01*
X640717D01*
G01X640103Y82052D02*
X639183D01*
G01X643050Y80450D02*
Y83550D01*
X642590Y82930D01*
G01Y80450D02*
X643510D01*
G01X645422Y83033D02*
X645652Y83343D01*
X645920Y83498D01*
X646227Y83550D01*
X646610Y83447D01*
X646878Y83188D01*
X646955Y82878D01*
X646917Y82568D01*
X646763Y82310D01*
X645997Y81793D01*
X645652Y81432D01*
X645422Y80915D01*
X645345Y80450D01*
X646955D01*
G01X633000Y111450D02*
X633268Y111502D01*
X633575Y111657D01*
X633767Y111915D01*
X633843Y112277D01*
X633767Y112638D01*
X633537Y112948D01*
X633192Y113103D01*
X632808D01*
X632578Y113207D01*
X632387Y113465D01*
X632310Y113827D01*
X632425Y114188D01*
X632693Y114447D01*
X633000Y114550D01*
X633307Y114447D01*
X633575Y114188D01*
X633690Y113827D01*
X633613Y113465D01*
X633422Y113207D01*
X633192Y113103D01*
X632808D01*
X632463Y112948D01*
X632233Y112638D01*
X632157Y112277D01*
X632233Y111915D01*
X632425Y111657D01*
X632732Y111502D01*
X633000Y111450D01*
G01X639000Y186630D02*
Y187397D01*
X639930D01*
X640240Y187167D01*
X640447Y186898D01*
X640550Y186515D01*
X640447Y186132D01*
X640240Y185863D01*
X639930Y185633D01*
X639568Y185480D01*
X639155Y185403D01*
X638793D01*
X638483Y185480D01*
X638122Y185633D01*
X637812Y185863D01*
X637605Y186093D01*
X637450Y186400D01*
Y186668D01*
X637553Y186975D01*
X637760Y187205D01*
G01X640550Y188695D02*
X637450D01*
G01Y190305D02*
X640550D01*
G01X639000D02*
Y188695D01*
G01X640550Y192600D02*
X637450D01*
X638070Y192140D01*
G01X640550D02*
Y193060D01*
G01X635000Y203950D02*
Y207050D01*
X634540Y206430D01*
G01Y203950D02*
X635460D01*
G01X621960Y212324D02*
Y215424D01*
X620542Y213202D01*
X622458D01*
G01X630772Y213742D02*
X631040Y214103D01*
X631270Y214310D01*
X631577Y214413D01*
X631845Y214310D01*
X632037Y214103D01*
X632190Y213793D01*
X632228Y213432D01*
X632190Y213122D01*
X632037Y212812D01*
X631807Y212553D01*
X631538Y212450D01*
X631232Y212553D01*
X630963Y212863D01*
X630810Y213328D01*
X630772Y213845D01*
X630848Y214517D01*
X630963Y214878D01*
X631155Y215240D01*
X631423Y215498D01*
X631692Y215550D01*
X631960Y215447D01*
X632152Y215188D01*
G01X634657Y217915D02*
X634887Y217657D01*
X635155Y217502D01*
X635500Y217450D01*
X635845Y217553D01*
X636113Y217760D01*
X636305Y218122D01*
X636343Y218535D01*
X636267Y218948D01*
X636075Y219207D01*
X635807Y219413D01*
X635538Y219465D01*
X635270Y219413D01*
X634925Y219207D01*
X635040Y220550D01*
X636075D01*
G01X638500Y230504D02*
Y231271D01*
X639430D01*
X639740Y231041D01*
X639947Y230772D01*
X640050Y230389D01*
X639947Y230006D01*
X639740Y229737D01*
X639430Y229507D01*
X639068Y229354D01*
X638655Y229277D01*
X638293D01*
X637983Y229354D01*
X637622Y229507D01*
X637312Y229737D01*
X637105Y229967D01*
X636950Y230274D01*
Y230542D01*
X637053Y230849D01*
X637260Y231079D01*
G01X640050Y232569D02*
X636950D01*
G01Y234179D02*
X640050D01*
G01X638500D02*
Y232569D01*
G01X637467Y235746D02*
X637157Y235976D01*
X637002Y236244D01*
X636950Y236551D01*
X637053Y236934D01*
X637312Y237202D01*
X637622Y237279D01*
X637932Y237241D01*
X638190Y237087D01*
X638707Y236321D01*
X639068Y235976D01*
X639585Y235746D01*
X640050Y235669D01*
Y237279D01*
G01X625107Y242550D02*
Y240328D01*
X625260Y239863D01*
X625567Y239553D01*
X625950Y239450D01*
X626333Y239553D01*
X626640Y239863D01*
X626793Y240328D01*
Y242550D01*
G01X628398Y239812D02*
X628667Y239553D01*
X628973Y239450D01*
X629280Y239553D01*
X629548Y239863D01*
X629740Y240328D01*
X629817Y240793D01*
Y241362D01*
X629740Y241827D01*
X629548Y242240D01*
X629318Y242447D01*
X629050Y242550D01*
X628743Y242447D01*
X628513Y242240D01*
X628360Y241930D01*
X628283Y241517D01*
X628360Y241155D01*
X628552Y240793D01*
X628782Y240587D01*
X629050Y240535D01*
X629357Y240638D01*
X629587Y240897D01*
X629817Y241362D01*
G01X633000Y258950D02*
Y262050D01*
X632540Y261430D01*
G01Y258950D02*
X633460D01*
G01X632848Y304312D02*
X633117Y304053D01*
X633423Y303950D01*
X633730Y304053D01*
X633998Y304363D01*
X634190Y304828D01*
X634267Y305293D01*
Y305862D01*
X634190Y306327D01*
X633998Y306740D01*
X633768Y306947D01*
X633500Y307050D01*
X633193Y306947D01*
X632963Y306740D01*
X632810Y306430D01*
X632733Y306017D01*
X632810Y305655D01*
X633002Y305293D01*
X633232Y305087D01*
X633500Y305035D01*
X633807Y305138D01*
X634037Y305397D01*
X634267Y305862D01*
G01X633183Y382000D02*
Y385100D01*
X634103D01*
X634410Y384945D01*
X634640Y384583D01*
X634717Y384170D01*
X634640Y383757D01*
X634448Y383447D01*
X634103Y383292D01*
X633183D01*
G01X636207Y382620D02*
X636437Y382258D01*
X636743Y382052D01*
X637088Y382000D01*
X637395Y382052D01*
X637702Y382310D01*
X637893Y382620D01*
X637932Y382930D01*
X637855Y383292D01*
X637587Y383550D01*
X637318Y383653D01*
X636973D01*
G01X637318D02*
X637548Y383808D01*
X637740Y384067D01*
X637817Y384377D01*
X637740Y384687D01*
X637548Y384945D01*
X637203Y385100D01*
X636858Y385048D01*
X636513Y384842D01*
G01X624550Y403007D02*
X621450D01*
Y403773D01*
X621605Y404080D01*
X621812Y404310D01*
X622122Y404502D01*
X622483Y404655D01*
X623000Y404693D01*
X623517Y404655D01*
X623878Y404502D01*
X624188Y404310D01*
X624395Y404080D01*
X624550Y403773D01*
Y403007D01*
G01X624137Y406145D02*
X624395Y406452D01*
X624550Y406797D01*
Y407103D01*
X624395Y407410D01*
X624137Y407640D01*
X623775Y407755D01*
X623413Y407678D01*
X623103Y407487D01*
X622897Y407142D01*
X622793Y406682D01*
X622587Y406413D01*
X622225Y406298D01*
X621863Y406375D01*
X621605Y406567D01*
X621450Y406835D01*
Y407103D01*
X621553Y407372D01*
X621812Y407602D01*
G01X624550Y410050D02*
X621450D01*
X622070Y409590D01*
G01X624550D02*
Y410510D01*
G01X621967Y412422D02*
X621657Y412652D01*
X621502Y412920D01*
X621450Y413227D01*
X621553Y413610D01*
X621812Y413878D01*
X622122Y413955D01*
X622432Y413917D01*
X622690Y413763D01*
X623207Y412997D01*
X623568Y412652D01*
X624085Y412422D01*
X624550Y412345D01*
Y413955D01*
G01X636853Y399450D02*
Y402550D01*
X637850Y399967D01*
X638847Y402550D01*
Y399450D01*
G01X641717D02*
X640183D01*
Y402550D01*
X641717D01*
G01X641103Y401052D02*
X640183D01*
G01X644050Y399450D02*
Y402550D01*
X643590Y401930D01*
G01Y399450D02*
X644510D01*
G01X647150D02*
Y402550D01*
X646690Y401930D01*
G01Y399450D02*
X647610D01*
G01X624550Y419507D02*
X621450D01*
Y420273D01*
X621605Y420580D01*
X621812Y420810D01*
X622122Y421002D01*
X622483Y421155D01*
X623000Y421193D01*
X623517Y421155D01*
X623878Y421002D01*
X624188Y420810D01*
X624395Y420580D01*
X624550Y420273D01*
Y419507D01*
G01X624137Y422645D02*
X624395Y422952D01*
X624550Y423297D01*
Y423603D01*
X624395Y423910D01*
X624137Y424140D01*
X623775Y424255D01*
X623413Y424178D01*
X623103Y423987D01*
X622897Y423642D01*
X622793Y423182D01*
X622587Y422913D01*
X622225Y422798D01*
X621863Y422875D01*
X621605Y423067D01*
X621450Y423335D01*
Y423603D01*
X621553Y423872D01*
X621812Y424102D01*
G01X624550Y426550D02*
X621450D01*
X622070Y426090D01*
G01X624550D02*
Y427010D01*
G01Y429650D02*
X621450D01*
X622070Y429190D01*
G01X624550D02*
Y430110D01*
G01X645083Y97450D02*
Y100550D01*
X646042D01*
X646348Y100395D01*
X646540Y100188D01*
X646617Y99775D01*
X646540Y99362D01*
X646310Y99103D01*
X646042Y98948D01*
X645083D01*
G01X646042D02*
X646617Y97450D01*
G01X649410D02*
Y100550D01*
X647992Y98328D01*
X649908D01*
G01X652050Y97450D02*
Y100550D01*
X651590Y99930D01*
G01Y97450D02*
X652510D01*
G01X655610D02*
Y100550D01*
X654192Y98328D01*
X656108D01*
G01X645083Y109450D02*
Y112550D01*
X646042D01*
X646348Y112395D01*
X646540Y112188D01*
X646617Y111775D01*
X646540Y111362D01*
X646310Y111103D01*
X646042Y110948D01*
X645083D01*
G01X646042D02*
X646617Y109450D01*
G01X649410D02*
Y112550D01*
X647992Y110328D01*
X649908D01*
G01X652050Y109450D02*
Y112550D01*
X651590Y111930D01*
G01Y109450D02*
X652510D01*
G01X654498Y109812D02*
X654767Y109553D01*
X655073Y109450D01*
X655380Y109553D01*
X655648Y109863D01*
X655840Y110328D01*
X655917Y110793D01*
Y111362D01*
X655840Y111827D01*
X655648Y112240D01*
X655418Y112447D01*
X655150Y112550D01*
X654843Y112447D01*
X654613Y112240D01*
X654460Y111930D01*
X654383Y111517D01*
X654460Y111155D01*
X654652Y110793D01*
X654882Y110587D01*
X655150Y110535D01*
X655457Y110638D01*
X655687Y110897D01*
X655917Y111362D01*
G01X646693Y117792D02*
X646463Y117947D01*
X646195Y118050D01*
X645888D01*
X645543Y117895D01*
X645275Y117637D01*
X645083Y117327D01*
X644930Y116810D01*
X644892Y116345D01*
X644968Y115880D01*
X645083Y115570D01*
X645313Y115260D01*
X645582Y115053D01*
X645850Y114950D01*
X646118D01*
X646387Y115053D01*
X646617Y115208D01*
X646808Y115415D01*
G01X648107Y115570D02*
X648337Y115208D01*
X648643Y115002D01*
X648988Y114950D01*
X649295Y115002D01*
X649602Y115260D01*
X649793Y115570D01*
X649832Y115880D01*
X649755Y116242D01*
X649487Y116500D01*
X649218Y116603D01*
X648873D01*
G01X649218D02*
X649448Y116758D01*
X649640Y117017D01*
X649717Y117327D01*
X649640Y117637D01*
X649448Y117895D01*
X649103Y118050D01*
X648758Y117998D01*
X648413Y117792D01*
G01X652050Y118050D02*
X651743Y117947D01*
X651513Y117688D01*
X651360Y117378D01*
X651245Y116965D01*
X651207Y116500D01*
X651245Y116035D01*
X651360Y115622D01*
X651513Y115312D01*
X651743Y115053D01*
X652050Y114950D01*
X652357Y115053D01*
X652587Y115312D01*
X652740Y115622D01*
X652855Y116035D01*
X652893Y116500D01*
X652855Y116965D01*
X652740Y117378D01*
X652587Y117688D01*
X652357Y117947D01*
X652050Y118050D01*
G01X654307Y115415D02*
X654537Y115157D01*
X654805Y115002D01*
X655150Y114950D01*
X655495Y115053D01*
X655763Y115260D01*
X655955Y115622D01*
X655993Y116035D01*
X655917Y116448D01*
X655725Y116707D01*
X655457Y116913D01*
X655188Y116965D01*
X654920Y116913D01*
X654575Y116707D01*
X654690Y118050D01*
X655725D01*
G01X652000Y186630D02*
Y187397D01*
X652930D01*
X653240Y187167D01*
X653447Y186898D01*
X653550Y186515D01*
X653447Y186132D01*
X653240Y185863D01*
X652930Y185633D01*
X652568Y185480D01*
X652155Y185403D01*
X651793D01*
X651483Y185480D01*
X651122Y185633D01*
X650812Y185863D01*
X650605Y186093D01*
X650450Y186400D01*
Y186668D01*
X650553Y186975D01*
X650760Y187205D01*
G01X653550Y188695D02*
X650450D01*
G01Y190305D02*
X653550D01*
G01X652000D02*
Y188695D01*
G01X652930Y191757D02*
X653292Y191987D01*
X653498Y192293D01*
X653550Y192638D01*
X653498Y192945D01*
X653240Y193252D01*
X652930Y193443D01*
X652620Y193482D01*
X652258Y193405D01*
X652000Y193137D01*
X651897Y192868D01*
Y192523D01*
G01Y192868D02*
X651742Y193098D01*
X651483Y193290D01*
X651173Y193367D01*
X650863Y193290D01*
X650605Y193098D01*
X650450Y192753D01*
X650502Y192408D01*
X650708Y192063D01*
G01X642633Y230444D02*
X642825Y230134D01*
X643055Y229927D01*
X643323Y229824D01*
X643630Y229927D01*
X643860Y230134D01*
X644090Y230444D01*
X644167Y230857D01*
Y232924D01*
G01X646500Y229824D02*
Y232924D01*
X646040Y232304D01*
G01Y229824D02*
X646960D01*
G01X649600D02*
Y232924D01*
X649140Y232304D01*
G01Y229824D02*
X650060D01*
G01X653000Y230504D02*
Y231271D01*
X653930D01*
X654240Y231041D01*
X654447Y230772D01*
X654550Y230389D01*
X654447Y230006D01*
X654240Y229737D01*
X653930Y229507D01*
X653568Y229354D01*
X653155Y229277D01*
X652793D01*
X652483Y229354D01*
X652122Y229507D01*
X651812Y229737D01*
X651605Y229967D01*
X651450Y230274D01*
Y230542D01*
X651553Y230849D01*
X651760Y231079D01*
G01X654550Y232569D02*
X651450D01*
G01Y234179D02*
X654550D01*
G01X653000D02*
Y232569D01*
G01X654550Y236934D02*
X651450D01*
X653672Y235516D01*
Y237432D01*
M02*
